G04 ================== begin FILE IDENTIFICATION RECORD ==================*
G04 Layout Name:  9127_F0T_Expander_BD_F_v02_0110_1240.brd*
G04 Film Name:    top*
G04 File Format:  Gerber RS274X*
G04 File Origin:  Cadence Allegro 17.2-S081*
G04 Origin Date:  Wed Jan 11 16:06:11 2023*
G04 *
G04 Layer:  PIN/SPECIAL_DRILL*
G04 Layer:  DRAWING FORMAT/TITLE_BLOCK_A*
G04 Layer:  DRAWING FORMAT/TITLE_BLOCK*
G04 Layer:  VIA CLASS/TOP*
G04 Layer:  PIN/TOP*
G04 Layer:  MANUFACTURING/PHOTOPLOT_OUTLINE*
G04 Layer:  ETCH/TOP*
G04 Layer:  DRAWING FORMAT/TITLE_DATA_TOP*
G04 *
G04 Offset:    (0.00 0.00)*
G04 Mirror:    No*
G04 Mode:      Positive*
G04 Rotation:  0*
G04 FullContactRelief:  No*
G04 UndefLineWidth:     6.00*
G04 ================== end FILE IDENTIFICATION RECORD ====================*
%FSLAX25Y25*MOIN*%
%IR0*IPPOS*OFA0.00000B0.00000*MIA0B0*SFA1.00000B1.00000*%
%AMMACRO212*
4,1,5,.10039,-.10039,
-.08858,-.10039,
-.10039,-.08858,
-.10039,.10039,
.10039,.10039,
.10039,-.10039,
0.0*
%
%ADD212MACRO212*%
%AMMACRO48*
4,1,32,-.01575,.06201,
-.01575,.0502,
.00197,.0502,
.00197,.04035,
-.01575,.04035,
-.01575,.03248,
.00197,.03248,
.00197,.02461,
-.01575,.02461,
-.01575,.01673,
.00197,.01673,
.00197,.00886,
-.01575,.00886,
-.01575,.00098,
.00197,.00098,
.00197,-.00689,
-.01575,-.00689,
-.01575,-.01476,
.00197,-.01476,
.00197,-.02264,
-.01575,-.02264,
-.01575,-.03051,
.00197,-.03051,
.00197,-.03839,
-.01575,-.03839,
-.01575,-.04626,
.00197,-.04626,
.00197,-.05413,
-.01575,-.05413,
-.01575,-.06201,
.01575,-.06201,
.01575,.06201,
-.01575,.06201,
0.0*
%
%ADD48MACRO48*%
%AMMACRO244*
4,1,5,-.10039,-.10039,
-.10039,.08858,
-.08858,.10039,
.10039,.10039,
.10039,-.10039,
-.10039,-.10039,
0.0*
%
%ADD244MACRO244*%
%AMMACRO174*
4,1,5,.05512,.05512,
-.04134,.05512,
-.05512,.04134,
-.05512,-.05512,
.05512,-.05512,
.05512,.05512,
0.0*
%
%ADD174MACRO174*%
%AMMACRO234*
4,1,8,.06299,-.02953,
.06299,.02953,
-.06299,.02953,
-.06299,-.02953,
-.01968,-.02953,
-.01968,.01771,
.01968,.01771,
.01968,-.02953,
.06299,-.02953,
0.0*
%
%ADD234MACRO234*%
%ADD219R,.02X.007*%
%ADD187R,.109X.04*%
%ADD139R,.17X.024*%
%ADD115R,.135X.05*%
%AMMACRO100*
4,1,8,.005,.02,
.005,-.002,
.01,-.002,
.01,-.02,
-.01,-.02,
-.01,-.002,
-.005,-.002,
-.005,.02,
.005,.02,
0.0*
%
%ADD100MACRO100*%
%ADD211R,.022X.007*%
%ADD114O,.137X.062*%
%ADD10C,.02*%
%ADD213R,.007X.022*%
%AMMACRO152*
4,1,21,-.017,0.0,
-.016916,.000955,
-.016668,.001881,
-.016263,.00275,
-.015713,.003535,
-.015035,.004213,
-.01425,.004763,
-.013381,.005168,
-.012455,.005416,
-.0115,.0055,
.017,.0055,
.017,-.0055,
-.0115,-.0055,
-.012455,-.005416,
-.013381,-.005168,
-.01425,-.004763,
-.015035,-.004213,
-.015713,-.003535,
-.016263,-.00275,
-.016668,-.001881,
-.016916,-.000955,
-.017,0.0,
0.0*
%
%ADD152MACRO152*%
%ADD140R,.111X.095*%
%ADD74R,.032X.007*%
%ADD50R,.0041X.016*%
%ADD11C,.03*%
%ADD167R,.024X.007*%
%AMMACRO132*
4,1,21,0.0,.017,
.000955,.016916,
.001881,.016668,
.00275,.016263,
.003535,.015713,
.004213,.015035,
.004763,.01425,
.005168,.013381,
.005416,.012455,
.0055,.0115,
.0055,-.017,
-.0055,-.017,
-.0055,.0115,
-.005416,.012455,
-.005168,.013381,
-.004763,.01425,
-.004213,.015035,
-.003535,.015713,
-.00275,.016263,
-.001881,.016668,
-.000955,.016916,
0.0,.017,
0.0*
%
%ADD132MACRO132*%
%ADD98R,.016X.0041*%
%ADD75C,.04*%
%ADD54O,.137X.064*%
%ADD242R,.095X.13*%
%AMMACRO231*
4,1,8,-.09252,.09055,
-.09252,.0315,
-.08268,.0315,
-.08268,-.09055,
.08268,-.09055,
.08268,.0315,
.09252,.0315,
.09252,.09055,
-.09252,.09055,
0.0*
%
%ADD231MACRO231*%
%ADD182C,.041*%
%ADD168R,.007X.024*%
%ADD194R,.015X.009*%
%AMMACRO92*
4,1,8,-.01771,-.01476,
.01772,-.01476,
.01772,.01476,
-.01771,.01476,
-.01771,.00492,
.00394,.00492,
.00394,-.00492,
-.01771,-.00492,
-.01771,-.01476,
0.0*
%
%ADD92MACRO92*%
%ADD69R,.024X.009*%
%ADD39R,.119X.063*%
%ADD249C,.061*%
%ADD216C,.052*%
%ADD193R,.009X.015*%
%ADD151R,.063X.119*%
%ADD131R,.138X.063*%
%AMMACRO130*
4,1,8,.005,.037,
.005,-.005,
.014,-.005,
.014,-.037,
-.014,-.037,
-.014,-.005,
-.005,-.005,
-.005,.037,
.005,.037,
0.0*
%
%ADD130MACRO130*%
%AMMACRO122*
4,1,8,-.01476,.01771,
-.01476,-.01772,
.01476,-.01772,
.01476,.01771,
.00492,.01771,
.00492,-.00394,
-.00492,-.00394,
-.00492,.01771,
-.01476,.01771,
0.0*
%
%ADD122MACRO122*%
%ADD68R,.009X.024*%
%ADD65C,.016*%
%ADD218R,.006X.028*%
%ADD163R,.063X.138*%
%AMMACRO148*
4,1,21,.0035,-.0135,
.003447,-.014108,
.003289,-.014697,
.003031,-.01525,
.002681,-.01575,
.00225,-.016181,
.00175,-.016531,
.001197,-.016789,
.000608,-.016947,
0.0,-.017,
-.000608,-.016947,
-.001197,-.016789,
-.00175,-.016531,
-.00225,-.016181,
-.002681,-.01575,
-.003031,-.01525,
-.003289,-.014697,
-.003447,-.014108,
-.0035,-.0135,
-.0035,.017,
.0035,.017,
.0035,-.0135,
0.0*
%
%ADD148MACRO148*%
%AMMACRO146*
4,1,21,.0135,.0035,
.014108,.003447,
.014697,.003289,
.01525,.003031,
.01575,.002681,
.016181,.00225,
.016531,.00175,
.016789,.001197,
.016947,.000608,
.017,0.0,
.016947,-.000608,
.016789,-.001197,
.016531,-.00175,
.016181,-.00225,
.01575,-.002681,
.01525,-.003031,
.014697,-.003289,
.014108,-.003447,
.0135,-.0035,
-.017,-.0035,
-.017,.0035,
.0135,.0035,
0.0*
%
%ADD146MACRO146*%
%ADD82R,.069X.105*%
%ADD56C,.044*%
%ADD96C,.018*%
%ADD66R,.073X.138*%
%ADD45R,.107X.078*%
%ADD135R,.13X.0848*%
%ADD113C,.064*%
%ADD59R,.078X.107*%
%ADD208C,.048*%
%ADD110C,.0282*%
%ADD255C,.085*%
%ADD202C,.07051*%
%ADD156C,.0193*%
%ADD141R,.386X.046*%
%AMMACRO51*
4,1,44,.11811,-.11614,
.11811,.11614,
.11808,.116482,
.117992,.116813,
.117847,.117124,
.117651,.117406,
.117408,.117648,
.117127,.117845,
.116817,.117991,
.116485,.11808,
.116143,.11811,
.11614,.11811,
-.11614,.11811,
-.116482,.11808,
-.116813,.117992,
-.117124,.117847,
-.117406,.117651,
-.117648,.117408,
-.117845,.117127,
-.117991,.116817,
-.11808,.116485,
-.11811,.116143,
-.11811,.11614,
-.11811,-.11614,
-.11808,-.116482,
-.117992,-.116813,
-.117847,-.117124,
-.117651,-.117406,
-.117408,-.117648,
-.117127,-.117845,
-.116817,-.117991,
-.116485,-.11808,
-.116143,-.11811,
-.11614,-.11811,
.11614,-.11811,
.116482,-.11808,
.116813,-.117992,
.117124,-.117847,
.117406,-.117651,
.117648,-.117408,
.117845,-.117127,
.117991,-.116817,
.11808,-.116485,
.11811,-.116143,
.11811,-.11614,
0.0*
%
%ADD51MACRO51*%
%ADD251R,.061X.061*%
%AMMACRO235*
4,1,8,-.0425,-.078,
.0425,-.078,
.0425,.078,
-.0425,.078,
-.0425,.0236,
-.0145,.0236,
-.0145,-.0236,
-.0425,-.0236,
-.0425,-.078,
0.0*
%
%ADD235MACRO235*%
%ADD35R,.046X.386*%
%ADD243C,.0177*%
%ADD90C,.0395*%
%ADD111R,.0282X.0282*%
%ADD248R,.07051X.07051*%
%ADD76C,.0785*%
%ADD70R,.067X.067*%
%AMMACRO107*
4,1,28,-.00566,.00492,
-.00733,.00659,
-.01122,.00269,
-.011659,.002174,
-.011998,.001588,
-.01223,.000951,
-.012348,.000284,
-.012348,-.000393,
-.012231,-.001061,
-.012,-.001697,
-.011661,-.002284,
-.011226,-.002803,
-.01119,-.00284,
-.00284,-.01119,
-.002326,-.011631,
-.001744,-.011978,
-.00111,-.012217,
-.000444,-.012343,
.000233,-.012352,
.000902,-.012243,
.001541,-.012019,
.002132,-.011688,
.002656,-.011259,
.00269,-.01122,
.00659,-.00733,
.00492,-.00566,
.0123,.00172,
.00172,.0123,
-.00566,.00492,
0.0*
%
%ADD107MACRO107*%
%AMMACRO15*
4,1,28,-.00748,-.00052,
-.00984,-.00052,
-.00984,-.00603,
-.009782,-.006705,
-.009607,-.007359,
-.009321,-.007974,
-.008933,-.008529,
-.008455,-.009009,
-.0079,-.009398,
-.007286,-.009685,
-.006632,-.009861,
-.005957,-.00992,
-.00591,-.00992,
.00591,-.00992,
.006585,-.009869,
.007242,-.009701,
.007859,-.009421,
.008418,-.009039,
.008903,-.008565,
.009297,-.008015,
.009591,-.007404,
.009773,-.006751,
.00984,-.006077,
.00984,-.00603,
.00984,-.00052,
.00748,-.00052,
.00748,.00991,
-.00748,.00991,
-.00748,-.00052,
0.0*
%
%ADD15MACRO15*%
%ADD109C,.03568*%
%AMMACRO80*
4,1,5,.00492,.01673,
-.00492,.01673,
-.00492,-.01673,
.00098,-.01673,
.00492,-.0128,
.00492,.01673,
0.0*
%
%ADD80MACRO80*%
%AMMACRO32*
4,1,28,-.00052,.00748,
-.00052,.00984,
-.00603,.00984,
-.006705,.009782,
-.007359,.009607,
-.007974,.009321,
-.008529,.008933,
-.009009,.008455,
-.009398,.0079,
-.009685,.007286,
-.009861,.006632,
-.00992,.005957,
-.00992,.00591,
-.00992,-.00591,
-.009869,-.006585,
-.009701,-.007242,
-.009421,-.007859,
-.009039,-.008418,
-.008565,-.008903,
-.008015,-.009297,
-.007404,-.009591,
-.006751,-.009773,
-.006077,-.00984,
-.00603,-.00984,
-.00052,-.00984,
-.00052,-.00748,
.00991,-.00748,
.00991,.00748,
-.00052,.00748,
0.0*
%
%ADD32MACRO32*%
%AMMACRO226*
4,1,8,.0034,-.0082,
-.0034,-.0082,
-.0082,-.0034,
-.0082,.00341,
-.00341,.0082,
.0034,.0082,
.0082,.0034,
.0082,-.0034,
.0034,-.0082,
0.0*
%
%ADD226MACRO226*%
%AMMACRO227*
4,1,8,-.0082,-.0034,
-.0082,.0034,
-.0034,.0082,
.00341,.0082,
.0082,.00341,
.0082,-.0034,
.0034,-.0082,
-.0034,-.0082,
-.0082,-.0034,
0.0*
%
%ADD227MACRO227*%
%AMMACRO108*
4,1,28,-.00493,.00565,
-.0066,.00732,
-.0027,.01121,
-.002185,.011649,
-.001599,.011989,
-.000962,.012222,
-.000295,.01234,
.000382,.012342,
.001049,.012225,
.001686,.011994,
.002273,.011657,
.002793,.011222,
.00283,.01119,
.01119,.00283,
.011629,.002313,
.011974,.00173,
.012212,.001096,
.012337,.00043,
.012344,-.000247,
.012234,-.000915,
.012009,-.001554,
.011677,-.002145,
.011247,-.002668,
.01121,-.0027,
.00732,-.0066,
.00565,-.00493,
-.00173,-.0123,
-.0123,-.00173,
-.00493,.00565,
0.0*
%
%ADD108MACRO108*%
%AMMACRO17*
4,1,28,-.00748,.00051,
-.00984,.00051,
-.00984,.00602,
-.009782,.006695,
-.009607,.007349,
-.009321,.007964,
-.008933,.008519,
-.008455,.008998,
-.0079,.009388,
-.007287,.009675,
-.006632,.009851,
-.005958,.00991,
-.00591,.00991,
.00591,.00991,
.006585,.009859,
.007242,.009691,
.007859,.009411,
.008418,.009029,
.008903,.008555,
.009297,.008005,
.00959,.007394,
.009773,.006742,
.00984,.006068,
.00984,.00602,
.00984,.00051,
.00748,.00051,
.00748,-.00992,
-.00748,-.00992,
-.00748,.00051,
0.0*
%
%ADD17MACRO17*%
%AMMACRO31*
4,1,28,.00051,.00748,
.00051,.00984,
.00602,.00984,
.006695,.009782,
.007349,.009607,
.007964,.009321,
.008519,.008933,
.008998,.008455,
.009388,.0079,
.009675,.007287,
.009851,.006632,
.00991,.005958,
.00991,.00591,
.00991,-.00591,
.009859,-.006585,
.009691,-.007242,
.009411,-.007859,
.009029,-.008418,
.008555,-.008903,
.008005,-.009297,
.007394,-.00959,
.006742,-.009773,
.006068,-.00984,
.00602,-.00984,
.00051,-.00984,
.00051,-.00748,
-.00992,-.00748,
-.00992,.00748,
.00051,.00748,
0.0*
%
%ADD31MACRO31*%
%AMMACRO123*
4,1,9,-.01476,.01181,
-.01476,-.01771,
-.00492,-.01771,
-.00492,.00394,
.00492,.00394,
.00492,-.01771,
.01476,-.01771,
.01476,.01772,
-.00886,.01772,
-.01476,.01181,
0.0*
%
%ADD123MACRO123*%
%AMMACRO91*
4,1,9,-.01181,-.01476,
.01771,-.01476,
.01771,-.00492,
-.00394,-.00492,
-.00394,.00492,
.01771,.00492,
.01771,.01476,
-.01772,.01476,
-.01772,-.00886,
-.01181,-.01476,
0.0*
%
%ADD91MACRO91*%
%AMMACRO79*
4,1,8,-.01821,.0246,
.01821,.0246,
.01821,.01476,
-.00837,.01476,
-.00837,-.01477,
.01821,-.01477,
.01821,-.02461,
-.01821,-.02461,
-.01821,.0246,
0.0*
%
%ADD79MACRO79*%
%ADD158R,.02X.01*%
%AMMACRO52*
4,1,40,-.00984,-.00472,
.00984,-.00472,
.010182,-.004691,
.010513,-.004603,
.010824,-.004458,
.011105,-.004262,
.011348,-.00402,
.011545,-.00374,
.01169,-.003429,
.01178,-.003098,
.01181,-.00276,
.01181,.00276,
.011779,.003101,
.011689,.003432,
.011543,.003742,
.011346,.004023,
.011102,.004264,
.010821,.00446,
.01051,.004604,
.010178,.004691,
.00984,.00472,
-.00984,.00472,
-.010182,.004691,
-.010513,.004603,
-.010824,.004458,
-.011105,.004262,
-.011348,.00402,
-.011545,.00374,
-.01169,.003429,
-.01178,.003098,
-.01181,.00276,
-.01181,-.00276,
-.011779,-.003101,
-.011689,-.003432,
-.011543,-.003742,
-.011346,-.004023,
-.011102,-.004264,
-.010821,-.00446,
-.01051,-.004604,
-.010178,-.004691,
-.00984,-.00472,
0.0*
%
%ADD52MACRO52*%
%ADD36R,.01X.02*%
%ADD185R,.02X.012*%
%AMMACRO53*
4,1,40,-.00472,.00984,
-.00472,-.00984,
-.004691,-.010182,
-.004603,-.010513,
-.004458,-.010824,
-.004262,-.011105,
-.00402,-.011348,
-.00374,-.011545,
-.003429,-.01169,
-.003098,-.01178,
-.00276,-.01181,
.00276,-.01181,
.003101,-.011779,
.003432,-.011689,
.003742,-.011543,
.004023,-.011346,
.004264,-.011102,
.00446,-.010821,
.004604,-.01051,
.004691,-.010178,
.00472,-.00984,
.00472,.00984,
.004691,.010182,
.004603,.010513,
.004458,.010824,
.004262,.011105,
.00402,.011348,
.00374,.011545,
.003429,.01169,
.003098,.01178,
.00276,.01181,
-.00276,.01181,
-.003101,.011779,
-.003432,.011689,
-.003742,.011543,
-.004023,.011346,
-.004264,.011102,
-.00446,.010821,
-.004604,.01051,
-.004691,.010178,
-.00472,.00984,
0.0*
%
%ADD53MACRO53*%
%ADD205R,.014X.01*%
%ADD149R,.05X.01*%
%ADD64R,.032X.01*%
%ADD206R,.015X.01*%
%ADD204R,.01X.014*%
%ADD157R,.122X.132*%
%ADD63R,.01X.05*%
%ADD62R,.01X.032*%
%ADD203R,.01X.015*%
%ADD94R,.011X.032*%
%ADD83R,.06X.02*%
%ADD60R,.024X.011*%
%ADD49R,.032X.012*%
%ADD97R,.015X.012*%
%ADD44R,.011X.024*%
%ADD28R,.05X.04*%
%AMMACRO153*
4,1,32,.01575,-.06201,
.01575,-.0502,
-.00197,-.0502,
-.00197,-.04035,
.01575,-.04035,
.01575,-.03248,
-.00197,-.03248,
-.00197,-.02461,
.01575,-.02461,
.01575,-.01673,
-.00197,-.01673,
-.00197,-.00886,
.01575,-.00886,
.01575,-.00098,
-.00197,-.00098,
-.00197,.00689,
.01575,.00689,
.01575,.01476,
-.00197,.01476,
-.00197,.02264,
.01575,.02264,
.01575,.03051,
-.00197,.03051,
-.00197,.03839,
.01575,.03839,
.01575,.04626,
-.00197,.04626,
-.00197,.05413,
.01575,.05413,
.01575,.06201,
-.01575,.06201,
-.01575,-.06201,
.01575,-.06201,
0.0*
%
%ADD153MACRO153*%
%ADD85R,.012X.015*%
%ADD27R,.04X.05*%
%ADD209R,.018X.011*%
%ADD207R,.04X.015*%
%ADD188R,.032X.024*%
%ADD176R,.054X.011*%
%ADD124R,.028X.01*%
%ADD99R,.02X.018*%
%ADD81R,.036X.011*%
%ADD55R,.05X.015*%
%ADD257R,.052X.014*%
%AMMACRO233*
4,1,8,-.06299,.02953,
-.06299,-.02953,
.06299,-.02953,
.06299,.02953,
.01968,.02953,
.01968,-.01771,
-.01968,-.01771,
-.01968,.02953,
-.06299,.02953,
0.0*
%
%ADD233MACRO233*%
%ADD210R,.011X.018*%
%ADD186R,.042X.024*%
%ADD177R,.011X.054*%
%ADD172R,.063X.012*%
%ADD155R,.018X.012*%
%ADD142R,.029X.01*%
%AMMACRO134*
4,1,21,0.0,-.017,
-.000955,-.016916,
-.001881,-.016668,
-.00275,-.016263,
-.003535,-.015713,
-.004213,-.015035,
-.004763,-.01425,
-.005168,-.013381,
-.005416,-.012455,
-.0055,-.0115,
-.0055,.017,
.0055,.017,
.0055,-.0115,
.005416,-.012455,
.005168,-.013381,
.004763,-.01425,
.004213,-.015035,
.003535,-.015713,
.00275,-.016263,
.001881,-.016668,
.000955,-.016916,
0.0,-.017,
0.0*
%
%ADD134MACRO134*%
%AMMACRO129*
4,1,21,.017,0.0,
.016916,-.000955,
.016668,-.001881,
.016263,-.00275,
.015713,-.003535,
.015035,-.004213,
.01425,-.004763,
.013381,-.005168,
.012455,-.005416,
.0115,-.0055,
-.017,-.0055,
-.017,.0055,
.0115,.0055,
.012455,.005416,
.013381,.005168,
.01425,.004763,
.015035,.004213,
.015713,.003535,
.016263,.00275,
.016668,.001881,
.016916,.000955,
.017,0.0,
0.0*
%
%ADD129MACRO129*%
%ADD119R,.053X.022*%
%AMMACRO88*
21,1,.016,.0041,0.0,0.0,135.*%
%ADD88MACRO88*%
%ADD86R,.018X.02*%
%ADD73R,.036X.012*%
%ADD29R,.024X.024*%
%ADD25R,.01X.028*%
%ADD240R,.27X.126*%
%ADD214R,.032X.034*%
%ADD195R,.011X.028*%
%ADD191R,.024X.042*%
%ADD179R,.022X.053*%
%ADD178R,.044X.014*%
%ADD164R,.04X.036*%
%ADD144R,.01X.029*%
%ADD121R,.014X.052*%
%ADD117R,.052X.024*%
%ADD33R,.024X.024*%
%ADD30R,.024X.016*%
%ADD262C,.122*%
%ADD259O,.044X.071*%
%ADD258R,.04X.028*%
%ADD217R,.053X.015*%
%ADD184R,.036X.032*%
%ADD181R,.063X.014*%
%ADD170R,.014X.044*%
%ADD118R,.024X.017*%
%ADD89R,.024X.052*%
%ADD58R,.016X.024*%
%ADD47R,.146X.116*%
%ADD38R,.138X.115*%
%ADD254R,.014X.063*%
%ADD198R,.054X.024*%
%ADD180R,.017X.024*%
%AMMACRO87*
4,1,8,.02,-.005,
-.002,-.005,
-.002,-.01,
-.02,-.01,
-.02,.01,
-.002,.01,
-.002,.005,
.02,.005,
.02,-.005,
0.0*
%
%ADD87MACRO87*%
%ADD78R,.115X.138*%
%ADD57R,.056X.04*%
%ADD46R,.032X.028*%
%ADD40R,.032X.036*%
%AMMACRO24*
4,1,8,.01771,.01476,
-.01772,.01476,
-.01772,-.01476,
.01771,-.01476,
.01771,-.00492,
-.00394,-.00492,
-.00394,.00492,
.01771,.00492,
.01771,.01476,
0.0*
%
%ADD24MACRO24*%
%ADD256R,.048X.04*%
%ADD246R,.056X.05*%
%ADD232R,.016X.044*%
%ADD229R,.024X.054*%
%ADD225R,.028X.024*%
%ADD222R,.022X.056*%
%ADD221R,.128X.135*%
%ADD199R,.054X.016*%
%AMMACRO165*
4,1,8,-.005,-.02,
-.005,.002,
-.01,.002,
-.01,.02,
.01,.02,
.01,.002,
.005,.002,
.005,-.02,
-.005,-.02,
0.0*
%
%ADD165MACRO165*%
%ADD127R,.046X.024*%
%ADD120R,.036X.016*%
%ADD34R,.028X.032*%
%ADD14R,.04X.056*%
%ADD228R,.016X.054*%
%ADD224R,.04X.048*%
%ADD196R,.016X.036*%
%ADD190C,.134*%
%ADD162R,.1692X.13*%
%ADD112R,.048X.014*%
%ADD102R,.054X.044*%
%ADD101R,.024X.028*%
%ADD95R,.052X.028*%
%ADD84R,.075X.032*%
%ADD19R,.024X.046*%
%ADD13C,.125*%
%ADD253R,.068X.022*%
%ADD215R,.058X.014*%
%ADD201C,.315*%
%ADD128R,.046X.017*%
%ADD104R,.044X.054*%
%ADD245R,.048X.025*%
%ADD200R,.059X.014*%
%ADD192R,.063X.046*%
%ADD137R,.091X.081*%
%ADD20R,.017X.046*%
%ADD241R,.014X.059*%
%ADD237R,.095X.024*%
%ADD189R,.025X.048*%
%ADD72R,.012X.079*%
%ADD261O,.044X.087*%
%ADD230R,.028X.046*%
%AMMACRO171*
4,1,8,.037,-.005,
-.005,-.005,
-.005,-.014,
-.037,-.014,
-.037,.014,
-.005,.014,
-.005,.005,
.037,.005,
.037,-.005,
0.0*
%
%ADD171MACRO171*%
%ADD143R,.14X.14*%
%ADD260R,.059X.017*%
%AMMACRO166*
4,1,8,-.005,-.037,
-.005,.005,
-.014,.005,
-.014,.037,
.014,.037,
.014,.005,
.005,.005,
.005,-.037,
-.005,-.037,
0.0*
%
%ADD166MACRO166*%
%AMMACRO160*
4,1,21,-.0135,-.0035,
-.014108,-.003447,
-.014697,-.003289,
-.01525,-.003031,
-.01575,-.002681,
-.016181,-.00225,
-.016531,-.00175,
-.016789,-.001197,
-.016947,-.000608,
-.017,0.0,
-.016947,.000608,
-.016789,.001197,
-.016531,.00175,
-.016181,.00225,
-.01575,.002681,
-.01525,.003031,
-.014697,.003289,
-.014108,.003447,
-.0135,.0035,
.017,.0035,
.017,-.0035,
-.0135,-.0035,
0.0*
%
%ADD160MACRO160*%
%ADD12C,.256*%
%ADD252R,.017X.059*%
%ADD223R,.038X.056*%
%ADD175R,.056X.048*%
%ADD173C,.009*%
%AMMACRO145*
4,1,21,-.0035,.0135,
-.003447,.014108,
-.003289,.014697,
-.003031,.01525,
-.002681,.01575,
-.00225,.016181,
-.00175,.016531,
-.001197,.016789,
-.000608,.016947,
0.0,.017,
.000608,.016947,
.001197,.016789,
.00175,.016531,
.00225,.016181,
.002681,.01575,
.003031,.01525,
.003289,.014697,
.003447,.014108,
.0035,.0135,
.0035,-.017,
-.0035,-.017,
-.0035,.0135,
0.0*
%
%ADD145MACRO145*%
%ADD197R,.134X.134*%
%ADD136R,.099X.042*%
%ADD41R,.048X.056*%
%ADD250R,.069X.046*%
%ADD169R,.144X.144*%
%ADD103C,.178*%
%ADD42C,.394*%
%ADD220R,.059X.048*%
%ADD43R,.166X.197*%
%ADD239R,.048X.059*%
%ADD247R,.189X.186*%
%AMMACRO183*
4,1,8,.0425,.078,
-.0425,.078,
-.0425,-.078,
.0425,-.078,
.0425,-.0236,
.0145,-.0236,
.0145,.0236,
.0425,.0236,
.0425,.078,
0.0*
%
%ADD183MACRO183*%
%ADD147R,.166X.166*%
%ADD159R,.079X.059*%
%ADD154R,.069X.077*%
%AMMACRO126*
4,1,28,.00492,.00566,
.00659,.00733,
.00269,.01122,
.002174,.011659,
.001588,.011998,
.000951,.01223,
.000284,.012348,
-.000393,.012348,
-.001061,.012231,
-.001697,.012,
-.002284,.011661,
-.002803,.011226,
-.00284,.01119,
-.01119,.00284,
-.011631,.002326,
-.011978,.001744,
-.012217,.00111,
-.012343,.000444,
-.012352,-.000233,
-.012243,-.000902,
-.012019,-.001541,
-.011688,-.002132,
-.011259,-.002656,
-.01122,-.00269,
-.00733,-.00659,
-.00566,-.00492,
.00172,-.0123,
.0123,-.00172,
.00492,.00566,
0.0*
%
%ADD126MACRO126*%
%AMMACRO106*
4,1,28,.00566,-.00492,
.00733,-.00659,
.01122,-.00269,
.011659,-.002174,
.011998,-.001588,
.01223,-.000951,
.012348,-.000284,
.012348,.000393,
.012231,.001061,
.012,.001697,
.011661,.002284,
.011226,.002803,
.01119,.00284,
.00284,.01119,
.002326,.011631,
.001744,.011978,
.00111,.012217,
.000444,.012343,
-.000233,.012352,
-.000902,.012243,
-.001541,.012019,
-.002132,.011688,
-.002656,.011259,
-.00269,.01122,
-.00659,.00733,
-.00492,.00566,
-.0123,-.00172,
-.00172,-.0123,
.00566,-.00492,
0.0*
%
%ADD106MACRO106*%
%ADD93R,.089X.085*%
%AMMACRO67*
4,1,28,-.00492,-.00566,
-.00659,-.00733,
-.00269,-.01122,
-.002174,-.011659,
-.001588,-.011998,
-.000951,-.01223,
-.000284,-.012348,
.000393,-.012348,
.001061,-.012231,
.001697,-.012,
.002284,-.011661,
.002803,-.011226,
.00284,-.01119,
.01119,-.00284,
.011631,-.002326,
.011978,-.001744,
.012217,-.00111,
.012343,-.000444,
.012352,.000233,
.012243,.000902,
.012019,.001541,
.011688,.002132,
.011259,.002656,
.01122,.00269,
.00733,.00659,
.00566,.00492,
-.00172,.0123,
-.0123,.00172,
-.00492,-.00566,
0.0*
%
%ADD67MACRO67*%
%AMMACRO22*
4,1,28,.00052,-.00748,
.00052,-.00984,
.00603,-.00984,
.006705,-.009782,
.007359,-.009607,
.007974,-.009321,
.008529,-.008933,
.009009,-.008455,
.009398,-.0079,
.009685,-.007286,
.009861,-.006632,
.00992,-.005957,
.00992,-.00591,
.00992,.00591,
.009869,.006585,
.009701,.007242,
.009421,.007859,
.009039,.008418,
.008565,.008903,
.008015,.009297,
.007404,.009591,
.006751,.009773,
.006077,.00984,
.00603,.00984,
.00052,.00984,
.00052,.00748,
-.00991,.00748,
-.00991,-.00748,
.00052,-.00748,
0.0*
%
%ADD22MACRO22*%
%AMMACRO18*
4,1,28,.00748,.00052,
.00984,.00052,
.00984,.00603,
.009782,.006705,
.009607,.007359,
.009321,.007974,
.008933,.008529,
.008455,.009009,
.0079,.009398,
.007286,.009685,
.006632,.009861,
.005957,.00992,
.00591,.00992,
-.00591,.00992,
-.006585,.009869,
-.007242,.009701,
-.007859,.009421,
-.008418,.009039,
-.008903,.008565,
-.009297,.008015,
-.009591,.007404,
-.009773,.006751,
-.00984,.006077,
-.00984,.00603,
-.00984,.00052,
-.00748,.00052,
-.00748,-.00991,
.00748,-.00991,
.00748,.00052,
0.0*
%
%ADD18MACRO18*%
%ADD133R,.168X.168*%
%ADD61R,.085X.089*%
%ADD37R,.059X.079*%
%ADD26R,.099X.067*%
%ADD77R,.067X.099*%
%AMMACRO161*
4,1,5,.01673,-.00492,
.01673,.00492,
-.01673,.00492,
-.01673,-.00098,
-.0128,-.00492,
.01673,-.00492,
0.0*
%
%ADD161MACRO161*%
%AMMACRO125*
4,1,28,.00565,.00493,
.00732,.0066,
.01121,.0027,
.011649,.002185,
.011989,.001599,
.012222,.000962,
.01234,.000295,
.012342,-.000382,
.012225,-.001049,
.011994,-.001686,
.011657,-.002273,
.011222,-.002793,
.01119,-.00283,
.00283,-.01119,
.002313,-.011629,
.00173,-.011974,
.001096,-.012212,
.00043,-.012337,
-.000247,-.012344,
-.000915,-.012234,
-.001554,-.012009,
-.002145,-.011677,
-.002668,-.011247,
-.0027,-.01121,
-.0066,-.00732,
-.00493,-.00565,
-.0123,.00173,
-.00173,.0123,
.00565,.00493,
0.0*
%
%ADD125MACRO125*%
%AMMACRO105*
4,1,28,.00493,-.00565,
.0066,-.00732,
.0027,-.01121,
.002185,-.011649,
.001599,-.011989,
.000962,-.012222,
.000295,-.01234,
-.000382,-.012342,
-.001049,-.012225,
-.001686,-.011994,
-.002273,-.011657,
-.002793,-.011222,
-.00283,-.01119,
-.01119,-.00283,
-.011629,-.002313,
-.011974,-.00173,
-.012212,-.001096,
-.012337,-.00043,
-.012344,.000247,
-.012234,.000915,
-.012009,.001554,
-.011677,.002145,
-.011247,.002668,
-.01121,.0027,
-.00732,.0066,
-.00565,.00493,
.00173,.0123,
.0123,.00173,
.00493,-.00565,
0.0*
%
%ADD105MACRO105*%
%AMMACRO71*
4,1,28,-.00565,-.00493,
-.00732,-.0066,
-.01121,-.0027,
-.011649,-.002185,
-.011989,-.001599,
-.012222,-.000962,
-.01234,-.000295,
-.012342,.000382,
-.012225,.001049,
-.011994,.001686,
-.011657,.002273,
-.011222,.002793,
-.01119,.00283,
-.00283,.01119,
-.002313,.011629,
-.00173,.011974,
-.001096,.012212,
-.00043,.012337,
.000247,.012344,
.000915,.012234,
.001554,.012009,
.002145,.011677,
.002668,.011247,
.0027,.01121,
.0066,.00732,
.00493,.00565,
.0123,-.00173,
.00173,-.0123,
-.00565,-.00493,
0.0*
%
%ADD71MACRO71*%
%AMMACRO21*
4,1,28,-.00051,-.00748,
-.00051,-.00984,
-.00602,-.00984,
-.006695,-.009782,
-.007349,-.009607,
-.007964,-.009321,
-.008519,-.008933,
-.008998,-.008455,
-.009388,-.0079,
-.009675,-.007287,
-.009851,-.006632,
-.00991,-.005958,
-.00991,-.00591,
-.00991,.00591,
-.009859,.006585,
-.009691,.007242,
-.009411,.007859,
-.009029,.008418,
-.008555,.008903,
-.008005,.009297,
-.007394,.00959,
-.006742,.009773,
-.006068,.00984,
-.00602,.00984,
-.00051,.00984,
-.00051,.00748,
.00992,.00748,
.00992,-.00748,
-.00051,-.00748,
0.0*
%
%ADD21MACRO21*%
%AMMACRO16*
4,1,28,.00748,-.00051,
.00984,-.00051,
.00984,-.00602,
.009782,-.006695,
.009607,-.007349,
.009321,-.007964,
.008933,-.008519,
.008455,-.008998,
.0079,-.009388,
.007287,-.009675,
.006632,-.009851,
.005958,-.00991,
.00591,-.00991,
-.00591,-.00991,
-.006585,-.009859,
-.007242,-.009691,
-.007859,-.009411,
-.008418,-.009029,
-.008903,-.008555,
-.009297,-.008005,
-.00959,-.007394,
-.009773,-.006742,
-.00984,-.006068,
-.00984,-.00602,
-.00984,-.00051,
-.00748,-.00051,
-.00748,.00992,
.00748,.00992,
.00748,-.00051,
0.0*
%
%ADD16MACRO16*%
%AMMACRO236*
4,1,13,-.11516,.02756,
.02744,.02756,
.031058,.025101,
.035049,.023307,
.03929,.022233,
.043653,.021912,
.048006,.022354,
.052216,.023545,
.056155,.025449,
.05917,.02756,
.11516,.02756,
.11516,-.02756,
-.11516,-.02756,
-.11516,.02756,
0.0*
%
%ADD236MACRO236*%
%AMMACRO138*
4,1,6,.1063,.04134,
.1063,-.01378,
.03543,-.01378,
.03543,-.04134,
-.1063,-.04134,
-.1063,.04134,
.1063,.04134,
0.0*
%
%ADD138MACRO138*%
%AMMACRO238*
4,1,13,-.11516,.02756,
.11516,.02756,
.11516,-.02756,
.05917,-.02756,
.055552,-.025101,
.051561,-.023307,
.04732,-.022233,
.042957,-.021912,
.038604,-.022354,
.034394,-.023545,
.030455,-.025449,
.02744,-.02756,
-.11516,-.02756,
-.11516,.02756,
0.0*
%
%ADD238MACRO238*%
%AMMACRO150*
4,1,8,.0246,.01821,
.0246,-.01821,
.01476,-.01821,
.01476,.00837,
-.01477,.00837,
-.01477,-.01821,
-.02461,-.01821,
-.02461,.01821,
.0246,.01821,
0.0*
%
%ADD150MACRO150*%
%AMMACRO23*
4,1,9,.01181,.01476,
-.01771,.01476,
-.01771,.00492,
.00394,.00492,
.00394,-.00492,
-.01771,-.00492,
-.01771,-.01476,
.01772,-.01476,
.01772,.00886,
.01181,.01476,
0.0*
%
%ADD23MACRO23*%
%ADD263C,.01*%
%ADD264C,.011*%
%ADD265C,.012*%
%ADD266C,.014*%
%ADD267C,.015*%
%ADD268C,.017*%
%ADD269C,.005*%
%ADD270C,.006*%
%ADD271C,.0043*%
%ADD272C,.007*%
%ADD273C,.0052*%
%ADD274C,.0035*%
%ADD275C,.008*%
%ADD276C,.0053*%
%ADD277C,.0045*%
%ADD278C,.0046*%
%ADD279C,.0065*%
%ADD280C,.00984*%
%ADD283C,.03004*%
%ADD281C,.03006*%
%ADD286C,.13006*%
%ADD287C,.1622*%
%ADD284C,.218*%
%ADD285C,.1742*%
%ADD282C,.16502*%
G75*
%LPD*%
G75*
G36*
G01X1081725Y1645992D02*
X1833071D01*
G02X1838945Y1640118I0J-5874D01*
G01Y970426D01*
G02X1837225Y966273I-5874J0D01*
G01X1826876Y955925D01*
G03X1823984Y948944I6982J-6982D01*
G01Y344836D01*
G03X1826876Y337855I9873J0D01*
G01X1837225Y327506D01*
G02X1838945Y323354I-4153J-4153D01*
G01Y7874D01*
G02X1833071Y2000I-5874J0D01*
G01X1756949D01*
G02X1751075Y7874I0J5874D01*
G01Y46654D01*
G03X1749600Y50571I-5938J0D01*
G01Y50666D01*
X1749606Y50672D01*
X1751979D01*
G02X1753072Y46654I-6841J-4019D01*
G01Y7874D01*
G03X1756947Y3998I3876J0D01*
G01X1833071D01*
G03X1836948Y7874I0J3877D01*
G01Y323354D01*
G03X1835813Y326094I-3876J0D01*
G01X1825464Y336443D01*
G02X1821987Y344836I8393J8394D01*
G01X1821986D01*
Y948944D01*
X1821987D01*
G02X1825464Y957337I11871J-1D01*
G01X1835813Y967685D01*
G03X1836948Y970426I-2742J2741D01*
G01Y1224424D01*
X1834890Y1226482D01*
X1824711D01*
X1820782Y1230411D01*
Y1239016D01*
X1825337Y1243571D01*
X1832026D01*
X1836948Y1248493D01*
Y1640118D01*
G03X1833073Y1643994I-3876J0D01*
G01X1633526D01*
Y1644873D01*
X1578560D01*
Y1643994D01*
X1285912D01*
Y1644677D01*
X1232543D01*
Y1643994D01*
X1081724D01*
G03X1078854Y1642722I1J-3877D01*
G02X1070058Y1638822I-8797J7971D01*
G01X800966D01*
G02X792169Y1642722I0J11872D01*
G03X789299Y1643994I-2871J-2603D01*
G01X608951D01*
Y1644464D01*
X555228D01*
Y1643994D01*
X262776D01*
Y1644377D01*
X208818D01*
Y1643994D01*
X7874D01*
G03X3998Y1640118I0J-3876D01*
G01Y970425D01*
G03X5133Y967685I3877J1D01*
G01X15480Y957338D01*
G02X18958Y948943I-8394J-8396D01*
G01Y442242D01*
X20229Y440971D01*
X127808D01*
X127882Y440941D01*
X127910Y440912D01*
X133906Y434916D01*
G02X133965Y434774I-141J-142D01*
G01Y378849D01*
G03X134024Y378707I200J0D01*
G01X140789Y371942D01*
G03X140931Y371883I142J141D01*
G01X187241D01*
G02X187317Y371868I0J-200D01*
G01X187417Y371827D01*
X187444Y371801D01*
G03X193203I2879J3061D01*
G01X193230Y371826D01*
X193336Y371869D01*
G02X193409Y371883I74J-186D01*
G01X223404D01*
X223478Y371853D01*
X223506Y371824D01*
X231169Y364161D01*
G03X231311Y364102I142J141D01*
G01X257071D01*
X257145Y364072D01*
X257173Y364043D01*
X281894Y339322D01*
G02X281953Y339180I-141J-142D01*
G01Y313310D01*
G03X282012Y313168I200J0D01*
G01X287880Y307300D01*
G03X288022Y307241I142J141D01*
G01X303308D01*
X303382Y307211D01*
X303410Y307182D01*
X311860Y298732D01*
G03X312002Y298673I142J141D01*
G01X342099D01*
G03X342241Y298732I0J200D01*
G01X345610Y302101D01*
G02X345752Y302160I142J-141D01*
G01X354584D01*
X354631Y302149D01*
G02X354742Y302078I-46J-195D01*
G01X354743Y302077D01*
X354930Y301837D01*
G02X354966Y301763I-158J-123D01*
G01X354976Y301725D01*
X354971Y301688D01*
X354968Y301663D01*
G03X354921Y301290I1455J-373D01*
G01Y301288D01*
G03X357925I1502J0D01*
G01Y301290D01*
G03X357881Y301651I-1502J0D01*
G01X357878Y301663D01*
X357870Y301727D01*
X357890Y301802D01*
X358108Y302083D01*
G02X358265Y302160I158J-123D01*
G01X418695D01*
X418769Y302130D01*
X418797Y302101D01*
X424077Y296821D01*
G02X424136Y296679I-141J-142D01*
G01Y283404D01*
G02X424077Y283262I-200J0D01*
G01X418446Y277631D01*
G02X418304Y277572I-142J141D01*
G01X403163D01*
X403131Y277540D01*
X395960D01*
X395926Y277574D01*
X393974D01*
X392522Y276122D01*
X390638D01*
X390612Y276095D01*
X389873D01*
X389563Y276405D01*
Y278760D01*
X393536Y282733D01*
Y286529D01*
X393067Y286998D01*
G03X392925Y287057I-142J-141D01*
G01X381009D01*
G03X380867Y286998I0J-200D01*
G01X380477Y286608D01*
Y278899D01*
X380236Y278658D01*
X361774D01*
G03X361632Y278599I0J-200D01*
G01X360664Y277631D01*
G02X360522Y277572I-142J141D01*
G01X300801D01*
X300769Y277540D01*
X293598D01*
X293564Y277574D01*
X291929D01*
X290477Y276122D01*
X288276D01*
X288250Y276095D01*
X287511D01*
X287201Y276405D01*
Y278760D01*
X291174Y282733D01*
Y287097D01*
X291140Y287131D01*
G03X290998Y287190I-142J-141D01*
G01X278900D01*
X278115Y286405D01*
Y278899D01*
X277874Y278658D01*
X261124D01*
X260988Y278794D01*
X260915Y278721D01*
X260887Y278692D01*
X260813Y278662D01*
X207343D01*
G03X207202Y278604I0J-200D01*
G01X206229Y277631D01*
X206201Y277602D01*
X206199Y277601D01*
X206170Y277572D01*
X198439D01*
X198407Y277540D01*
X191236D01*
X191202Y277574D01*
X189567D01*
X188115Y276122D01*
X185914D01*
X185888Y276095D01*
X185149D01*
X184839Y276405D01*
Y278760D01*
X188812Y282733D01*
Y285617D01*
X187185Y287244D01*
G03X187043Y287303I-142J-141D01*
G01X177200D01*
X175753Y285856D01*
Y278899D01*
X175512Y278658D01*
X104894D01*
X103808Y277572D01*
X96077D01*
X96045Y277540D01*
X88874D01*
X88840Y277574D01*
X87205D01*
X85753Y276122D01*
X83552D01*
X83526Y276095D01*
X82787D01*
X82477Y276405D01*
Y278760D01*
X86450Y282733D01*
Y286080D01*
X85361Y287169D01*
G03X85219Y287228I-142J-141D01*
G01X74400D01*
X73391Y286219D01*
Y278899D01*
X73150Y278658D01*
X55342D01*
X46742Y287258D01*
X46714Y287287D01*
X33772Y300229D01*
G03X33630Y300288I-142J-141D01*
G01X5300D01*
X3998Y298986D01*
Y7874D01*
G03X7874Y3998I3876J0D01*
G01X23484D01*
G03X27360Y7874I0J3876D01*
G01Y46654D01*
G02X35295Y54588I7935J-1D01*
G01X62406D01*
Y52591D01*
X35295D01*
G03X29358Y46654I0J-5937D01*
G01Y7874D01*
G02X23484Y2000I-5874J0D01*
G01X7874D01*
G02X2000Y7874I0J5874D01*
G01Y323354D01*
G02X3720Y327506I5873J-1D01*
G01X14068Y337855D01*
G03X16961Y344836I-6980J6983D01*
G01Y948943D01*
G03X14068Y955925I-9875J-1D01*
G01X3720Y966273D01*
G02X2000Y970426I4154J4153D01*
G01Y1640118D01*
G02X7874Y1645992I5874J0D01*
G01X789298D01*
G02X793649Y1644063I-1J-5873D01*
G03X800966Y1640819I7317J6631D01*
G01X1070058D01*
G03X1077374Y1644063I-1J9873D01*
G02X1081725Y1645992I4352J-3945D01*
G37*
G36*
G01X19303Y70037D02*
X27289D01*
G02X27431Y69978I0J-200D01*
G01X27611Y69798D01*
Y69633D01*
X27594Y69616D01*
X27564Y69543D01*
Y58667D01*
G02X27505Y58525I-200J0D01*
G01X27316Y58336D01*
G02X27174Y58278I-141J142D01*
G01X24807D01*
G03X24666Y58219I1J-200D01*
G01X24661Y58214D01*
X24588Y58184D01*
X24525D01*
G03X24383Y58125I0J-200D01*
G01X24028Y57770D01*
G03X23969Y57628I141J-142D01*
G01Y57605D01*
G02X23910Y57464I-200J1D01*
G01X23634Y57187D01*
G03X23576Y57046I142J-141D01*
G01Y50465D01*
G03X23634Y50324I200J0D01*
G01X23910Y50047D01*
G02X23969Y49906I-141J-142D01*
G01Y49518D01*
G02X23910Y49376I-200J0D01*
G01X22713Y48179D01*
G02X22571Y48120I-142J141D01*
G01X18385D01*
G02X18243Y48179I0J200D01*
G01X17626Y48796D01*
G02X17567Y48938I141J142D01*
G01Y68301D01*
G02X17626Y68443I200J0D01*
G01X19161Y69978D01*
G02X19303Y70037I142J-141D01*
G37*
G36*
G01X13975Y157202D02*
X15230D01*
G02X15430Y157002I0J-200D01*
G01Y153706D01*
G02X15371Y153564I-200J0D01*
G01X13741Y151935D01*
G03X13682Y151793I141J-142D01*
G01Y148662D01*
G03X13741Y148520I200J0D01*
G01X13864Y148397D01*
G03X14006Y148338I142J141D01*
G01X24712D01*
G03X24854Y148397I0J200D01*
G01X24930Y148473D01*
G03X24989Y148615I-141J142D01*
G01Y152160D01*
G03X24930Y152302I-200J0D01*
G01X24696Y152536D01*
G02X24637Y152678I141J142D01*
G01Y157031D01*
X24667Y157104D01*
X24678Y157114D01*
X30066D01*
G02X30207Y157056I0J-200D01*
G01X30226Y157037D01*
Y145090D01*
G02X30167Y144948I-200J0D01*
G01X28953Y143734D01*
G02X28811Y143675I-142J141D01*
G01X7435D01*
G02X7293Y143734I0J200D01*
G01X6486Y144541D01*
G02X6427Y144683I141J142D01*
G01Y156528D01*
G02X6486Y156670I200J0D01*
G01X6608Y156792D01*
G02X6750Y156851I142J-141D01*
G01X13459D01*
G03X13601Y156910I0J200D01*
G01X13834Y157143D01*
G02X13975Y157202I142J-141D01*
G37*
G36*
G01X17712Y161714D02*
X21158D01*
X23994Y164550D01*
X30041D01*
X30411Y164180D01*
Y158597D01*
X29930Y158116D01*
X20256D01*
X17900D01*
X17552Y158464D01*
Y161554D01*
X17712Y161714D01*
G37*
G36*
G01X6437Y158233D02*
X6422Y158248D01*
G02X6363Y158390I141J142D01*
G01Y163084D01*
G02X6422Y163226I200J0D01*
G01X6467Y163271D01*
G02X6609Y163330I142J-141D01*
G01X12026D01*
G02X12168Y163271I0J-200D01*
G01X13789Y161650D01*
G03X13931Y161591I142J141D01*
G01X15446D01*
G02X15588Y161532I0J-200D01*
G01X16061Y161059D01*
G02X16120Y160917I-141J-142D01*
G01Y158509D01*
G02X16062Y158367I-200J-1D01*
G01X15957Y158262D01*
G02X15815Y158203I-142J141D01*
G01X6510D01*
X6437Y158233D01*
G37*
G36*
G01X10320Y210785D02*
X19760D01*
X21561Y208984D01*
X22657Y207888D01*
Y187037D01*
X21710Y186090D01*
X10938D01*
X9494Y187534D01*
Y209959D01*
X10320Y210785D01*
G37*
G36*
G01X22949Y223195D02*
X32974D01*
X35427D01*
X39281Y227049D01*
X48824D01*
X49592Y226281D01*
Y214177D01*
X48759Y213344D01*
X38769D01*
X36663Y215450D01*
X33206D01*
X33025Y215268D01*
X22048D01*
X20425D01*
X19536Y214379D01*
Y212756D01*
X18765Y211985D01*
X18353D01*
X17576D01*
X9949D01*
X9289Y212645D01*
Y226569D01*
X9965Y227245D01*
X20899D01*
X22659Y225485D01*
Y223485D01*
X22949Y223195D01*
G37*
G36*
G01X7735Y988730D02*
X47968D01*
G02X48110Y988671I0J-200D01*
G01X49033Y987748D01*
G02X49092Y987606I-141J-142D01*
G01Y984054D01*
G02X49033Y983912I-200J0D01*
G01X46177Y981056D01*
G03X46118Y980914I141J-142D01*
G01Y975131D01*
G03X46177Y974989I200J0D01*
G01X46356Y974810D01*
G03X46498Y974751I142J141D01*
G01X47546D01*
G02X47744Y974575I0J-199D01*
G01Y973492D01*
X53460D01*
Y974575D01*
G02X53658Y974751I198J-23D01*
G01X53866D01*
G03X54008Y974810I0J200D01*
G01X55229Y976031D01*
G03X55288Y976173I-141J142D01*
G01Y986664D01*
G02X55347Y986806I200J0D01*
G01X55856Y987315D01*
G02X55997Y987374I142J-141D01*
G01X59289D01*
G02X59430Y987315I-1J-200D01*
G01X60251Y986494D01*
G02X60310Y986353I-141J-142D01*
G01Y982730D01*
G02X60251Y982589I-200J1D01*
G01X58421Y980759D01*
G03X58362Y980617I141J-142D01*
G01Y974686D01*
G03X58421Y974544I200J0D01*
G01X58551Y974414D01*
G03X58693Y974355I142J141D01*
G01X58698D01*
Y973492D01*
X64412D01*
Y974169D01*
G02X64612Y974355I200J-15D01*
G01X64657D01*
X65193Y974891D01*
G03X65252Y975033I-141J142D01*
G01Y986362D01*
G02X65311Y986504I200J0D01*
G01X65892Y987085D01*
G02X66034Y987144I142J-141D01*
G01X70379D01*
G02X70521Y987085I0J-200D01*
G01X70842Y986764D01*
G02X70900Y986623I-142J-141D01*
G01Y957973D01*
G02X70842Y957832I-200J0D01*
G01X69282Y956272D01*
G02X69140Y956213I-142J141D01*
G01X19283D01*
G02X19141Y956272I0J200D01*
G01X5827Y969586D01*
G02X5768Y969728I141J142D01*
G01Y986763D01*
G02X5827Y986905I200J0D01*
G01X7593Y988671D01*
G02X7735Y988730I142J-141D01*
G37*
G36*
G01X67746Y1061401D02*
Y1005636D01*
X66590Y1004480D01*
X9896D01*
X6420D01*
X6010Y1004890D01*
Y1008428D01*
X7589Y1010007D01*
Y1060188D01*
X9187Y1061786D01*
X18037D01*
G02X18179Y1061727I0J-200D01*
G01X18262Y1061644D01*
G02X18321Y1061503I-141J-142D01*
G01Y1022179D01*
G03X18379Y1022038I200J0D01*
G01X18389Y1022027D01*
G02X18448Y1021886I-141J-142D01*
G01Y1020355D01*
G03X18507Y1020213I200J0D01*
G01X19646Y1019074D01*
G03X19788Y1019015I142J141D01*
G01X45131D01*
G03X45273Y1019074I0J200D01*
G01X47230Y1021031D01*
G03X47289Y1021173I-141J142D01*
G01Y1061051D01*
X47290Y1061052D01*
Y1064160D01*
X47700Y1064570D01*
X67027D01*
X67280Y1064317D01*
X67746Y1063851D01*
Y1061401D01*
G37*
G36*
G01X36375Y1076966D02*
X36377Y1076932D01*
G03X36436Y1076804I200J14D01*
G01X45755Y1067485D01*
G02X45814Y1067343I-141J-142D01*
G01Y1022103D01*
G02X45755Y1021961I-200J0D01*
G01X45152Y1021358D01*
X45124Y1021329D01*
X45050Y1021299D01*
X20617D01*
G02X20475Y1021358I0J200D01*
G01X19381Y1022452D01*
X19352Y1022480D01*
X19322Y1022554D01*
Y1062256D01*
Y1062422D01*
Y1062746D01*
X19055Y1063013D01*
X10797D01*
X8592Y1065218D01*
Y1082394D01*
X9959Y1083761D01*
X33797D01*
X36269Y1081289D01*
Y1079813D01*
G02X36327Y1079672I-142J-141D01*
G01Y1077120D01*
G03X36343Y1077042I200J0D01*
G01X36375Y1076966D01*
G37*
G36*
G01X52448Y1097139D02*
X51610Y1096301D01*
X51582Y1096272D01*
X51508Y1096242D01*
X37299D01*
G03X37157Y1096183I0J-200D01*
G01X35734Y1094760D01*
G03X35675Y1094618I141J-142D01*
G01Y1089103D01*
G03X35734Y1088961I200J0D01*
G01X36959Y1087736D01*
G03X37101Y1087677I142J141D01*
G01X41364D01*
G02X41506Y1087618I0J-200D01*
G01X42579Y1086545D01*
G02X42638Y1086403I-141J-142D01*
G01Y1085589D01*
G03X42697Y1085447I200J0D01*
G01X43574Y1084570D01*
G03X43716Y1084511I142J141D01*
G01X44972D01*
G02X45027Y1084504I2J-200D01*
G02X45049Y1084496I-57J-192D01*
G01X45612Y1084263D01*
G03X45837Y1084190I574J1387D01*
G02X45841Y1084189I-47J-195D01*
G03X45848Y1084187I416J1442D01*
G01X45873Y1084182D01*
X45924Y1084154D01*
X45997Y1084124D01*
X48125D01*
X48199Y1084094D01*
X48227Y1084065D01*
X48287Y1084005D01*
G02X48346Y1083863I-141J-142D01*
G01Y1083573D01*
X48316Y1083499D01*
X48287Y1083471D01*
X48092Y1083276D01*
G02X47950Y1083217I-142J141D01*
G01X45373D01*
G03X45267Y1083187I-1J-200D01*
G01X45243Y1083171D01*
X45189Y1083156D01*
X45074D01*
G03X44933Y1083097I1J-200D01*
G01X44425Y1082590D01*
X43417Y1081582D01*
X43389Y1081553D01*
X43315Y1081523D01*
X38780D01*
G02X38638Y1081582I0J200D01*
G01X35195Y1085025D01*
G03X35053Y1085084I-142J-141D01*
G01X32442D01*
G03X32300Y1085025I0J-200D01*
G01X32212Y1084937D01*
X32184Y1084908D01*
X32110Y1084878D01*
X12325D01*
G02X12183Y1084937I0J200D01*
G01X9599Y1087521D01*
X9570Y1087549D01*
X9540Y1087623D01*
Y1105739D01*
G02X9599Y1105881I200J0D01*
G01X11035Y1107317D01*
G02X11177Y1107376I142J-141D01*
G01X15418D01*
G03X15560Y1107435I0J200D01*
G01X19177Y1111052D01*
G03X19236Y1111194I-141J142D01*
G01Y1144826D01*
G02X19295Y1144968I200J0D01*
G01X21042Y1146715D01*
G02X21184Y1146774I142J-141D01*
G01X52102D01*
G02X52244Y1146715I0J-200D01*
G01X52448Y1146511D01*
G02X52507Y1146369I-141J-142D01*
G01Y1097281D01*
G02X52448Y1097139I-200J0D01*
G37*
G36*
G01X17747Y1111671D02*
Y1145771D01*
X20387Y1148411D01*
X52262D01*
X53788Y1146885D01*
Y1100357D01*
Y1098585D01*
X54155Y1098218D01*
X69629D01*
X77420D01*
X78480Y1099278D01*
Y1160953D01*
X76613Y1162820D01*
X7083D01*
X5305Y1161042D01*
Y1153316D01*
Y1111360D01*
X6600Y1110065D01*
X16141D01*
X17747Y1111671D01*
G37*
G36*
G01X622043Y1345959D02*
X629404Y1338598D01*
G03X629546Y1338539I142J141D01*
G01X799098D01*
G02X799240Y1338480I0J-200D01*
G01X802574Y1335146D01*
G02X802633Y1335004I-141J-142D01*
G01Y1306693D01*
G02X802574Y1306551I-200J0D01*
G01X792623Y1296600D01*
X792595Y1296571D01*
X792521Y1296541D01*
X581220D01*
G02X581078Y1296600I0J200D01*
G01X571990Y1305688D01*
X571961Y1305716D01*
X571931Y1305790D01*
Y1408644D01*
G03X571872Y1408786I-200J0D01*
G01X565949Y1414709D01*
G03X565807Y1414768I-142J-141D01*
G01X448383D01*
X448368Y1414753D01*
X441540Y1421581D01*
G03X441398Y1421640I-142J-141D01*
G01X401601D01*
G03X401459Y1421581I0J-200D01*
G01X400936Y1421058D01*
X400916Y1421045D01*
X400915Y1421044D01*
G03X400438Y1420567I796J-1273D01*
G01X400437Y1420566D01*
X400424Y1420546D01*
X386959Y1407081D01*
G03X386900Y1406939I141J-142D01*
G01Y1337979D01*
G02X386841Y1337837I-200J0D01*
G01X378338Y1329334D01*
Y1329286D01*
X364226Y1315174D01*
G03X364167Y1315032I141J-142D01*
G01Y1303491D01*
G02X364108Y1303349I-200J0D01*
G01X360657Y1299898D01*
X360629Y1299869D01*
X360555Y1299839D01*
X20728D01*
G02X20586Y1299898I0J200D01*
G01X9907Y1310577D01*
X9878Y1310605D01*
X9848Y1310679D01*
Y1336011D01*
G02X9907Y1336153I200J0D01*
G01X13961Y1340207D01*
G02X14103Y1340266I142J-141D01*
G01X366749D01*
G03X366891Y1340325I0J200D01*
G01X372141Y1345575D01*
G03X372200Y1345717I-141J142D01*
G01Y1408874D01*
G02X372259Y1409016I200J0D01*
G01X393683Y1430440D01*
G02X393825Y1430499I142J-141D01*
G01X416604D01*
G03X416746Y1430558I0J200D01*
G01X421345Y1435157D01*
G02X421487Y1435216I142J-141D01*
G01X619545D01*
G02X619687Y1435157I0J-200D01*
G01X621925Y1432919D01*
G02X621984Y1432777I-141J-142D01*
G01Y1346101D01*
G03X622043Y1345959I200J0D01*
G37*
G36*
G01X64659Y89438D02*
X74822D01*
G02X74964Y89379I0J-200D01*
G01X75290Y89053D01*
G02X75349Y88911I-141J-142D01*
G01Y87322D01*
X75334Y87271D01*
X75320Y87247D01*
G03X70942Y74553I26904J-16381D01*
G01X70885Y74435D01*
X69828Y73378D01*
G02X69686Y73319I-142J141D01*
G01X62468D01*
G03X62268Y73119I0J-200D01*
G01Y57188D01*
G02X62209Y57046I-200J0D01*
G01X60811Y55648D01*
G02X60670Y55590I-141J142D01*
G01X35295D01*
G03X34357Y55540I6J-8937D01*
G01X34346Y55539D01*
X31737D01*
G03X31595Y55480I0J-200D01*
G01X29868Y53753D01*
X29857Y53745D01*
G03X28203Y52091I5438J-7092D01*
G01X28195Y52080D01*
X26623Y50508D01*
G02X26481Y50449I-142J141D01*
G01X25008D01*
G02X24866Y50508I0J200D01*
G01X24636Y50738D01*
G02X24577Y50880I141J142D01*
G01Y56631D01*
G02X24636Y56773I200J0D01*
G01X25080Y57217D01*
G02X25222Y57276I142J-141D01*
G01X27589D01*
G03X27731Y57335I0J200D01*
G01X28506Y58110D01*
G03X28565Y58252I-141J142D01*
G01Y69088D01*
G02X28624Y69230I200J0D01*
G01X29724Y70330D01*
G02X29866Y70389I142J-141D01*
G01X38833D01*
G03X38975Y70448I0J200D01*
G01X40014Y71487D01*
G02X40156Y71546I142J-141D01*
G01X50521D01*
G03X50663Y71605I0J200D01*
G01X53597Y74539D01*
G03X53656Y74681I-141J142D01*
G01Y84608D01*
G02X53715Y84750I200J0D01*
G01X55455Y86490D01*
G02X55597Y86549I142J-141D01*
G01X63104D01*
G03X63246Y86608I0J200D01*
G01X64079Y87441D01*
G03X64138Y87583I-141J142D01*
G01Y88917D01*
G02X64197Y89059I200J0D01*
G01X64517Y89379D01*
G02X64659Y89438I142J-141D01*
G37*
G36*
G01X23679Y186998D02*
Y210417D01*
X21671Y212425D01*
Y214067D01*
X22063Y214459D01*
X30485D01*
X30693Y214251D01*
Y212947D01*
X30641Y212895D01*
Y212503D01*
Y211814D01*
X31073Y211382D01*
X31762D01*
X35988D01*
X37316Y210054D01*
Y205828D01*
Y187369D01*
X36161Y186214D01*
X24463D01*
X23679Y186998D01*
G37*
G36*
G01X39723Y592103D02*
X26516D01*
X26231Y591818D01*
Y556112D01*
Y555516D01*
X26618Y555129D01*
X26969Y554778D01*
X35076D01*
X35655Y554199D01*
X40274D01*
X41272Y555197D01*
Y590554D01*
X39723Y592103D01*
G37*
G36*
G01X30957Y614747D02*
X29166D01*
X29044Y614625D01*
Y600460D01*
X29899Y599605D01*
X35740D01*
X35985Y599850D01*
Y603288D01*
X35740Y603533D01*
X32158D01*
X31207Y604484D01*
Y614671D01*
X31131Y614747D01*
X30957D01*
G37*
G36*
G01X35389Y614714D02*
X33171D01*
X32724D01*
X32621Y614611D01*
Y614164D01*
Y605739D01*
X32825Y605535D01*
X35695D01*
X35939Y605779D01*
Y614164D01*
X35389Y614714D01*
G37*
G36*
G01X41296Y617902D02*
X25055D01*
X24912Y617759D01*
Y615948D01*
X25075Y615785D01*
X36167D01*
X36912D01*
X37889Y616762D01*
X41276D01*
X41331Y616817D01*
Y617867D01*
X41296Y617902D01*
G37*
G36*
G01X62073Y638140D02*
X34312D01*
X33985Y638467D01*
Y642374D01*
X34555Y642944D01*
X62130D01*
X62358Y642716D01*
Y642170D01*
Y638425D01*
X62073Y638140D01*
G37*
G36*
G01X31841Y662234D02*
X30916Y661309D01*
X23475D01*
X22144Y662640D01*
Y682302D01*
X23059Y683217D01*
X24431D01*
X31202D01*
X31841Y682578D01*
Y662234D01*
G37*
G36*
G01X360419Y1035928D02*
X411072D01*
X421521Y1025479D01*
X436390D01*
G03X436449Y1025337I200J0D01*
G01X440734Y1021052D01*
G03X440876Y1020993I142J141D01*
G01X441879D01*
G02X442048Y1020899I-1J-200D01*
G01X442256Y1020569D01*
X442261Y1020466D01*
X442238Y1020419D01*
G03X442089Y1019767I1353J-652D01*
G01Y1019766D01*
G03X445093I1502J0D01*
G01Y1019767D01*
G03X444944Y1020419I-1502J0D01*
G01X444921Y1020466D01*
X444926Y1020569D01*
X445134Y1020899D01*
G02X445303Y1020993I170J-106D01*
G01X448464D01*
G02X448606Y1020934I0J-200D01*
G01X450086Y1019454D01*
G02X450145Y1019312I-141J-142D01*
G01Y1012209D01*
G02X450086Y1012067I-200J0D01*
G01X449057Y1011038D01*
G02X448915Y1010979I-142J141D01*
G01X412045D01*
G02X411903Y1011038I0J200D01*
G01X405531Y1017410D01*
G03X405389Y1017469I-142J-141D01*
G01X342969D01*
G02X342821Y1017535I0J200D01*
G01X342594Y1017786D01*
X342568Y1017866D01*
X342572Y1017908D01*
G03X342579Y1018056I-1495J145D01*
G03X339575I-1502J0D01*
G03X339582Y1017908I1502J-3D01*
G01X339586Y1017866D01*
X339560Y1017786D01*
X339333Y1017535D01*
G02X339184Y1017469I-148J134D01*
G01X339147D01*
G02X338947Y1017669I0J200D01*
G01Y1017707D01*
X338961Y1017742D01*
G03X339066Y1018293I-1397J552D01*
G01Y1018294D01*
G03X336062I-1502J0D01*
G01Y1018293D01*
G03X336100Y1017958I1502J1D01*
G01X336110Y1017914D01*
X336090Y1017824D01*
X335866Y1017544D01*
G02X335710Y1017469I-156J125D01*
G01X335664D01*
G02X335464Y1017669I0J200D01*
G01Y1017685D01*
X335467Y1017701D01*
G03X335487Y1017945I-1482J244D01*
G03X332483I-1502J0D01*
G03X332484Y1017885I1502J-5D01*
G01X332486Y1017844D01*
X332458Y1017768D01*
X332229Y1017530D01*
G02X332085Y1017469I-144J139D01*
G01X210259D01*
G03X210117Y1017410I0J-200D01*
G01X187257Y994551D01*
G03X187198Y994409I141J-142D01*
G01Y829148D01*
G02X187139Y829006I-200J0D01*
G01X50504Y692371D01*
G02X50492Y692360I-141J142D01*
G01Y662745D01*
X49161Y661414D01*
X34629D01*
X33357Y662686D01*
Y683065D01*
X31207Y685215D01*
Y707877D01*
G02X31266Y708019I200J0D01*
G01X31871Y708624D01*
G02X32013Y708683I142J-141D01*
G01X48075D01*
G03X48217Y708742I0J200D01*
G01X75172Y735697D01*
G03X91705Y752230I-12967J29500D01*
G01X168697Y829222D01*
G03X168756Y829364I-141J142D01*
G01Y1010622D01*
G02X168815Y1010764I200J0D01*
G01X193920Y1035869D01*
G02X194062Y1035928I142J-141D01*
G01X345485D01*
G02X345532Y1035922I-2J-200D01*
G03X360372I7420J30613D01*
G02X360419Y1035928I49J-194D01*
G37*
G36*
G01X53929Y1174474D02*
X34623D01*
X31041D01*
X29387D01*
X28796Y1175065D01*
Y1192544D01*
X30298Y1194046D01*
X34969D01*
X38474Y1197551D01*
Y1204333D01*
X38744Y1204603D01*
X39284D01*
X39664Y1204223D01*
Y1191173D01*
X40789Y1190048D01*
X40794D01*
X42129Y1188713D01*
X42229Y1188613D01*
X48153D01*
X50245D01*
X50698D01*
X50919Y1188834D01*
X51023Y1188938D01*
Y1193220D01*
X51168Y1193365D01*
X53106D01*
X54500Y1191971D01*
Y1191591D01*
Y1175045D01*
X53929Y1174474D01*
G37*
G36*
G01X58756Y1219220D02*
X53073D01*
X52585Y1219708D01*
Y1225928D01*
Y1255004D01*
X50332Y1257257D01*
X40904D01*
X36404Y1252757D01*
Y1200904D01*
X36241Y1200741D01*
X22447D01*
X22021Y1201167D01*
Y1212017D01*
X23622Y1213618D01*
G03X29616Y1226024I-9842J12406D01*
G03X22514Y1239234I-15837J0D01*
G01Y1247134D01*
X22494Y1247154D01*
Y1251460D01*
X22502Y1251468D01*
Y1261267D01*
Y1266747D01*
X23260Y1267505D01*
X63261D01*
X64906Y1265860D01*
Y1220164D01*
X63962Y1219220D01*
X58756D01*
G37*
G36*
G01X28153Y1199741D02*
X36164D01*
X36334Y1199571D01*
Y1198191D01*
X35724Y1197581D01*
X28127D01*
X27946Y1197762D01*
Y1199534D01*
X28153Y1199741D01*
G37*
G36*
G01X28836Y1533196D02*
X50780D01*
X51652Y1532324D01*
Y1511058D01*
X50586Y1509992D01*
X29465D01*
X28593Y1510864D01*
Y1532953D01*
X28836Y1533196D01*
G37*
G36*
G01X39593Y86514D02*
X48308D01*
X48661Y86161D01*
Y73377D01*
X48215Y72931D01*
X39817D01*
X39482Y73266D01*
Y86403D01*
X39593Y86514D01*
G37*
G36*
G01X50014Y488854D02*
Y499374D01*
Y501186D01*
X50601Y501773D01*
X57433D01*
X57941Y501265D01*
Y499252D01*
Y487471D01*
Y486284D01*
X58640Y485585D01*
X59827D01*
X61224Y484188D01*
Y483142D01*
Y475515D01*
X60973Y475264D01*
X56490D01*
X56081Y474855D01*
X47770D01*
X47122Y475503D01*
Y487623D01*
X47868Y488369D01*
X49529D01*
X50014Y488854D01*
G37*
G36*
G01X48110Y545147D02*
Y533484D01*
X51393Y530201D01*
Y529803D01*
Y518852D01*
G02X51334Y518710I-200J0D01*
G01X51286Y518662D01*
G03X51227Y518520I141J-142D01*
G01Y504632D01*
G02X51168Y504490I-200J0D01*
G01X50089Y503411D01*
G02X49947Y503352I-142J141D01*
G01X36460D01*
G02X36318Y503411I0J200D01*
G01X35652Y504077D01*
G02X35593Y504219I141J142D01*
G01Y532166D01*
X37698Y534271D01*
Y534788D01*
Y535061D01*
X37726Y535089D01*
X40067D01*
X40183Y535205D01*
Y535259D01*
Y544824D01*
Y545347D01*
X40522Y545686D01*
X41045D01*
X47571D01*
X48110Y545147D01*
G37*
G36*
G01X42835Y615406D02*
X57636D01*
X58165Y614877D01*
Y607165D01*
X57000Y606000D01*
Y594000D01*
X58165Y592835D01*
Y573133D01*
X61664Y569634D01*
X67964D01*
X68786Y570456D01*
X70795Y572466D01*
Y577231D01*
X71343Y577779D01*
X72659D01*
X73654Y578774D01*
Y580708D01*
X74041Y581095D01*
Y583479D01*
X74106Y583544D01*
X74911D01*
X74948Y583507D01*
Y579964D01*
X75349Y579563D01*
Y579518D01*
X76642Y578225D01*
Y570737D01*
X74442Y568537D01*
Y556856D01*
X74471Y556827D01*
Y551391D01*
X76236Y549626D01*
X79563D01*
X80566Y548623D01*
Y536737D01*
X79818Y535989D01*
X52961D01*
X50953Y533981D01*
X49311D01*
X48919Y534373D01*
Y542795D01*
X49127Y543003D01*
X50431D01*
X50483Y542951D01*
X50875D01*
X51508D01*
X51996Y543439D01*
Y544072D01*
Y548298D01*
X51990D01*
X51122Y549166D01*
X43997D01*
X42755Y550408D01*
Y554389D01*
X42737Y554407D01*
Y596265D01*
X42835Y596363D01*
Y615406D01*
G37*
G36*
G01X41802Y615416D02*
X39930D01*
X38438Y613924D01*
Y596847D01*
X38937Y596348D01*
X41406D01*
X41835Y596777D01*
Y615383D01*
X41802Y615416D01*
G37*
G36*
G01X58950Y621858D02*
X42392D01*
X42341Y621807D01*
Y616817D01*
X42426Y616732D01*
X59319D01*
X63746Y612305D01*
X82996D01*
X83605Y612914D01*
Y624584D01*
X82084Y626105D01*
X63197D01*
X58950Y621858D01*
G37*
G36*
G01X65849Y839218D02*
Y820318D01*
X65149Y819618D01*
X45449D01*
X44949Y820118D01*
Y828518D01*
X45149Y828718D01*
X52149D01*
X52749Y828118D01*
Y822818D01*
X53349Y822218D01*
X58649D01*
X59249Y822818D01*
Y839318D01*
Y839718D01*
X58249Y840718D01*
Y844318D01*
X58549Y844618D01*
X65549D01*
X65849Y844318D01*
Y842218D01*
Y839218D01*
G37*
G36*
G01X45549Y839518D02*
X52149D01*
X53149Y838518D01*
Y837018D01*
X54149Y836018D01*
X57849D01*
X58149Y835718D01*
Y831518D01*
X57949Y831318D01*
X45349D01*
X45049Y831618D01*
Y839018D01*
X45549Y839518D01*
G37*
G36*
G01X52049Y849718D02*
X56549D01*
X57149Y849118D01*
Y840418D01*
X57247Y840320D01*
Y840303D01*
X58247Y839303D01*
Y837116D01*
X58151Y837020D01*
X54747D01*
X54549Y837218D01*
Y839418D01*
X51249Y842718D01*
Y848918D01*
X52049Y849718D01*
G37*
G36*
G01X49236Y1080283D02*
X50009D01*
X50179Y1080113D01*
Y1077814D01*
X51020Y1076973D01*
Y1075416D01*
X51044Y1075392D01*
Y1071129D01*
X50762Y1070847D01*
X46944D01*
X43750Y1074041D01*
Y1074797D01*
X49236Y1080283D01*
G37*
G36*
G01X49485Y1087985D02*
X55828D01*
X55995Y1087818D01*
Y1081508D01*
X55815Y1081328D01*
X49551D01*
X49384Y1081495D01*
Y1087884D01*
X49485Y1087985D01*
G37*
G36*
G01X45406Y1082154D02*
X48290D01*
X48361Y1082083D01*
Y1081247D01*
Y1080958D01*
X43309Y1075906D01*
X38874D01*
X37329Y1077451D01*
Y1079927D01*
X37918Y1080516D01*
X43768D01*
X45406Y1082154D01*
G37*
G36*
G01X43795Y1198212D02*
Y1199602D01*
X43954Y1199761D01*
X47124D01*
X47336Y1199548D01*
Y1198550D01*
Y1197963D01*
X49923Y1195376D01*
Y1190942D01*
X49685Y1190704D01*
X47738D01*
X47457D01*
X46981Y1191180D01*
Y1194057D01*
X43795Y1197243D01*
Y1198212D01*
G37*
G36*
G01X42633Y1192043D02*
X41024D01*
X40814Y1192253D01*
Y1205553D01*
X39367Y1207000D01*
X37512Y1208855D01*
Y1244101D01*
X38291Y1244880D01*
X50546D01*
X51498Y1243928D01*
Y1227006D01*
Y1220718D01*
X49139Y1218359D01*
X47610D01*
X42034Y1212783D01*
Y1196663D01*
X43001Y1195696D01*
Y1192411D01*
X42633Y1192043D01*
G37*
G36*
G01X51703Y1218206D02*
G03I-506J0D01*
G37*
G36*
G01X48897Y1246478D02*
X42075D01*
X41402Y1247151D01*
Y1252559D01*
Y1254613D01*
X41581Y1254792D01*
X41895Y1255106D01*
X49212D01*
X49526Y1254792D01*
X49885Y1254433D01*
Y1252300D01*
Y1246735D01*
X49628Y1246478D01*
X48897D01*
G37*
G36*
G01X67622Y95055D02*
X74504D01*
X75384Y94175D01*
Y91144D01*
X75026Y90786D01*
X67859D01*
X67820Y90747D01*
X67543Y91024D01*
Y94976D01*
X67622Y95055D01*
G37*
G36*
G01X70709Y175943D02*
Y174878D01*
G03X70768Y174736I200J0D01*
G01X71413Y174091D01*
G03X71555Y174032I142J141D01*
G01X74497D01*
G02X74639Y173973I0J-200D01*
G01X75108Y173504D01*
G02X75167Y173362I-141J-142D01*
G01Y161506D01*
G02X75108Y161364I-200J0D01*
G01X74522Y160778D01*
G02X74380Y160719I-142J141D01*
G01X56164D01*
Y160720D01*
X54251D01*
G02X54109Y160779I0J200D01*
G01X53466Y161422D01*
G02X53407Y161564I141J142D01*
G01Y176120D01*
G02X53466Y176262I200J0D01*
G01X53934Y176730D01*
G02X54076Y176789I142J-141D01*
G01X69863D01*
G02X70005Y176730I0J-200D01*
G01X70650Y176085D01*
G02X70709Y175943I-141J-142D01*
G37*
G36*
G01X82521Y219609D02*
X83997D01*
G02X84139Y219550I0J-200D01*
G01X84221Y219468D01*
G02X84280Y219327I-141J-142D01*
G01Y211102D01*
G02X84208Y210949I-200J1D01*
G01X83939Y210723D01*
X83855Y210700D01*
X83811Y210708D01*
G03X83552Y210730I-256J-1479D01*
G03X83059Y210647I-1J-1501D01*
G01X82985Y210621D01*
X82930Y210634D01*
G03X82885Y210639I-44J-195D01*
G01X82599D01*
X81627D01*
X81395Y210407D01*
Y209435D01*
Y204885D01*
G02X81336Y204743I-200J0D01*
G01X70985Y194392D01*
G03X70926Y194250I141J-142D01*
G01Y189274D01*
G03X70985Y189132I200J0D01*
G01X74504Y185613D01*
G03X74646Y185554I142J141D01*
G01X79245D01*
G02X79387Y185495I0J-200D01*
G01X79817Y185065D01*
G02X79876Y184923I-141J-142D01*
G01Y183773D01*
G03X79935Y183631I200J0D01*
G01X80812Y182754D01*
G03X80954Y182695I142J141D01*
G01X82516D01*
G02X82592Y182680I0J-200D01*
G01X82932Y182539D01*
G03X82943Y182535I484J1314D01*
G01X82981Y182519D01*
X83133Y182367D01*
G03X83275Y182308I142J141D01*
G01X85323D01*
G02X85465Y182249I0J-200D01*
G01X85525Y182189D01*
G02X85584Y182047I-141J-142D01*
G01Y181797D01*
G02X85525Y181655I-200J0D01*
G01X85330Y181460D01*
G02X85188Y181401I-142J141D01*
G01X82144D01*
G03X82002Y181342I0J-200D01*
G01X81660Y181000D01*
X81615D01*
X80381Y179766D01*
G02X80239Y179707I-142J141D01*
G01X54846D01*
G02X54704Y179766I0J200D01*
G01X53510Y180960D01*
G02X53451Y181102I141J142D01*
G01Y216615D01*
G02X53510Y216757I200J0D01*
G01X54295Y217542D01*
G02X54437Y217601I142J-141D01*
G01X80347D01*
G03X80489Y217660I0J200D01*
G01X82379Y219550D01*
G02X82521Y219609I142J-141D01*
G37*
G36*
G01X80798Y234621D02*
Y221520D01*
X78997Y219719D01*
X77901Y218623D01*
X55060D01*
X53332Y220351D01*
Y252516D01*
X54643Y253827D01*
X76883D01*
X80798Y249912D01*
Y234621D01*
G37*
G36*
G01X55678Y277007D02*
X63107D01*
X75558D01*
X77415Y275150D01*
X79994D01*
X80269Y274875D01*
Y272398D01*
X79719Y271848D01*
X77175D01*
X77071Y271952D01*
X73391Y268272D01*
Y265554D01*
X70193Y262356D01*
X55609D01*
X54921Y263044D01*
Y276250D01*
X55678Y277007D01*
G37*
G36*
G01X76143Y451919D02*
X70143D01*
X69059D01*
X67497D01*
X67244Y451666D01*
Y446698D01*
X67984Y445958D01*
X69615D01*
X76059D01*
X76643Y446542D01*
Y451419D01*
X76143Y451919D01*
G37*
G36*
G01X61769Y456982D02*
X59129D01*
X58470Y457641D01*
Y460485D01*
Y461933D01*
X58465Y461937D01*
Y462774D01*
X57744Y463495D01*
X53755D01*
X53039Y462779D01*
Y462195D01*
Y460910D01*
Y458716D01*
Y454556D01*
X53574Y454021D01*
X62359D01*
X62370Y454032D01*
Y456381D01*
X61769Y456982D01*
G37*
G36*
G01X164206Y554616D02*
X177028D01*
G02X177170Y554557I0J-200D01*
G01X178391Y553336D01*
X178406Y553300D01*
G03X178676Y553030I463J193D01*
G01X178712Y553015D01*
X179138Y552589D01*
G03X179280Y552530I142J141D01*
G01X179735D01*
X179800Y552506D01*
X179828Y552483D01*
G03X181269Y551956I1442J1710D01*
G01X183646D01*
G02X183846Y551756I0J-200D01*
G01Y551373D01*
G02X183787Y551231I-200J0D01*
G01X183702Y551146D01*
G02X183560Y551087I-142J141D01*
G01X178440D01*
G03X178298Y551028I0J-200D01*
G01X176184Y548914D01*
G02X176042Y548855I-142J141D01*
G01X174673D01*
G03X174531Y548796I0J-200D01*
G01X166822Y541087D01*
G02X166680Y541028I-142J141D01*
G01X156025D01*
X156013Y541029D01*
G03X155698Y541048I-322J-2723D01*
G03X155383Y541029I7J-2742D01*
G01X155371Y541028D01*
X153925D01*
X153913Y541029D01*
G03X153598Y541048I-322J-2723D01*
G03X153283Y541029I7J-2742D01*
G01X153271Y541028D01*
X136854D01*
G03X136712Y540969I0J-200D01*
G01X123148Y527405D01*
G03X123089Y527263I141J-142D01*
G01Y474821D01*
G02X123030Y474679I-200J0D01*
G01X102381Y454030D01*
G02X102239Y453971I-142J141D01*
G01X78622D01*
X78600Y453949D01*
G02X78458Y453890I-142J141D01*
G01X74797D01*
G02X74655Y453949I0J200D01*
G01X74633Y453971D01*
X72434D01*
Y453993D01*
X64116D01*
G02X63916Y454193I0J200D01*
G01Y456924D01*
X63946Y456997D01*
X63952Y457003D01*
X66697D01*
G03X66839Y457062I0J200D01*
G01X69672Y459895D01*
G03X69731Y460037I-141J142D01*
G01Y465233D01*
G02X69790Y465375I200J0D01*
G01X72434Y468019D01*
Y468025D01*
X73061Y468652D01*
G02X73203Y468711I142J-141D01*
G01X85137D01*
G03X85279Y468770I0J200D01*
G01X88459Y471950D01*
G03X88518Y472092I-141J142D01*
G01Y487807D01*
G03X88459Y487949I-200J0D01*
G01X87234Y489174D01*
G03X87092Y489233I-142J-141D01*
G01X62863D01*
G03X62721Y489174I0J-200D01*
G01X60819Y487272D01*
G02X60677Y487213I-142J141D01*
G01X59142D01*
G02X58942Y487413I0J200D01*
G01Y495744D01*
G02X59014Y495897I200J-1D01*
G01X59283Y496123D01*
X59367Y496146D01*
X59411Y496138D01*
G03X59670Y496116I256J1479D01*
G03X60163Y496199I1J1501D01*
G01X60237Y496225D01*
X60292Y496212D01*
G03X60337Y496207I44J195D01*
G01X60623D01*
X61452D01*
X61827Y496582D01*
Y497411D01*
Y500592D01*
G02X61886Y500734I200J0D01*
G01X62745Y501593D01*
G02X62887Y501652I142J-141D01*
G01X80618D01*
G03X80760Y501711I0J200D01*
G01X84347Y505298D01*
G03X84406Y505440I-141J142D01*
G01Y528321D01*
G02X84465Y528463I200J0D01*
G01X107110Y551108D01*
G02X107252Y551167I142J-141D01*
G01X140698D01*
G02X140830Y551117I0J-200D01*
G03X142024Y550664I1195J1349D01*
G03X143218Y551117I-1J1802D01*
G02X143350Y551167I132J-150D01*
G01X157653D01*
G02X157779Y551122I0J-200D01*
G03X160309I1265J1553D01*
G01X160336Y551144D01*
X160400Y551167D01*
X160591D01*
G03X160733Y551226I0J200D01*
G01X164064Y554557D01*
G02X164206Y554616I142J-141D01*
G37*
G36*
G01X62424Y475886D02*
Y485326D01*
X64225Y487127D01*
X65321Y488223D01*
X86172D01*
X87119Y487276D01*
Y476504D01*
X85675Y475060D01*
X63250D01*
X62424Y475886D01*
G37*
G36*
G01X52593Y518969D02*
Y532070D01*
X54394Y533871D01*
X55490Y534967D01*
X78331D01*
X81774Y531524D01*
Y520887D01*
Y504757D01*
X80616Y503599D01*
X54202D01*
X52593Y505208D01*
Y518969D01*
G37*
G36*
G01X210015Y1015809D02*
X351943D01*
G02X352083Y1015752I0J-200D01*
G01X363815Y1004020D01*
G02X363817Y1004018I-140J-142D01*
G02X363874Y1003878I-143J-140D01*
G01Y970120D01*
G02X363858Y970043I-200J1D01*
G03X363762Y969566I1142J-478D01*
G01Y953081D01*
G02X363703Y952940I-200J1D01*
G01X360197Y949433D01*
G03X359534Y947834I1599J-1600D01*
G01Y940718D01*
G03X360197Y939119I2262J1D01*
G01X360939Y938377D01*
G03X362538Y937714I1600J1599D01*
G01X365196D01*
G02X365337Y937656I0J-200D01*
G01X366379Y936614D01*
G02X366427Y936536I-142J-141D01*
G01Y936535D01*
G02X366433Y936430I-189J-63D01*
G01X366350Y936051D01*
X366284Y935975D01*
X366236Y935957D01*
G03X365259Y934550I525J-1407D01*
G03X366761Y933048I1502J0D01*
G03X368168Y934025I0J1502D01*
G01X368186Y934073D01*
X368262Y934139D01*
X368641Y934222D01*
G02X368746Y934216I42J-195D01*
G01X368747D01*
G02X368825Y934168I-63J-190D01*
G01X373613Y929380D01*
G02X373615Y929378I-140J-142D01*
G02X373672Y929238I-143J-140D01*
G01Y863079D01*
G03X373731Y862937I200J0D01*
G01X390497Y846171D01*
G02X390499Y846169I-140J-142D01*
G02X390556Y846029I-143J-140D01*
G01Y832224D01*
G03X390615Y832082I200J0D01*
G01X398470Y824227D01*
G03X398612Y824168I142J141D01*
G01X450610D01*
G03X450752Y824227I0J200D01*
G01X456550Y830025D01*
G03X456609Y830167I-141J142D01*
G01Y967176D01*
G02X456668Y967318I200J0D01*
G01X457438Y968088D01*
G02X457580Y968147I142J-141D01*
G01X486442D01*
G02X486584Y968088I0J-200D01*
G01X499203Y955469D01*
G02X499262Y955327I-141J-142D01*
G01Y909544D01*
G02X499203Y909402I-200J0D01*
G01X482400Y892598D01*
G03X481748Y891024I1574J-1574D01*
G01Y831903D01*
G03X482400Y830329I2226J0D01*
G01X483241Y829487D01*
G02X483300Y829345I-141J-142D01*
G01Y826083D01*
G03X483359Y825941I200J0D01*
G01X493934Y815366D01*
G02X493993Y815224I-141J-142D01*
G01Y809607D01*
G03X494008Y809530I200J-1D01*
G01X494037Y809462D01*
G02X494052Y809385I-185J-76D01*
G01Y775269D01*
G02X493884Y775072I-200J0D01*
G01X493496Y775008D01*
G02X493471Y775006I-28J198D01*
G02X493273Y775143I-8J200D01*
G03X472251Y795423I-29887J-9945D01*
G01X472226Y795430D01*
X472184Y795455D01*
X471587Y796052D01*
G02X471528Y796194I141J142D01*
G01Y799112D01*
X471531Y799128D01*
G03X471562Y799500I-2217J372D01*
G03X469300Y801762I-2262J0D01*
G01X437984D01*
G02X437842Y801820I-1J200D01*
G01X434163Y805499D01*
G03X432564Y806162I-1600J-1599D01*
G01X389136D01*
G03X387537Y805499I1J-2262D01*
G01X385566Y803529D01*
G02X385339Y803489I-142J141D01*
G01X384941Y803678D01*
X384879Y803788D01*
X384886Y803851D01*
G03X384893Y804000I-1495J145D01*
G03X383391Y802498I-1502J0D01*
G03X383540Y802505I4J1502D01*
G01X383603Y802512D01*
X383713Y802450D01*
X383902Y802052D01*
G02X383862Y801825I-181J-85D01*
G01X377758Y795721D01*
G02X377617Y795662I-142J141D01*
G01X373934D01*
G03X373792Y795603I0J-200D01*
G01X373453Y795264D01*
X373394Y795235D01*
X373360Y795231D01*
G03X372247Y794689I231J-1888D01*
G01X370091Y792533D01*
G03X369534Y791188I1345J-1345D01*
G03X370642Y789460I1901J0D01*
G01X370696Y789435D01*
X370759Y789337D01*
Y784984D01*
G02X370700Y784842I-200J0D01*
G01X369567Y783708D01*
G03X369138Y782675I1032J-1034D01*
G01Y779388D01*
G02X369080Y779247I-200J0D01*
G01X365062Y775229D01*
X365044Y775217D01*
G03X364348Y773950I805J-1267D01*
G01Y773949D01*
G03X364488Y773316I1502J0D01*
G01X364507Y773276D01*
Y772334D01*
G03X364566Y772192I200J0D01*
G01X369271Y767487D01*
G02X369330Y767347I-141J-142D01*
G01X369331Y767227D01*
G02X369282Y767094I-200J-2D01*
G03X368913Y766108I1133J-986D01*
G03X369913Y764692I1503J0D01*
G01X369956Y764677D01*
X371167Y763467D01*
G03X371463Y763238I1035J1032D01*
G02X371562Y763066I-101J-173D01*
G01Y751420D01*
G02X371472Y751253I-200J0D01*
G03Y748747I828J-1253D01*
G02X371562Y748580I-110J-167D01*
G01Y747648D01*
G02X371484Y747490I-200J1D01*
G03Y745110I915J-1190D01*
G02X371562Y744952I-122J-159D01*
G01Y742161D01*
G03X371621Y742019I200J0D01*
G01X375781Y737859D01*
G03X375923Y737800I142J141D01*
G01X445034D01*
G02X445176Y737741I0J-200D01*
G01X446634Y736283D01*
G02X446693Y736141I-141J-142D01*
G01Y731348D01*
G02X446634Y731206I-200J0D01*
G01X444575Y729147D01*
G02X444433Y729088I-142J141D01*
G01X426372D01*
G02X426210Y729171I0J200D01*
G03X423776I-1217J-880D01*
G02X423614Y729088I-162J117D01*
G01X399796D01*
G03X399654Y729029I0J-200D01*
G01X395626Y725001D01*
G03X395567Y724859I141J-142D01*
G01Y656601D01*
G02X395508Y656459I-200J0D01*
G01X371339Y632290D01*
X371311Y632261D01*
X371237Y632231D01*
X283387D01*
G02X283204Y632350I0J200D01*
G03X275517I-3844J-1701D01*
G02X275334Y632231I-183J81D01*
G01X260584D01*
G02X260442Y632290I0J200D01*
G01X257005Y635727D01*
X256976Y635755D01*
X256946Y635829D01*
Y678651D01*
G03X256887Y678793I-200J0D01*
G01X253154Y682526D01*
G03X253012Y682585I-142J-141D01*
G01X237479D01*
G03X237337Y682526I0J-200D01*
G01X229458Y674647D01*
G03X229399Y674505I141J-142D01*
G01Y640608D01*
G02X229340Y640466I-200J0D01*
G01X221164Y632290D01*
X221136Y632261D01*
X221062Y632231D01*
X187461D01*
G02X187278Y632350I0J200D01*
G03X179592I-3843J-1701D01*
G02X179409Y632231I-183J81D01*
G01X174390D01*
G02X174248Y632290I0J200D01*
G01X156297Y650241D01*
G03X156155Y650300I-142J-141D01*
G01X152323D01*
G03X152181Y650241I0J-200D01*
G01X145190Y643250D01*
G03X145131Y643108I141J-142D01*
G01Y602600D01*
X147217Y600514D01*
X150924D01*
X151352Y600086D01*
Y589755D01*
X152456Y588651D01*
X155253D01*
X155839Y588065D01*
Y584209D01*
X155478Y583848D01*
X141654D01*
X96052D01*
X90500Y589400D01*
Y605261D01*
X88838Y606923D01*
X88809Y606951D01*
X88779Y607025D01*
Y622241D01*
X83789Y627231D01*
X62846D01*
X62503Y627574D01*
Y632025D01*
X63054Y632576D01*
X67145D01*
X67653Y633084D01*
Y640798D01*
X68671Y641816D01*
X83284D01*
X83315Y641785D01*
X90546D01*
G03X90688Y641844I0J200D01*
G01X101997Y653153D01*
G03X102056Y653295I-141J142D01*
G01Y739397D01*
G02X102113Y739537I200J0D01*
G01X117096Y754520D01*
G02X117272Y754576I142J-141D01*
G01X117594Y754520D01*
G02X117741Y754409I-33J-197D01*
G03X119099Y753550I1358J644D01*
G03X120601Y755052I0J1502D01*
G01X120602D01*
G03X119743Y756410I-1503J0D01*
G02X119631Y756557I85J181D01*
G01X119575Y756879D01*
G02X119631Y757055I197J34D01*
G01X119874Y757298D01*
G02X120041Y757353I140J-143D01*
G03X120250Y757339I205J1488D01*
G03X121752Y758841I0J1502D01*
G03X121738Y759050I-1502J4D01*
G01X121731Y759097D01*
X121760Y759184D01*
X188191Y825615D01*
G03X188250Y825757I-141J142D01*
G01Y994045D01*
G02X188309Y994186I200J-1D01*
G01X209874Y1015750D01*
G02X210015Y1015809I142J-141D01*
G37*
G36*
G01X73670Y672370D02*
X74576D01*
X74810Y672135D01*
Y669543D01*
Y669011D01*
Y664876D01*
X74688Y664754D01*
X61997D01*
X61462Y665289D01*
Y678595D01*
X62058Y679191D01*
X62751D01*
X63814D01*
X70081D01*
X71051Y678221D01*
Y674989D01*
X73670Y672370D01*
G37*
G36*
G01X54749Y830018D02*
X57349D01*
X57749Y829618D01*
Y824018D01*
X57249Y823518D01*
X55049D01*
X54649Y823918D01*
Y829918D01*
X54749Y830018D01*
G37*
G36*
G01X67249Y834118D02*
X72149D01*
X72899Y833368D01*
Y829768D01*
X73249Y829418D01*
X73749Y828918D01*
X76249D01*
X76349Y828818D01*
Y820318D01*
X75649Y819618D01*
X67549D01*
X66949Y820218D01*
Y833818D01*
X67249Y834118D01*
G37*
G36*
G01X69149Y837118D02*
X67349D01*
X67149Y837318D01*
Y843418D01*
Y843818D01*
Y848571D01*
X67308Y848730D01*
X69693D01*
X69914Y848509D01*
Y844183D01*
X69549Y843818D01*
Y837318D01*
X69349Y837118D01*
X69149D01*
G37*
G36*
G01X76049Y836018D02*
Y830618D01*
X75749Y830318D01*
X74249D01*
X74049Y830518D01*
Y834118D01*
X73049Y835118D01*
X67149D01*
X66949Y835318D01*
Y835818D01*
X67049Y835918D01*
X70649D01*
X71349Y836618D01*
X75849D01*
X76049Y836418D01*
Y836018D01*
G37*
G36*
G01X66593Y1209382D02*
G03I-653J0D01*
G37*
G36*
G01X137657Y54588D02*
X164284D01*
Y52591D01*
X137657D01*
G03X131720Y46654I0J-5937D01*
G01Y7874D01*
G02X125846Y2000I-5874J0D01*
G01X78602D01*
G02X72728Y7874I0J5874D01*
G01Y46323D01*
X74726D01*
Y7874D01*
G03X78602Y3998I3876J0D01*
G01X125846D01*
G03X129722Y7874I0J3876D01*
G01Y46654D01*
G02X137657Y54588I7935J-1D01*
G37*
G36*
G01X87533Y276354D02*
X105106D01*
X105932Y275528D01*
Y258570D01*
X104750Y257388D01*
Y233430D01*
X97798Y226478D01*
Y224471D01*
Y220921D01*
X95498Y218621D01*
X93498D01*
X93208Y218331D01*
Y205660D01*
X92621Y205073D01*
X85789D01*
X85281Y205581D01*
Y220421D01*
X81998Y223704D01*
Y234821D01*
X82164Y234987D01*
Y250246D01*
X85328Y253410D01*
X85364D01*
X87584Y255630D01*
Y268925D01*
X84575Y271934D01*
X82271D01*
X81755Y272450D01*
Y274738D01*
X81978Y274961D01*
X86140D01*
X87533Y276354D01*
G37*
G36*
G01X170194Y577871D02*
X183024D01*
G02X183166Y577812I0J-200D01*
G01X183652Y577326D01*
G02X183711Y577184I-141J-142D01*
G01Y563277D01*
G02X183652Y563135I-200J0D01*
G01X183519Y563002D01*
G02X183377Y562943I-142J141D01*
G01X169190D01*
G02X169048Y563002I0J200D01*
G01X166234Y565816D01*
G03X166092Y565875I-142J-141D01*
G01X160377D01*
G02X160250Y565920I-1J200D01*
G03X157714I-1268J-1548D01*
G02X157587Y565875I-126J155D01*
G01X140925D01*
G03X140783Y565816I0J-200D01*
G01X139517Y564550D01*
G03X139458Y564408I141J-142D01*
G01Y558946D01*
G02X139399Y558804I-200J0D01*
G01X136764Y556169D01*
G02X136622Y556110I-142J141D01*
G01X102807D01*
G03X102665Y556051I0J-200D01*
G01X98720Y552106D01*
G02X98578Y552047I-142J141D01*
G01X77670D01*
G02X77528Y552106I0J200D01*
G01X76669Y552965D01*
G02X76610Y553107I141J142D01*
G01Y567243D01*
G02X76669Y567385I200J0D01*
G01X78165Y568881D01*
G02X78307Y568940I142J-141D01*
G01X81470D01*
G03X81612Y568999I0J200D01*
G01X82029Y569416D01*
G03X82088Y569558I-141J142D01*
G01Y572492D01*
G02X82147Y572634I200J0D01*
G01X82720Y573207D01*
G02X82862Y573266I142J-141D01*
G01X90144D01*
G03X90286Y573325I0J200D01*
G01X98120Y581159D01*
X98164D01*
X98335Y581330D01*
G02X98477Y581389I142J-141D01*
G01X99399Y582311D01*
X165754D01*
X170194Y577871D01*
G37*
G36*
G01X79314Y656157D02*
Y660107D01*
X78914Y660507D01*
X77214D01*
X76914Y660207D01*
Y656207D01*
X77264Y655857D01*
X79014D01*
X79314Y656157D01*
G37*
G36*
G01X72914Y663307D02*
Y659207D01*
X73014Y659107D01*
X74814D01*
X74914Y659207D01*
Y663307D01*
X74714Y663507D01*
X73114D01*
X72914Y663307D01*
G37*
G36*
G01X78059Y672291D02*
X78714D01*
X78823Y672182D01*
Y669150D01*
Y669037D01*
X80065Y667795D01*
Y667581D01*
Y667079D01*
X79636Y666650D01*
X79396Y666410D01*
X78540D01*
X77941Y667009D01*
Y667499D01*
Y672173D01*
X78059Y672291D01*
G37*
G36*
G01X75972Y669158D02*
Y669301D01*
Y672139D01*
X76214Y672381D01*
X76676D01*
X76918Y672139D01*
Y666852D01*
Y666523D01*
X77935Y665506D01*
X77939D01*
X78084Y665361D01*
X80303D01*
X81660Y666718D01*
X85026D01*
X85524Y666220D01*
Y655653D01*
X85170Y655299D01*
X81374D01*
X81123Y655550D01*
Y659666D01*
Y659917D01*
X79408Y661632D01*
X77053D01*
X76505Y662180D01*
X75972Y662713D01*
Y664235D01*
Y668224D01*
Y669158D01*
G37*
G36*
G01X76935Y676310D02*
X77100Y676145D01*
X77143Y676102D01*
X83711D01*
X88116D01*
X93138D01*
X93524Y675717D01*
Y661312D01*
X93014Y660802D01*
X87307D01*
X86913Y661196D01*
Y665636D01*
Y666480D01*
X84902Y668491D01*
Y672253D01*
X83725Y673430D01*
X80023D01*
X74621D01*
X72226Y675825D01*
Y678816D01*
X70716Y680326D01*
Y684607D01*
X71216Y685107D01*
X76114D01*
X76741Y684480D01*
Y681466D01*
Y676504D01*
X76842Y676403D01*
X76935Y676310D01*
G37*
G36*
G01X80100Y672401D02*
X83112D01*
X83733Y671780D01*
Y669750D01*
X83248Y669265D01*
X80239D01*
X79923Y669581D01*
Y672224D01*
X80100Y672401D01*
G37*
G36*
G01X79874Y677584D02*
Y680308D01*
X81821Y682255D01*
X82477Y682911D01*
X82773Y683207D01*
X85118D01*
X85414Y682911D01*
Y677289D01*
X85314Y677189D01*
X84278D01*
X80269D01*
X80040D01*
X80025Y677204D01*
X79874Y677355D01*
Y677584D01*
G37*
G36*
G01X77914Y677207D02*
X78714D01*
X78814Y677307D01*
Y681007D01*
X78914Y681107D01*
X79614Y681807D01*
Y685807D01*
Y687107D01*
Y688405D01*
X79221Y688798D01*
X73759D01*
X73620Y688659D01*
Y686617D01*
X73713Y686524D01*
X77520D01*
X77814Y686230D01*
Y685707D01*
Y677307D01*
X77914Y677207D01*
G37*
G36*
G01X81014Y685107D02*
X85214D01*
X85314Y685207D01*
Y687007D01*
X85214Y687107D01*
X81014D01*
X80814Y686907D01*
Y685307D01*
X81014Y685107D01*
G37*
G36*
G01X75749Y837818D02*
X71849D01*
X71549Y838118D01*
Y839518D01*
X71949Y839918D01*
X75849D01*
X75949Y839818D01*
X76049Y839718D01*
Y838018D01*
X75849Y837818D01*
X75749D01*
G37*
G36*
G01X71149Y844118D02*
X75049D01*
X75299Y843868D01*
Y841818D01*
X75099Y841618D01*
X71249D01*
X71049Y841818D01*
Y844018D01*
X71149Y844118D01*
G37*
G36*
G01X87045Y658047D02*
Y654864D01*
X87605Y654304D01*
X96385D01*
X97004Y654923D01*
Y658047D01*
Y658981D01*
X96494Y659491D01*
X87368D01*
X87045Y659168D01*
Y658047D01*
G37*
G36*
G01X86714Y685407D02*
Y681207D01*
X86814Y681107D01*
X88614D01*
X88714Y681207D01*
Y685407D01*
X88514Y685607D01*
X86914D01*
X86714Y685407D01*
G37*
G36*
G01X86764Y677307D02*
Y679107D01*
X86889Y679232D01*
X89239D01*
X90314Y680307D01*
X93014D01*
X93414D01*
X93514Y680207D01*
Y677257D01*
X93414Y677157D01*
X93064D01*
X86914D01*
X86764Y677307D01*
G37*
G36*
G01X93711Y876914D02*
X100625D01*
X102111Y878400D01*
X103888D01*
X104922Y877366D01*
Y873263D01*
X104696Y873037D01*
X93776D01*
X93388Y873425D01*
Y876591D01*
X93711Y876914D01*
G37*
G36*
G01X101103Y1017056D02*
X106232D01*
G02X106374Y1016997I0J-200D01*
G01X106521Y1016850D01*
G02X106580Y1016708I-141J-142D01*
G01Y1002279D01*
G02X106521Y1002137I-200J0D01*
G01X105937Y1001553D01*
G02X105795Y1001494I-142J141D01*
G01X102224D01*
X100549D01*
X99904Y1002139D01*
Y1016642D01*
X100318Y1017056D01*
X101103D01*
G37*
G36*
G01X97253Y1037418D02*
X102430D01*
X103060Y1036788D01*
X103523Y1036325D01*
X103816Y1036032D01*
X107733D01*
X108210Y1035555D01*
Y1034906D01*
X107887Y1034583D01*
X100602D01*
X99834Y1033815D01*
G03X99776Y1033674I142J-141D01*
G01Y1033636D01*
G02X99717Y1033495I-200J1D01*
G01X98487Y1032265D01*
G03X98428Y1032123I141J-142D01*
G01Y1026422D01*
G02X98369Y1026280I-200J0D01*
G01X98224Y1026135D01*
G02X98082Y1026076I-142J141D01*
G01X93242D01*
G02X93100Y1026135I0J200D01*
G01X93072Y1026163D01*
G02X93013Y1026305I141J142D01*
G01Y1033178D01*
G02X93072Y1033320I200J0D01*
G01X97111Y1037359D01*
G02X97253Y1037418I142J-141D01*
G37*
G36*
G01X100278Y1029045D02*
X100609D01*
G02X100750Y1028986I-1J-200D01*
G01X101003Y1028734D01*
G03X101144Y1028676I141J142D01*
G01X107770D01*
G02X107911Y1028617I-1J-200D01*
G01X108737Y1027791D01*
G02X108796Y1027649I-141J-142D01*
G01Y1026320D01*
G02X108737Y1026179I-200J1D01*
G01X107844Y1025286D01*
G03X107626Y1024987I850J-849D01*
G01X107612Y1024960D01*
X106748Y1024096D01*
G03X106689Y1023954I141J-142D01*
G01Y1019269D01*
G02X106630Y1019127I-200J0D01*
G01X106607Y1019104D01*
G02X106465Y1019045I-142J141D01*
G01X100019D01*
G02X99877Y1019104I0J200D01*
G01X99314Y1019667D01*
G02X99255Y1019809I141J142D01*
G01Y1025511D01*
G02X99314Y1025653I200J0D01*
G01X99827Y1026166D01*
G03X99886Y1026308I-141J142D01*
G01Y1028653D01*
G02X99945Y1028795I200J0D01*
G01X100136Y1028986D01*
G02X100278Y1029045I142J-141D01*
G37*
G36*
G01X134431Y1066535D02*
G02I-17700J0D01*
G37*
G36*
G01Y1263386D02*
G02I-17700J0D01*
G37*
G36*
G01X110745Y115094D02*
X111801D01*
X111828Y115067D01*
Y111227D01*
G02X111769Y111085I-200J0D01*
G01X110139Y109456D01*
G03X110080Y109314I141J-142D01*
G01Y106183D01*
G03X110139Y106041I200J0D01*
G01X110262Y105918D01*
G03X110404Y105859I142J141D01*
G01X121110D01*
G03X121252Y105918I0J200D01*
G01X121328Y105994D01*
G03X121387Y106136I-141J142D01*
G01Y109681D01*
G03X121328Y109823I-200J0D01*
G01X121094Y110057D01*
G02X121035Y110199I141J142D01*
G01Y114552D01*
X121065Y114625D01*
X121076Y114636D01*
X126660D01*
X128002D01*
X128066Y114572D01*
X128182Y114456D01*
G02X128241Y114314I-141J-142D01*
G01Y105226D01*
G02X128182Y105084I-200J0D01*
G01X127511Y104413D01*
X127428Y104383D01*
X127383Y104388D01*
G03X127201Y104396I-174J-1893D01*
G01X124619D01*
X123333D01*
X122587Y103650D01*
Y101528D01*
X122255Y101196D01*
X110724D01*
X110697Y101203D01*
G03X103020Y102354I-8473J-30337D01*
G02X102825Y102554I5J200D01*
G01Y114049D01*
G02X102884Y114191I200J0D01*
G01X103006Y114313D01*
G02X103148Y114372I142J-141D01*
G01X109857D01*
G03X109999Y114431I0J200D01*
G01X110603Y115035D01*
G02X110745Y115094I142J-141D01*
G37*
G36*
G01X103007Y120851D02*
X108424D01*
G02X108566Y120792I0J-200D01*
G01X110187Y119171D01*
G03X110329Y119112I142J141D01*
G01X111844D01*
G02X111986Y119053I0J-200D01*
G01X112459Y118580D01*
G02X112518Y118438I-141J-142D01*
G01Y116276D01*
G02X112395Y116091I-200J0D01*
G01X112338Y116068D01*
X112220Y116091D01*
X112216Y116096D01*
X110744D01*
G03X109930Y115777I1J-1202D01*
G02X109794Y115724I-136J147D01*
G01X102948D01*
G02X102806Y115783I0J200D01*
G01X102791Y115798D01*
X102761Y115871D01*
Y120605D01*
G02X102820Y120747I200J0D01*
G01X102865Y120792D01*
G02X103007Y120851I142J-141D01*
G37*
G36*
G01X114110Y119235D02*
X117556D01*
X120392Y122071D01*
X126439D01*
X126809Y121701D01*
Y116118D01*
X126328Y115637D01*
X116654D01*
X114298D01*
X113950Y115985D01*
Y119075D01*
X114110Y119235D01*
G37*
G36*
G01X112682Y210785D02*
X122122D01*
X123923Y208984D01*
X125019Y207888D01*
Y187037D01*
X124072Y186090D01*
X113300D01*
X111856Y187534D01*
Y209959D01*
X112682Y210785D01*
G37*
G36*
G01X125311Y223195D02*
X135336D01*
X135366Y223225D01*
X137889D01*
X140526Y225862D01*
X149468D01*
X149810Y225520D01*
Y213126D01*
X149098Y212414D01*
X141681D01*
X138827Y215268D01*
X135387D01*
X124410D01*
X122846D01*
X122400Y214822D01*
Y213258D01*
X121127Y211985D01*
X120715D01*
X119938D01*
X112311D01*
X111651Y212645D01*
Y226569D01*
X112327Y227245D01*
X123261D01*
X125021Y225485D01*
Y223485D01*
X125311Y223195D01*
G37*
G36*
G01X107817Y1017168D02*
X112376D01*
G02X112518Y1017109I0J-200D01*
G01X112544Y1017083D01*
X112574Y1017010D01*
Y1001850D01*
G02X112515Y1001708I-200J0D01*
G01X112312Y1001505D01*
G02X112170Y1001446I-142J141D01*
G01X108494D01*
Y1001447D01*
X108095D01*
G02X107953Y1001506I0J200D01*
G01X107640Y1001819D01*
G02X107582Y1001960I142J141D01*
G01Y1016933D01*
G02X107640Y1017074I200J0D01*
G01X107675Y1017109D01*
G02X107817Y1017168I142J-141D01*
G37*
G36*
G01X114277Y1013048D02*
X129250D01*
G02X129391Y1012989I-1J-200D01*
G01X129426Y1012954D01*
G02X129485Y1012812I-141J-142D01*
G01Y1008253D01*
G02X129426Y1008111I-200J0D01*
G01X129400Y1008085D01*
X129327Y1008055D01*
X114167D01*
G02X114025Y1008114I0J200D01*
G01X113822Y1008317D01*
G02X113763Y1008459I141J142D01*
G01Y1012135D01*
X113764D01*
Y1012534D01*
G02X113823Y1012676I200J0D01*
G01X114136Y1012989D01*
G02X114277Y1013048I142J-141D01*
G37*
G36*
G01Y1025648D02*
X129250D01*
G02X129391Y1025589I-1J-200D01*
G01X129426Y1025554D01*
G02X129485Y1025412I-141J-142D01*
G01Y1020770D01*
X129460Y1020746D01*
X120925D01*
X120901Y1020720D01*
X114710D01*
G03X114569Y1020662I0J-200D01*
G01X114562Y1020655D01*
X114167D01*
G02X114025Y1020714I0J200D01*
G01X113822Y1020917D01*
G02X113763Y1021059I141J142D01*
G01Y1024735D01*
X113764D01*
Y1025134D01*
G02X113823Y1025276I200J0D01*
G01X114136Y1025589D01*
G02X114277Y1025648I142J-141D01*
G37*
G36*
G01X121352Y1019744D02*
X129155D01*
G02X129297Y1019685I0J-200D01*
G01X129314Y1019668D01*
G02X129373Y1019526I-141J-142D01*
G01Y1014397D01*
G02X129314Y1014255I-200J0D01*
G01X129167Y1014108D01*
G02X129025Y1014049I-142J141D01*
G01X114596D01*
G02X114454Y1014108I0J200D01*
G01X113870Y1014692D01*
G02X113811Y1014834I141J142D01*
G01Y1018405D01*
G02X113870Y1018547I200J0D01*
G01X114983Y1019660D01*
G02X115125Y1019719I142J-141D01*
G01X121328D01*
X121352Y1019744D01*
G37*
G36*
G01X110574Y1028234D02*
X111675D01*
G02X111817Y1028175I0J-200D01*
G01X112079Y1027912D01*
G02X112138Y1027771I-141J-142D01*
G01Y1019455D01*
G02X112079Y1019313I-200J0D01*
G01X111532Y1018766D01*
G02X111390Y1018707I-142J141D01*
G01X108897D01*
G02X108755Y1018766I0J200D01*
G01X108552Y1018969D01*
G02X108493Y1019111I141J142D01*
G01Y1024435D01*
G02X108552Y1024577I200J0D01*
G01X109832Y1025857D01*
G03X109891Y1025999I-141J142D01*
G01Y1027551D01*
G02X109950Y1027692I200J-1D01*
G01X110432Y1028175D01*
G02X110574Y1028234I142J-141D01*
G37*
G36*
G01X121352Y1032344D02*
X129155D01*
G02X129297Y1032285I0J-200D01*
G01X129314Y1032268D01*
G02X129373Y1032126I-141J-142D01*
G01Y1026997D01*
G02X129314Y1026855I-200J0D01*
G01X129167Y1026708D01*
G02X129025Y1026649I-142J141D01*
G01X114596D01*
G02X114454Y1026708I0J200D01*
G01X113870Y1027292D01*
G02X113811Y1027434I141J142D01*
G01Y1028754D01*
X112888Y1029677D01*
X101476D01*
X100989Y1030164D01*
Y1032644D01*
X102026Y1033681D01*
X115672D01*
X117034Y1032319D01*
X121328D01*
X121352Y1032344D01*
G37*
G36*
G01X102631Y1105784D02*
X117604D01*
G02X117745Y1105726I0J-200D01*
G01X117780Y1105691D01*
G02X117839Y1105549I-141J-142D01*
G01Y1100990D01*
G02X117780Y1100848I-200J0D01*
G01X117754Y1100822D01*
X117681Y1100792D01*
X102521D01*
G02X102379Y1100851I0J200D01*
G01X102176Y1101054D01*
G02X102117Y1101196I141J142D01*
G01Y1104872D01*
X102118D01*
Y1105271D01*
G02X102177Y1105413I200J0D01*
G01X102490Y1105726D01*
G02X102631Y1105784I141J-142D01*
G37*
G36*
G01X109706Y1112481D02*
X117509D01*
G02X117651Y1112422I0J-200D01*
G01X117668Y1112405D01*
G02X117727Y1112263I-141J-142D01*
G01Y1107134D01*
G02X117668Y1106992I-200J0D01*
G01X117521Y1106845D01*
G02X117379Y1106786I-142J141D01*
G01X102950D01*
G02X102808Y1106845I0J200D01*
G01X102224Y1107429D01*
G02X102165Y1107571I141J142D01*
G01Y1111142D01*
G02X102224Y1111284I200J0D01*
G01X103337Y1112397D01*
G02X103479Y1112456I142J-141D01*
G01X109682D01*
X109706Y1112481D01*
G37*
G36*
G01X102631Y1118384D02*
X117604D01*
G02X117746Y1118325I0J-200D01*
G01X117780Y1118291D01*
G02X117782Y1118289I-140J-142D01*
G02X117839Y1118149I-143J-140D01*
G01Y1113590D01*
G02X117808Y1113482I-200J-1D01*
G01X109279D01*
X109255Y1113458D01*
X103064D01*
G03X102923Y1113399I1J-200D01*
G01X102916Y1113392D01*
X102521D01*
G02X102379Y1113451I0J200D01*
G01X102176Y1113654D01*
X102147Y1113682D01*
X102117Y1113756D01*
Y1117472D01*
X102118D01*
Y1117871D01*
G02X102175Y1118011I200J0D01*
G01X102176Y1118012D01*
X102489Y1118325D01*
G02X102631Y1118384I142J-141D01*
G37*
G36*
G01X109706Y1125081D02*
X117509D01*
G02X117651Y1125022I0J-200D01*
G01X117668Y1125005D01*
G02X117727Y1124863I-141J-142D01*
G01Y1119734D01*
G02X117668Y1119592I-200J0D01*
G01X117521Y1119445D01*
G02X117379Y1119386I-142J141D01*
G01X111994D01*
Y1120626D01*
X111542Y1121078D01*
X109274D01*
X108796Y1120600D01*
Y1119527D01*
X108700Y1119431D01*
X108661Y1119392D01*
Y1119386D01*
X102950D01*
G02X102808Y1119445I0J200D01*
G01X102224Y1120029D01*
G02X102165Y1120171I141J142D01*
G01Y1123742D01*
G02X102224Y1123884I200J0D01*
G01X103337Y1124997D01*
G02X103479Y1125056I142J-141D01*
G01X109682D01*
X109706Y1125081D01*
G37*
G36*
G01X102631Y1130984D02*
X117604D01*
G02X117745Y1130926I0J-200D01*
G01X117780Y1130891D01*
G02X117839Y1130749I-141J-142D01*
G01Y1126107D01*
X117814Y1126082D01*
X109279D01*
X109255Y1126058D01*
X103064D01*
G03X102923Y1125999I1J-200D01*
G01X102916Y1125992D01*
X102521D01*
G02X102379Y1126051I0J200D01*
G01X102176Y1126254D01*
G02X102117Y1126396I141J142D01*
G01Y1130072D01*
X102118D01*
Y1130471D01*
G02X102177Y1130613I200J0D01*
G01X102490Y1130926D01*
G02X102631Y1130984I141J-142D01*
G37*
G36*
G01Y1143584D02*
X117604D01*
G02X117745Y1143526I0J-200D01*
G01X117780Y1143491D01*
G02X117839Y1143349I-141J-142D01*
G01Y1138707D01*
X117814Y1138682D01*
X109279D01*
X109255Y1138658D01*
X103064D01*
G03X102923Y1138599I1J-200D01*
G01X102916Y1138592D01*
X102521D01*
G02X102379Y1138651I0J200D01*
G01X102176Y1138854D01*
G02X102117Y1138996I141J142D01*
G01Y1142672D01*
X102118D01*
Y1143071D01*
G02X102177Y1143213I200J0D01*
G01X102490Y1143526D01*
G02X102631Y1143584I141J-142D01*
G37*
G36*
G01X109706Y1137681D02*
X117509D01*
G02X117651Y1137622I0J-200D01*
G01X117668Y1137605D01*
G02X117727Y1137463I-141J-142D01*
G01Y1132334D01*
G02X117668Y1132192I-200J0D01*
G01X117521Y1132045D01*
G02X117379Y1131986I-142J141D01*
G01X102950D01*
G02X102808Y1132045I0J200D01*
G01X102224Y1132629D01*
G02X102165Y1132771I141J142D01*
G01Y1136342D01*
G02X102224Y1136484I200J0D01*
G01X103337Y1137597D01*
G02X103479Y1137656I142J-141D01*
G01X109682D01*
X109706Y1137681D01*
G37*
G36*
G01X102631Y1156184D02*
X117604D01*
G02X117745Y1156126I0J-200D01*
G01X117780Y1156091D01*
G02X117839Y1155949I-141J-142D01*
G01Y1151307D01*
X117814Y1151282D01*
X109279D01*
X109255Y1151258D01*
X103064D01*
G03X102923Y1151199I1J-200D01*
G01X102916Y1151192D01*
X102521D01*
G02X102379Y1151251I0J200D01*
G01X102176Y1151454D01*
G02X102117Y1151596I141J142D01*
G01Y1155272D01*
X102118D01*
Y1155671D01*
G02X102177Y1155813I200J0D01*
G01X102490Y1156126D01*
G02X102631Y1156184I141J-142D01*
G37*
G36*
G01X109706Y1150281D02*
X117509D01*
G02X117651Y1150222I0J-200D01*
G01X117668Y1150205D01*
G02X117727Y1150063I-141J-142D01*
G01Y1144934D01*
G02X117668Y1144792I-200J0D01*
G01X117521Y1144645D01*
G02X117379Y1144586I-142J141D01*
G01X102950D01*
G02X102808Y1144645I0J200D01*
G01X102224Y1145229D01*
G02X102165Y1145371I141J142D01*
G01Y1148942D01*
G02X102224Y1149084I200J0D01*
G01X103337Y1150197D01*
G02X103479Y1150256I142J-141D01*
G01X109682D01*
X109706Y1150281D01*
G37*
G36*
G01X102631Y1168784D02*
X117604D01*
G02X117745Y1168726I0J-200D01*
G01X117780Y1168691D01*
G02X117839Y1168549I-141J-142D01*
G01Y1163907D01*
X117814Y1163882D01*
X109279D01*
X109255Y1163858D01*
X103064D01*
G03X102923Y1163799I1J-200D01*
G01X102916Y1163792D01*
X102521D01*
G02X102379Y1163851I0J200D01*
G01X102176Y1164054D01*
G02X102117Y1164196I141J142D01*
G01Y1167872D01*
X102118D01*
Y1168271D01*
G02X102177Y1168413I200J0D01*
G01X102490Y1168726D01*
G02X102631Y1168784I141J-142D01*
G37*
G36*
G01X109706Y1175481D02*
X117509D01*
G02X117651Y1175422I0J-200D01*
G01X117668Y1175405D01*
G02X117727Y1175263I-141J-142D01*
G01Y1170134D01*
G02X117668Y1169992I-200J0D01*
G01X117521Y1169845D01*
G02X117379Y1169786I-142J141D01*
G01X102950D01*
G02X102808Y1169845I0J200D01*
G01X102224Y1170429D01*
G02X102165Y1170571I141J142D01*
G01Y1174142D01*
G02X102224Y1174284I200J0D01*
G01X103337Y1175397D01*
G02X103479Y1175456I142J-141D01*
G01X109682D01*
X109706Y1175481D01*
G37*
G36*
G01Y1162881D02*
X117509D01*
G02X117651Y1162822I0J-200D01*
G01X117668Y1162805D01*
G02X117727Y1162663I-141J-142D01*
G01Y1157534D01*
G02X117668Y1157392I-200J0D01*
G01X117521Y1157245D01*
G02X117379Y1157186I-142J141D01*
G01X112133D01*
X111949Y1157370D01*
Y1158405D01*
X111449Y1158905D01*
X109432D01*
X108953Y1158426D01*
Y1157370D01*
X108769Y1157186D01*
X102950D01*
G02X102808Y1157245I0J200D01*
G01X102224Y1157829D01*
G02X102165Y1157971I141J142D01*
G01Y1161542D01*
G02X102224Y1161684I200J0D01*
G01X103337Y1162797D01*
G02X103479Y1162856I142J-141D01*
G01X109682D01*
X109706Y1162881D01*
G37*
G36*
G01X104750Y1181384D02*
X117604D01*
G02X117745Y1181326I0J-200D01*
G01X117780Y1181291D01*
G02X117839Y1181149I-141J-142D01*
G01Y1176507D01*
X117814Y1176482D01*
X109279D01*
X109255Y1176458D01*
X103064D01*
G03X102923Y1176399I1J-200D01*
G01X102916Y1176392D01*
X102521D01*
G02X102379Y1176451I0J200D01*
G01X102176Y1176654D01*
G02X102117Y1176796I141J142D01*
G01Y1180472D01*
X102118D01*
Y1180871D01*
G02X102177Y1181013I200J0D01*
G01X102274Y1181110D01*
X104476D01*
X104750Y1181384D01*
G37*
G36*
G01X109706Y1188081D02*
X117509D01*
G02X117651Y1188022I0J-200D01*
G01X117668Y1188005D01*
G02X117727Y1187863I-141J-142D01*
G01Y1182734D01*
G02X117668Y1182592I-200J0D01*
G01X117521Y1182445D01*
G02X117379Y1182386I-142J141D01*
G01X102950D01*
G02X102808Y1182445I0J200D01*
G01X102224Y1183029D01*
G02X102165Y1183171I141J142D01*
G01Y1186742D01*
G02X102224Y1186884I200J0D01*
G01X103337Y1187997D01*
G02X103479Y1188056I142J-141D01*
G01X109682D01*
X109706Y1188081D01*
G37*
G36*
G01X126041Y186998D02*
Y210417D01*
X124033Y212425D01*
Y214067D01*
X124425Y214459D01*
X132847D01*
X133055Y214251D01*
Y212947D01*
X133003Y212895D01*
Y212503D01*
Y211681D01*
X133302Y211382D01*
X134124D01*
X138350D01*
X139678Y210054D01*
Y205828D01*
Y187369D01*
X138523Y186214D01*
X126825D01*
X126041Y186998D01*
G37*
G36*
G01X131428Y1012136D02*
X134219D01*
G02X134361Y1012078I1J-200D01*
G01X134613Y1011826D01*
G02X134672Y1011684I-141J-142D01*
G01Y1011122D01*
G03X134731Y1010980I200J0D01*
G01X134914Y1010797D01*
G03X135056Y1010738I142J141D01*
G01X135240D01*
G02X135381Y1010679I-1J-200D01*
G01X135569Y1010492D01*
G03X135710Y1010434I141J142D01*
G01X140359D01*
G02X140559Y1010234I0J-200D01*
G01Y1008803D01*
G02X140500Y1008661I-200J0D01*
G01X140389Y1008550D01*
G02X140247Y1008491I-142J141D01*
G01X131772D01*
G02X131630Y1008550I0J200D01*
G01X131083Y1009097D01*
G02X131024Y1009239I141J142D01*
G01Y1011732D01*
G02X131083Y1011874I200J0D01*
G01X131286Y1012077D01*
G02X131428Y1012136I142J-141D01*
G37*
G36*
G01X132183Y1019852D02*
X142299D01*
G02X142441Y1019793I0J-200D01*
G01X142929Y1019305D01*
G02X142988Y1019163I-141J-142D01*
G01Y1012172D01*
G02X142929Y1012030I-200J0D01*
G01X142393Y1011494D01*
G02X142251Y1011435I-142J141D01*
G01X136125D01*
G02X135983Y1011494I0J200D01*
G01X135764Y1011713D01*
G02X135705Y1011855I141J142D01*
G01Y1013406D01*
G03X135646Y1013548I-200J0D01*
G01X135546Y1013648D01*
G03X135404Y1013707I-142J-141D01*
G01X132220D01*
G02X132078Y1013766I0J200D01*
G01X131727Y1014117D01*
G02X131668Y1014259I141J142D01*
G01Y1019338D01*
G02X131727Y1019480I200J0D01*
G01X132041Y1019794D01*
G02X132183Y1019852I141J-142D01*
G37*
G36*
G01X131428Y1024736D02*
X134219D01*
G02X134361Y1024678I1J-200D01*
G01X134613Y1024426D01*
G02X134672Y1024284I-141J-142D01*
G01Y1023722D01*
G03X134731Y1023580I200J0D01*
G01X134914Y1023397D01*
G03X135056Y1023338I142J141D01*
G01X135240D01*
G02X135381Y1023279I-1J-200D01*
G01X135569Y1023092D01*
G03X135710Y1023034I141J142D01*
G01X140359D01*
G02X140559Y1022834I0J-200D01*
G01Y1021403D01*
G02X140500Y1021261I-200J0D01*
G01X140389Y1021150D01*
G02X140247Y1021091I-142J141D01*
G01X131772D01*
G02X131630Y1021150I0J200D01*
G01X131083Y1021697D01*
G02X131024Y1021839I141J142D01*
G01Y1024332D01*
G02X131083Y1024474I200J0D01*
G01X131286Y1024677D01*
G02X131428Y1024736I142J-141D01*
G37*
G36*
G01X132183Y1032452D02*
X142299D01*
G02X142441Y1032393I0J-200D01*
G01X142929Y1031905D01*
G02X142988Y1031763I-141J-142D01*
G01Y1024772D01*
G02X142929Y1024630I-200J0D01*
G01X142393Y1024094D01*
G02X142251Y1024035I-142J141D01*
G01X136125D01*
G02X135983Y1024094I0J200D01*
G01X135764Y1024313D01*
G02X135705Y1024455I141J142D01*
G01Y1026006D01*
G03X135646Y1026148I-200J0D01*
G01X135546Y1026248D01*
G03X135404Y1026307I-142J-141D01*
G01X132220D01*
G02X132078Y1026366I0J200D01*
G01X131727Y1026717D01*
G02X131668Y1026859I141J142D01*
G01Y1031938D01*
G02X131727Y1032080I200J0D01*
G01X132041Y1032394D01*
G02X132183Y1032452I141J-142D01*
G37*
G36*
G01X132711Y1188245D02*
X134999D01*
X135538Y1187706D01*
Y1166474D01*
X135889Y1166123D01*
X136715Y1165297D01*
Y1104789D01*
X136331Y1104405D01*
G02X136309Y1104386I-141J141D01*
G02X136189Y1104346I-120J160D01*
G01X132964D01*
G02X132844Y1104386I0J200D01*
G02X132822Y1104405I119J160D01*
G01X132402Y1104825D01*
G02X132344Y1104966I142J141D01*
G01Y1112278D01*
G02X132375Y1112385I200J0D01*
G01Y1117452D01*
X132366Y1117461D01*
G02X132347Y1117483I141J141D01*
G02X132307Y1117603I160J120D01*
G01Y1124841D01*
G02X132347Y1124961I200J0D01*
G02X132366Y1124983I160J-119D01*
G01X132375Y1124992D01*
Y1130052D01*
X132366Y1130061D01*
G02X132347Y1130083I141J141D01*
G02X132307Y1130203I160J120D01*
G01Y1137441D01*
G02X132347Y1137561I200J0D01*
G02X132366Y1137583I160J-119D01*
G01X132375Y1137592D01*
Y1142652D01*
X132366Y1142661D01*
G02X132347Y1142683I141J141D01*
G02X132307Y1142803I160J120D01*
G01Y1150041D01*
G02X132347Y1150161I200J0D01*
G02X132366Y1150183I160J-119D01*
G01X132375Y1150192D01*
Y1155252D01*
X132366Y1155261D01*
G02X132347Y1155283I141J141D01*
G02X132307Y1155403I160J120D01*
G01Y1162641D01*
G02X132347Y1162761I200J0D01*
G02X132366Y1162783I160J-119D01*
G01X132375Y1162792D01*
Y1167859D01*
G02X132344Y1167966I169J107D01*
G01Y1175278D01*
G02X132375Y1175385I200J0D01*
G01Y1178989D01*
X132665Y1179279D01*
Y1180161D01*
X132642Y1180184D01*
Y1183102D01*
X132307Y1183437D01*
Y1187841D01*
G02X132347Y1187961I200J0D01*
G02X132366Y1187983I160J-119D01*
G01X132569Y1188186D01*
G02X132591Y1188205I141J-141D01*
G02X132711Y1188245I120J-160D01*
G37*
G36*
G01X119782Y1104873D02*
X122573D01*
G02X122715Y1104815I1J-200D01*
G01X122967Y1104563D01*
G02X123026Y1104421I-141J-142D01*
G01Y1103859D01*
G03X123085Y1103717I200J0D01*
G01X123268Y1103534D01*
G03X123410Y1103475I142J141D01*
G01X123594D01*
G02X123735Y1103416I-1J-200D01*
G01X123923Y1103229D01*
G03X124064Y1103170I142J141D01*
G01X128713D01*
G02X128913Y1102970I0J-200D01*
G01Y1101540D01*
G02X128854Y1101398I-200J0D01*
G01X128743Y1101287D01*
G02X128601Y1101228I-142J141D01*
G01X120126D01*
G02X119984Y1101287I0J200D01*
G01X119437Y1101834D01*
G02X119378Y1101976I141J142D01*
G01Y1104469D01*
G02X119437Y1104611I200J0D01*
G01X119640Y1104814D01*
G02X119782Y1104873I142J-141D01*
G37*
G36*
G01X120537Y1112589D02*
X130653D01*
G02X130795Y1112530I0J-200D01*
G01X131283Y1112042D01*
G02X131342Y1111900I-141J-142D01*
G01Y1104909D01*
G02X131283Y1104767I-200J0D01*
G01X130747Y1104231D01*
G02X130605Y1104172I-142J141D01*
G01X124479D01*
G02X124337Y1104231I0J200D01*
G01X124118Y1104450D01*
G02X124059Y1104592I141J142D01*
G01Y1106143D01*
G03X124000Y1106285I-200J0D01*
G01X123900Y1106385D01*
G03X123758Y1106444I-142J-141D01*
G01X120574D01*
G02X120432Y1106503I0J200D01*
G01X120081Y1106854D01*
G02X120022Y1106996I141J142D01*
G01Y1112075D01*
G02X120081Y1112217I200J0D01*
G01X120395Y1112531D01*
G02X120537Y1112589I141J-142D01*
G37*
G36*
G01X119782Y1117473D02*
X122573D01*
G02X122715Y1117415I1J-200D01*
G01X122967Y1117163D01*
G02X123026Y1117021I-141J-142D01*
G01Y1116459D01*
G03X123085Y1116317I200J0D01*
G01X123268Y1116134D01*
G03X123410Y1116075I142J141D01*
G01X128616D01*
G02X128758Y1116016I0J-200D01*
G01X128854Y1115920D01*
G02X128913Y1115778I-141J-142D01*
G01Y1114140D01*
G02X128854Y1113998I-200J0D01*
G01X128743Y1113887D01*
G02X128601Y1113828I-142J141D01*
G01X120126D01*
G02X119984Y1113887I0J200D01*
G01X119437Y1114434D01*
G02X119378Y1114576I141J142D01*
G01Y1117069D01*
G02X119437Y1117211I200J0D01*
G01X119640Y1117414D01*
G02X119782Y1117473I142J-141D01*
G37*
G36*
G01X120537Y1125189D02*
X130653D01*
G02X130795Y1125130I0J-200D01*
G01X131247Y1124678D01*
G02X131306Y1124537I-141J-142D01*
G01Y1117472D01*
G02X131247Y1117331I-200J1D01*
G01X130747Y1116831D01*
G02X130605Y1116772I-142J141D01*
G01X129677D01*
G02X129535Y1116831I0J200D01*
G01X129112Y1117254D01*
G03X128970Y1117313I-142J-141D01*
G01X126055D01*
G03X125913Y1117254I0J-200D01*
G01X125794Y1117135D01*
G02X125653Y1117076I-142J141D01*
G01X124134D01*
X124061Y1117107D01*
X124059Y1117109D01*
Y1118743D01*
G03X124000Y1118885I-200J0D01*
G01X123900Y1118985D01*
G03X123758Y1119044I-142J-141D01*
G01X120574D01*
G02X120432Y1119103I0J200D01*
G01X120081Y1119454D01*
G02X120022Y1119596I141J142D01*
G01Y1124675D01*
G02X120081Y1124817I200J0D01*
G01X120395Y1125131D01*
G02X120537Y1125189I141J-142D01*
G37*
G36*
G01X119782Y1142673D02*
X122573D01*
G02X122715Y1142615I1J-200D01*
G01X122967Y1142363D01*
G02X123026Y1142221I-141J-142D01*
G01Y1141659D01*
G03X123085Y1141517I200J0D01*
G01X123268Y1141334D01*
G03X123410Y1141275I142J141D01*
G01X128616D01*
G02X128758Y1141216I0J-200D01*
G01X128854Y1141120D01*
G02X128913Y1140978I-141J-142D01*
G01Y1139340D01*
G02X128854Y1139198I-200J0D01*
G01X128743Y1139087D01*
G02X128601Y1139028I-142J141D01*
G01X120126D01*
G02X119984Y1139087I0J200D01*
G01X119437Y1139634D01*
G02X119378Y1139776I141J142D01*
G01Y1142269D01*
G02X119437Y1142411I200J0D01*
G01X119640Y1142614D01*
G02X119782Y1142673I142J-141D01*
G37*
G36*
G01Y1130073D02*
X122573D01*
G02X122715Y1130015I1J-200D01*
G01X122967Y1129763D01*
G02X123026Y1129621I-141J-142D01*
G01Y1129059D01*
G03X123085Y1128917I200J0D01*
G01X123268Y1128734D01*
G03X123410Y1128675I142J141D01*
G01X128616D01*
G02X128758Y1128616I0J-200D01*
G01X128854Y1128520D01*
G02X128913Y1128378I-141J-142D01*
G01Y1126740D01*
G02X128854Y1126598I-200J0D01*
G01X128743Y1126487D01*
G02X128601Y1126428I-142J141D01*
G01X120126D01*
G02X119984Y1126487I0J200D01*
G01X119437Y1127034D01*
G02X119378Y1127176I141J142D01*
G01Y1129669D01*
G02X119437Y1129811I200J0D01*
G01X119640Y1130014D01*
G02X119782Y1130073I142J-141D01*
G37*
G36*
G01X120537Y1137789D02*
X130653D01*
G02X130795Y1137730I0J-200D01*
G01X131247Y1137278D01*
G02X131306Y1137137I-141J-142D01*
G01Y1130072D01*
G02X131247Y1129931I-200J1D01*
G01X130747Y1129431D01*
G02X130605Y1129372I-142J141D01*
G01X129677D01*
G02X129535Y1129431I0J200D01*
G01X129112Y1129854D01*
G03X128970Y1129913I-142J-141D01*
G01X126055D01*
G03X125913Y1129854I0J-200D01*
G01X125794Y1129735D01*
G02X125653Y1129676I-142J141D01*
G01X124134D01*
X124061Y1129707D01*
X124059Y1129709D01*
Y1131343D01*
G03X124000Y1131485I-200J0D01*
G01X123900Y1131585D01*
G03X123758Y1131644I-142J-141D01*
G01X120574D01*
G02X120432Y1131703I0J200D01*
G01X120081Y1132054D01*
G02X120022Y1132196I141J142D01*
G01Y1137275D01*
G02X120081Y1137417I200J0D01*
G01X120395Y1137731D01*
G02X120537Y1137789I141J-142D01*
G37*
G36*
G01Y1150389D02*
X130653D01*
G02X130795Y1150330I0J-200D01*
G01X131247Y1149878D01*
G02X131306Y1149737I-141J-142D01*
G01Y1142672D01*
G02X131247Y1142531I-200J1D01*
G01X130747Y1142031D01*
G02X130605Y1141972I-142J141D01*
G01X129677D01*
G02X129535Y1142031I0J200D01*
G01X129112Y1142454D01*
G03X128970Y1142513I-142J-141D01*
G01X126055D01*
G03X125913Y1142454I0J-200D01*
G01X125794Y1142335D01*
G02X125653Y1142276I-142J141D01*
G01X124134D01*
X124061Y1142307D01*
X124059Y1142309D01*
Y1143943D01*
G03X124000Y1144085I-200J0D01*
G01X123900Y1144185D01*
G03X123758Y1144244I-142J-141D01*
G01X120574D01*
G02X120432Y1144303I0J200D01*
G01X120081Y1144654D01*
G02X120022Y1144796I141J142D01*
G01Y1149875D01*
G02X120081Y1150017I200J0D01*
G01X120395Y1150331D01*
G02X120537Y1150389I141J-142D01*
G37*
G36*
G01Y1162989D02*
X130653D01*
G02X130795Y1162930I0J-200D01*
G01X131247Y1162478D01*
G02X131306Y1162337I-141J-142D01*
G01Y1155272D01*
G02X131247Y1155131I-200J1D01*
G01X130747Y1154631D01*
G02X130605Y1154572I-142J141D01*
G01X129677D01*
G02X129535Y1154631I0J200D01*
G01X129112Y1155054D01*
G03X128970Y1155113I-142J-141D01*
G01X126055D01*
G03X125913Y1155054I0J-200D01*
G01X125794Y1154935D01*
G02X125653Y1154876I-142J141D01*
G01X124134D01*
X124061Y1154907D01*
X124059Y1154909D01*
Y1156543D01*
G03X124000Y1156685I-200J0D01*
G01X123900Y1156785D01*
G03X123758Y1156844I-142J-141D01*
G01X120574D01*
G02X120432Y1156903I0J200D01*
G01X120081Y1157254D01*
G02X120022Y1157396I141J142D01*
G01Y1162475D01*
G02X120081Y1162617I200J0D01*
G01X120395Y1162931D01*
G02X120537Y1162989I141J-142D01*
G37*
G36*
G01X119782Y1155273D02*
X122573D01*
G02X122715Y1155215I1J-200D01*
G01X122967Y1154963D01*
G02X123026Y1154821I-141J-142D01*
G01Y1154259D01*
G03X123085Y1154117I200J0D01*
G01X123268Y1153934D01*
G03X123410Y1153875I142J141D01*
G01X128616D01*
G02X128758Y1153816I0J-200D01*
G01X128854Y1153720D01*
G02X128913Y1153578I-141J-142D01*
G01Y1151940D01*
G02X128854Y1151798I-200J0D01*
G01X128743Y1151687D01*
G02X128601Y1151628I-142J141D01*
G01X120126D01*
G02X119984Y1151687I0J200D01*
G01X119437Y1152234D01*
G02X119378Y1152376I141J142D01*
G01Y1154869D01*
G02X119437Y1155011I200J0D01*
G01X119640Y1155214D01*
G02X119782Y1155273I142J-141D01*
G37*
G36*
G01X120537Y1175589D02*
X130653D01*
G02X130795Y1175530I0J-200D01*
G01X131283Y1175042D01*
G02X131342Y1174900I-141J-142D01*
G01Y1167909D01*
G02X131283Y1167767I-200J0D01*
G01X130747Y1167231D01*
G02X130605Y1167172I-142J141D01*
G01X129677D01*
G02X129535Y1167231I0J200D01*
G01X129112Y1167654D01*
G03X128970Y1167713I-142J-141D01*
G01X126055D01*
G03X125913Y1167654I0J-200D01*
G01X125490Y1167231D01*
G02X125348Y1167172I-142J141D01*
G01X124479D01*
G02X124337Y1167231I0J200D01*
G01X124118Y1167450D01*
G02X124059Y1167592I141J142D01*
G01Y1169143D01*
G03X124000Y1169285I-200J0D01*
G01X123900Y1169385D01*
G03X123758Y1169444I-142J-141D01*
G01X120574D01*
G02X120432Y1169503I0J200D01*
G01X120081Y1169854D01*
G02X120022Y1169996I141J142D01*
G01Y1175075D01*
G02X120081Y1175217I200J0D01*
G01X120395Y1175531D01*
G02X120537Y1175589I141J-142D01*
G37*
G36*
G01X119782Y1167873D02*
X122573D01*
G02X122715Y1167815I1J-200D01*
G01X122967Y1167563D01*
G02X123026Y1167421I-141J-142D01*
G01Y1166859D01*
G03X123085Y1166717I200J0D01*
G01X123268Y1166534D01*
G03X123410Y1166475I142J141D01*
G01X123594D01*
G02X123735Y1166416I-1J-200D01*
G01X123923Y1166229D01*
G03X124064Y1166170I142J141D01*
G01X125763D01*
G03X125904Y1166229I-1J200D01*
G01X126092Y1166416D01*
G02X126233Y1166475I142J-141D01*
G01X128616D01*
G02X128758Y1166416I0J-200D01*
G01X128854Y1166320D01*
G02X128913Y1166178I-141J-142D01*
G01Y1164540D01*
G02X128854Y1164398I-200J0D01*
G01X128743Y1164287D01*
G02X128601Y1164228I-142J141D01*
G01X120126D01*
G02X119984Y1164287I0J200D01*
G01X119437Y1164834D01*
G02X119378Y1164976I141J142D01*
G01Y1167469D01*
G02X119437Y1167611I200J0D01*
G01X119640Y1167814D01*
G02X119782Y1167873I142J-141D01*
G37*
G36*
G01Y1180473D02*
X122573D01*
G02X122715Y1180415I1J-200D01*
G01X122967Y1180163D01*
G02X123026Y1180021I-141J-142D01*
G01Y1179459D01*
G03X123085Y1179317I200J0D01*
G01X123268Y1179134D01*
G03X123410Y1179075I142J141D01*
G01X128616D01*
G02X128758Y1179016I0J-200D01*
G01X128854Y1178920D01*
G02X128913Y1178778I-141J-142D01*
G01Y1177140D01*
G02X128854Y1176998I-200J0D01*
G01X128743Y1176887D01*
G02X128601Y1176828I-142J141D01*
G01X120126D01*
G02X119984Y1176887I0J200D01*
G01X119437Y1177434D01*
G02X119378Y1177576I141J142D01*
G01Y1180069D01*
G02X119437Y1180211I200J0D01*
G01X119640Y1180414D01*
G02X119782Y1180473I142J-141D01*
G37*
G36*
G01X120537Y1188189D02*
X130653D01*
G02X130795Y1188130I0J-200D01*
G01X131247Y1187678D01*
G02X131306Y1187537I-141J-142D01*
G01Y1181891D01*
X131469Y1181728D01*
Y1179673D01*
X131087Y1179291D01*
X130075D01*
X129536Y1179830D01*
X129535Y1179831D01*
X129112Y1180254D01*
G03X128970Y1180313I-142J-141D01*
G01X126055D01*
G03X125913Y1180254I0J-200D01*
G01X125794Y1180135D01*
G02X125653Y1180076I-142J141D01*
G01X124134D01*
X124061Y1180107D01*
X124059Y1180109D01*
Y1181743D01*
G03X124000Y1181885I-200J0D01*
G01X123900Y1181985D01*
G03X123758Y1182044I-142J-141D01*
G01X120574D01*
G02X120432Y1182103I0J200D01*
G01X120081Y1182454D01*
G02X120022Y1182596I141J142D01*
G01Y1187675D01*
G02X120081Y1187817I200J0D01*
G01X120395Y1188131D01*
G02X120537Y1188189I141J-142D01*
G37*
G36*
G01X141955Y86514D02*
X150670D01*
X151023Y86161D01*
Y73377D01*
X150577Y72931D01*
X142179D01*
X141844Y73266D01*
Y86403D01*
X141955Y86514D01*
G37*
G36*
G01X144357Y1032508D02*
X148133D01*
G02X148275Y1032449I0J-200D01*
G01X148477Y1032247D01*
G02X148536Y1032105I-141J-142D01*
G01Y1024910D01*
G02X148477Y1024768I-200J0D01*
G01X147977Y1024268D01*
G02X147835Y1024209I-142J141D01*
G01X144610D01*
G02X144468Y1024268I0J200D01*
G01X144048Y1024688D01*
G02X143990Y1024829I142J141D01*
G01Y1032141D01*
G02X144048Y1032282I200J0D01*
G01X144215Y1032449D01*
G02X144357Y1032508I142J-141D01*
G37*
G36*
G01Y1019908D02*
X148133D01*
G02X148275Y1019849I0J-200D01*
G01X148477Y1019647D01*
G02X148536Y1019505I-141J-142D01*
G01Y1012310D01*
G02X148477Y1012168I-200J0D01*
G01X147977Y1011668D01*
G02X147835Y1011609I-142J141D01*
G01X144610D01*
G02X144468Y1011668I0J200D01*
G01X144048Y1012088D01*
G02X143990Y1012229I142J141D01*
G01Y1019541D01*
G02X144048Y1019682I200J0D01*
G01X144215Y1019849D01*
G02X144357Y1019908I142J-141D01*
G37*
G36*
G01X141737Y1191142D02*
G03I-400J0D01*
G37*
G36*
G01Y1198622D02*
G03I-400J0D01*
G37*
G36*
G01Y1206103D02*
G03I-400J0D01*
G37*
G36*
G01Y1213583D02*
G03I-400J0D01*
G37*
G36*
G01Y1221063D02*
G03I-400J0D01*
G37*
G36*
G01Y1228542D02*
G03I-400J0D01*
G37*
G36*
G01X141736Y1239762D02*
G03I-400J0D01*
G37*
G36*
G01Y1247242D02*
G03I-400J0D01*
G37*
G36*
G01X170133Y89379D02*
X170231D01*
G02X170372Y89438I142J-141D01*
G01X184397D01*
G02X184539Y89379I0J-200D01*
G01X184542Y89376D01*
Y74039D01*
G03X184600Y73898I200J0D01*
G01X184647Y73851D01*
G02Y73568I-141J-141D01*
G01X184460Y73381D01*
G02X184318Y73322I-142J141D01*
G01X180503D01*
X180500Y73319D01*
X160155D01*
G02X160013Y73378I0J200D01*
G01X159945Y73446D01*
G02X159886Y73588I141J142D01*
G01Y86280D01*
G02X159945Y86422I200J0D01*
G01X160013Y86490D01*
G02X160155Y86549I142J-141D01*
G01X165466D01*
G03X165608Y86608I0J200D01*
G01X166441Y87441D01*
G03X166500Y87583I-141J142D01*
G01Y88917D01*
G02X166559Y89059I200J0D01*
G01X166879Y89379D01*
G02X167021Y89438I142J-141D01*
G01X169992D01*
G02X170133Y89379I-1J-200D01*
G37*
G36*
G01X173071Y175943D02*
Y174878D01*
G03X173130Y174736I200J0D01*
G01X173775Y174091D01*
G03X173917Y174032I142J141D01*
G01X176859D01*
G02X177001Y173973I0J-200D01*
G01X177470Y173504D01*
G02X177529Y173362I-141J-142D01*
G01Y161506D01*
G02X177470Y161364I-200J0D01*
G01X176884Y160778D01*
G02X176742Y160719I-142J141D01*
G01X158526D01*
Y160720D01*
X156613D01*
G02X156471Y160779I0J200D01*
G01X155828Y161422D01*
G02X155769Y161564I141J142D01*
G01Y176120D01*
G02X155828Y176262I200J0D01*
G01X156296Y176730D01*
G02X156438Y176789I142J-141D01*
G01X172225D01*
G02X172367Y176730I0J-200D01*
G01X173012Y176085D01*
G02X173071Y175943I-141J-142D01*
G37*
G36*
G01X184800Y219609D02*
X186442D01*
X186834Y219217D01*
Y210795D01*
X186626Y210587D01*
X185322D01*
X185270Y210639D01*
X184878D01*
X184868Y210629D01*
X184031D01*
X183757Y210355D01*
Y209518D01*
Y204802D01*
X173288Y194333D01*
Y189191D01*
X176925Y185554D01*
X181690D01*
X182238Y185006D01*
Y183690D01*
X183233Y182695D01*
X185167D01*
X185554Y182308D01*
X187768D01*
X187946Y182130D01*
Y181714D01*
X187633Y181401D01*
X184423D01*
X184022Y181000D01*
X183977D01*
X182684Y179707D01*
X157125D01*
X155813Y181019D01*
Y216698D01*
X156716Y217601D01*
X182792D01*
X184800Y219609D01*
G37*
G36*
G01X183160Y234621D02*
Y221520D01*
X181359Y219719D01*
X180263Y218623D01*
X157422D01*
X155694Y220351D01*
Y252516D01*
X157005Y253827D01*
X179245D01*
X183160Y249912D01*
Y234621D01*
G37*
G36*
G01X158040Y277007D02*
X165469D01*
X177920D01*
X179777Y275150D01*
X182356D01*
X182631Y274875D01*
Y272398D01*
X182081Y271848D01*
X179537D01*
X179433Y271952D01*
X175753Y268272D01*
Y265554D01*
X172555Y262356D01*
X157971D01*
X157283Y263044D01*
Y276250D01*
X158040Y277007D01*
G37*
G36*
G01X160439Y1258465D02*
G03I-400J0D01*
G37*
G36*
G01X152959D02*
G03I-400J0D01*
G37*
G36*
G01X240020Y54588D02*
X266605D01*
Y52591D01*
X240020D01*
G03X234083Y46654I0J-5937D01*
G01Y7874D01*
G02X228209Y2000I-5874J0D01*
G01X180965D01*
G02X175091Y7874I0J5874D01*
G01Y46588D01*
X177088D01*
Y7874D01*
G03X180963Y3998I3876J0D01*
G01X228209D01*
G03X232086Y7874I0J3877D01*
G01Y46654D01*
G02X240020Y54588I7934J0D01*
G37*
G36*
G01X169984Y95055D02*
X185000D01*
X185020Y95035D01*
X189025D01*
X189738Y94322D01*
Y74773D01*
X188877Y73912D01*
X186266D01*
X186002D01*
X185543Y74371D01*
Y90663D01*
X185420Y90786D01*
X184714D01*
X181959D01*
X170221D01*
X170182Y90747D01*
X169905Y91024D01*
Y94976D01*
X169984Y95055D01*
G37*
G36*
G01X175398Y1071455D02*
G03I-400J0D01*
G37*
G36*
G01D02*
G03I-400J0D01*
G37*
G36*
G01X175400Y1258465D02*
G03I-400J0D01*
G37*
G36*
G01X167919D02*
G03I-400J0D01*
G37*
G36*
G01X189895Y276354D02*
X207468D01*
X208294Y275528D01*
Y258570D01*
X206876Y257152D01*
Y231532D01*
X200160Y224816D01*
Y220921D01*
X197860Y218621D01*
X195860D01*
X195570Y218331D01*
Y205660D01*
X194983Y205073D01*
X188151D01*
X187643Y205581D01*
Y220421D01*
X184360Y223704D01*
Y234821D01*
X184526Y234987D01*
Y250246D01*
X187690Y253410D01*
X187726D01*
X189946Y255630D01*
Y268925D01*
X186937Y271934D01*
X184633D01*
X184117Y272450D01*
Y274738D01*
X184340Y274961D01*
X188502D01*
X189895Y276354D01*
G37*
G36*
G01X196545Y576428D02*
X204393D01*
X204799Y576022D01*
Y564799D01*
X204000Y564000D01*
X203000D01*
X202515Y563515D01*
X196485D01*
X196229Y563771D01*
Y576112D01*
X196545Y576428D01*
G37*
G36*
G01X197839Y1071455D02*
G03I-400J0D01*
G37*
G36*
G01D02*
G03I-400J0D01*
G37*
G36*
G01X190359D02*
G03I-400J0D01*
G37*
G36*
G01D02*
G03I-400J0D01*
G37*
G36*
G01X182879D02*
G03I-400J0D01*
G37*
G36*
G01D02*
G03I-400J0D01*
G37*
G36*
G01X197841Y1258465D02*
G03I-400J0D01*
G37*
G36*
G01X190360D02*
G03I-400J0D01*
G37*
G36*
G01X182880D02*
G03I-400J0D01*
G37*
G36*
G01X213107Y115094D02*
X214163D01*
X214190Y115067D01*
Y111227D01*
G02X214131Y111085I-200J0D01*
G01X212501Y109456D01*
G03X212442Y109314I141J-142D01*
G01Y106183D01*
G03X212501Y106041I200J0D01*
G01X212624Y105918D01*
G03X212766Y105859I142J141D01*
G01X223472D01*
G03X223614Y105918I0J200D01*
G01X223690Y105994D01*
G03X223749Y106136I-141J142D01*
G01Y109681D01*
G03X223690Y109823I-200J0D01*
G01X223456Y110057D01*
G02X223397Y110199I141J142D01*
G01Y114552D01*
X223427Y114625D01*
X223438Y114636D01*
X229022D01*
X230364D01*
X230428Y114572D01*
X230544Y114456D01*
G02X230603Y114314I-141J-142D01*
G01Y105226D01*
G02X230544Y105084I-200J0D01*
G01X229873Y104413D01*
X229790Y104383D01*
X229745Y104388D01*
G03X229563Y104396I-174J-1893D01*
G01X226981D01*
X225695D01*
X224949Y103650D01*
Y101528D01*
X224617Y101196D01*
X213086D01*
X213062Y101202D01*
X205882D01*
X205187Y101897D01*
Y102887D01*
Y114049D01*
G02X205246Y114191I200J0D01*
G01X205368Y114313D01*
G02X205510Y114372I142J-141D01*
G01X212219D01*
G03X212361Y114431I0J200D01*
G01X212965Y115035D01*
G02X213107Y115094I142J-141D01*
G37*
G36*
G01X205369Y120851D02*
X210786D01*
G02X210928Y120792I0J-200D01*
G01X212549Y119171D01*
G03X212691Y119112I142J141D01*
G01X214206D01*
G02X214348Y119053I0J-200D01*
G01X214821Y118580D01*
G02X214880Y118438I-141J-142D01*
G01Y116276D01*
G02X214757Y116091I-200J0D01*
G01X214700Y116068D01*
X214582Y116091D01*
X214578Y116096D01*
X213106D01*
G03X212292Y115777I1J-1202D01*
G02X212156Y115724I-136J147D01*
G01X205310D01*
G02X205168Y115783I0J200D01*
G01X205153Y115798D01*
X205123Y115871D01*
Y120605D01*
G02X205182Y120747I200J0D01*
G01X205227Y120792D01*
G02X205369Y120851I142J-141D01*
G37*
G36*
G01X212800Y1071455D02*
G03I-400J0D01*
G37*
G36*
G01X205320D02*
G03I-400J0D01*
G37*
G36*
G01D02*
G03I-400J0D01*
G37*
G36*
G01X212800D02*
G03I-400J0D01*
G37*
G36*
G01X212801Y1258465D02*
G03I-400J0D01*
G37*
G36*
G01X205321D02*
G03I-400J0D01*
G37*
G36*
G01X216472Y119235D02*
X219918D01*
X222754Y122071D01*
X228801D01*
X229171Y121701D01*
Y116118D01*
X228690Y115637D01*
X219016D01*
X216660D01*
X216312Y115985D01*
Y119075D01*
X216472Y119235D01*
G37*
G36*
G01X215044Y210785D02*
X224484D01*
X226285Y208984D01*
X227381Y207888D01*
Y187037D01*
X226434Y186090D01*
X215662D01*
X214218Y187534D01*
Y209959D01*
X215044Y210785D01*
G37*
G36*
G01X228403Y186998D02*
Y210417D01*
X226395Y212425D01*
Y214067D01*
X226787Y214459D01*
X235209D01*
X235417Y214251D01*
Y212947D01*
X235365Y212895D01*
Y212503D01*
X235372Y212496D01*
Y211679D01*
X235669Y211382D01*
X236486D01*
X240712D01*
X242040Y210054D01*
Y205828D01*
Y187369D01*
X240885Y186214D01*
X229187D01*
X228403Y186998D01*
G37*
G36*
G01X227673Y223195D02*
X237698D01*
X237728Y223225D01*
X240251D01*
X242888Y225862D01*
X251830D01*
X252172Y225520D01*
Y213126D01*
X251460Y212414D01*
X244043D01*
X241189Y215268D01*
X237749D01*
X226772D01*
X225208D01*
X224762Y214822D01*
Y213258D01*
X223489Y211985D01*
X223077D01*
X222300D01*
X214673D01*
X214013Y212645D01*
Y226569D01*
X214689Y227245D01*
X225623D01*
X227383Y225485D01*
Y223485D01*
X227673Y223195D01*
G37*
G36*
G01X227761Y1071455D02*
G03I-400J0D01*
G37*
G36*
G01X220280D02*
G03I-400J0D01*
G37*
G36*
G01D02*
G03I-400J0D01*
G37*
G36*
G01X227761D02*
G03I-400J0D01*
G37*
G36*
G01X227763Y1258465D02*
G03I-400J0D01*
G37*
G36*
G01X220282D02*
G03I-400J0D01*
G37*
G36*
G01X244317Y86514D02*
X253032D01*
X253385Y86161D01*
Y73377D01*
X252939Y72931D01*
X244541D01*
X244206Y73266D01*
Y86403D01*
X244317Y86514D01*
G37*
G36*
G01X242721Y1071455D02*
G03I-400J0D01*
G37*
G36*
G01X235241Y1071454D02*
G03I-400J0D01*
G37*
G36*
G01D02*
G03I-400J0D01*
G37*
G36*
G01X242721Y1071455D02*
G03I-400J0D01*
G37*
G36*
G01X242722Y1258465D02*
G03I-400J0D01*
G37*
G36*
G01X235242D02*
G03I-400J0D01*
G37*
G36*
G01X272694Y89438D02*
X286759D01*
G02X286901Y89379I0J-200D01*
G01X286904Y89376D01*
Y74039D01*
G03X286962Y73898I200J0D01*
G01X287009Y73851D01*
G02Y73568I-141J-141D01*
G01X286822Y73381D01*
G02X286680Y73322I-142J141D01*
G01X282865D01*
X282862Y73319D01*
X262517D01*
G02X262375Y73378I0J200D01*
G01X262307Y73446D01*
G02X262248Y73588I141J142D01*
G01Y86280D01*
G02X262307Y86422I200J0D01*
G01X262375Y86490D01*
G02X262517Y86549I142J-141D01*
G01X267828D01*
G03X267970Y86608I0J200D01*
G01X268803Y87441D01*
G03X268862Y87583I-141J142D01*
G01Y88917D01*
G02X268921Y89059I200J0D01*
G01X269241Y89379D01*
G02X269383Y89438I142J-141D01*
G01X272354D01*
G02X272495Y89379I-1J-200D01*
G01X272593D01*
X272621Y89408D01*
X272694Y89438D01*
G37*
G36*
G01X260243Y176789D02*
X274670D01*
X275433Y176026D01*
Y174795D01*
X276196Y174032D01*
X279304D01*
X279891Y173445D01*
Y161423D01*
X279187Y160719D01*
X260888D01*
Y160720D01*
X258892D01*
X258131Y161481D01*
Y176203D01*
X258717Y176789D01*
X260243D01*
G37*
G36*
G01X287162Y219609D02*
X288804D01*
X289196Y219217D01*
Y210795D01*
X288988Y210587D01*
X287684D01*
X287632Y210639D01*
X287240D01*
X286429D01*
X286119Y210329D01*
Y209518D01*
Y204802D01*
X275650Y194333D01*
Y189191D01*
X279287Y185554D01*
X284052D01*
X284600Y185006D01*
Y183690D01*
X285595Y182695D01*
X287529D01*
X287916Y182308D01*
X290130D01*
X290308Y182130D01*
Y181714D01*
X289995Y181401D01*
X286785D01*
X286384Y181000D01*
X286339D01*
X285046Y179707D01*
X259487D01*
X258175Y181019D01*
Y216698D01*
X259078Y217601D01*
X285154D01*
X287162Y219609D01*
G37*
G36*
G01X285522Y234621D02*
Y221520D01*
X283721Y219719D01*
X282625Y218623D01*
X259784D01*
X258056Y220351D01*
Y252516D01*
X259367Y253827D01*
X281607D01*
X285522Y249912D01*
Y234621D01*
G37*
G36*
G01X260402Y277007D02*
X267831D01*
X280282D01*
X282139Y275150D01*
X284718D01*
X284993Y274875D01*
Y272398D01*
X284443Y271848D01*
X281899D01*
X281795Y271952D01*
X278115Y268272D01*
Y265554D01*
X274917Y262356D01*
X260333D01*
X259645Y263044D01*
Y276250D01*
X260402Y277007D01*
G37*
G36*
G01X250202Y1071455D02*
G03I-400J0D01*
G37*
G36*
G01D02*
G03I-400J0D01*
G37*
G36*
G01X257682D02*
G03I-400J0D01*
G37*
G36*
G01D02*
G03I-400J0D01*
G37*
G36*
G01X257683Y1258465D02*
G03I-400J0D01*
G37*
G36*
G01X250203D02*
G03I-400J0D01*
G37*
G36*
G01X342382Y54588D02*
X367777D01*
Y52591D01*
X342382D01*
G03X336445Y46654I0J-5937D01*
G01Y7874D01*
G02X330571Y2000I-5874J0D01*
G01X283327D01*
G02X277453Y7874I0J5874D01*
G01Y46656D01*
G03X276981Y48975I-5938J-1D01*
G01X279103D01*
G02X279450Y46655I-7587J-2321D01*
G01Y7874D01*
G03X283325Y3998I3876J0D01*
G01X330571D01*
G03X334448Y7874I0J3877D01*
G01Y46654D01*
G02X342382Y54588I7934J0D01*
G37*
G36*
G01X272346Y95055D02*
X287362D01*
X287382Y95035D01*
X291387D01*
X292100Y94322D01*
Y74773D01*
X291239Y73912D01*
X288628D01*
X288364D01*
X287905Y74371D01*
Y90663D01*
X287782Y90786D01*
X287076D01*
X284321D01*
X272583D01*
X272544Y90747D01*
X272267Y91024D01*
Y94976D01*
X272346Y95055D01*
G37*
G36*
G01X273140Y429084D02*
X265292D01*
X264886Y429490D01*
Y440945D01*
X265932Y441991D01*
X273009D01*
X273456Y441544D01*
Y429400D01*
X273140Y429084D01*
G37*
G36*
G01X272643Y1071455D02*
G03I-400J0D01*
G37*
G36*
G01X265162D02*
G03I-400J0D01*
G37*
G36*
G01D02*
G03I-400J0D01*
G37*
G36*
G01X272643D02*
G03I-400J0D01*
G37*
G36*
G01X272644Y1258465D02*
G03I-400J0D01*
G37*
G36*
G01X265163D02*
G03I-400J0D01*
G37*
G36*
G01X292257Y276354D02*
X309830D01*
X310656Y275528D01*
Y258570D01*
X309257Y257171D01*
Y231895D01*
X302522Y225160D01*
Y224007D01*
Y220921D01*
X300222Y218621D01*
X298222D01*
X297932Y218331D01*
Y205660D01*
X297345Y205073D01*
X290513D01*
X290005Y205581D01*
Y220421D01*
X286722Y223704D01*
Y234821D01*
X286888Y234987D01*
Y250246D01*
X290052Y253410D01*
X290088D01*
X292308Y255630D01*
Y268925D01*
X289299Y271934D01*
X286995D01*
X286479Y272450D01*
Y274738D01*
X286702Y274961D01*
X290864D01*
X292257Y276354D01*
G37*
G36*
G01X286091Y442631D02*
X297327D01*
X297356Y442602D01*
X333049D01*
X339072Y436579D01*
X353741D01*
X355351Y434969D01*
Y432764D01*
Y428021D01*
Y411754D01*
G02X355293Y411613I-200J0D01*
G01X354643Y410963D01*
G02X354502Y410905I-141J142D01*
G01X351950D01*
X345020D01*
X335353D01*
X322444Y423814D01*
X303671D01*
X298181Y429304D01*
X286062D01*
X285928Y429438D01*
Y442468D01*
X286091Y442631D01*
G37*
G36*
G01X346116Y482893D02*
X370291D01*
Y473993D01*
X370201Y473903D01*
X364405D01*
X362711Y472209D01*
Y457025D01*
X362363Y456677D01*
X359273D01*
X359113Y456837D01*
Y458826D01*
X359032D01*
X355999Y461859D01*
X345036D01*
X333873Y450696D01*
X292936D01*
X290661Y452971D01*
X286108D01*
X286002Y453077D01*
Y454290D01*
X286097Y454385D01*
X291707D01*
X293586Y456264D01*
X295682D01*
X302705Y463287D01*
X326510D01*
X346116Y482893D01*
G37*
G36*
G01X295084Y1071455D02*
G03I-400J0D01*
G37*
G36*
G01D02*
G03I-400J0D01*
G37*
G36*
G01X287603D02*
G03I-400J0D01*
G37*
G36*
G01X280123D02*
G03I-400J0D01*
G37*
G36*
G01D02*
G03I-400J0D01*
G37*
G36*
G01X287603D02*
G03I-400J0D01*
G37*
G36*
G01X295085Y1258465D02*
G03I-400J0D01*
G37*
G36*
G01X287604D02*
G03I-400J0D01*
G37*
G36*
G01X280124D02*
G03I-400J0D01*
G37*
G36*
G01X315469Y115094D02*
X316525D01*
X316552Y115067D01*
Y111227D01*
G02X316493Y111085I-200J0D01*
G01X314863Y109456D01*
G03X314804Y109314I141J-142D01*
G01Y106183D01*
G03X314863Y106041I200J0D01*
G01X314986Y105918D01*
G03X315128Y105859I142J141D01*
G01X325834D01*
G03X325976Y105918I0J200D01*
G01X326052Y105994D01*
G03X326111Y106136I-141J142D01*
G01Y109681D01*
G03X326052Y109823I-200J0D01*
G01X325818Y110057D01*
G02X325759Y110199I141J142D01*
G01Y114552D01*
X325789Y114625D01*
X325800Y114636D01*
X331384D01*
X332726D01*
X332790Y114572D01*
X332906Y114456D01*
G02X332965Y114314I-141J-142D01*
G01Y105226D01*
G02X332906Y105084I-200J0D01*
G01X332235Y104413D01*
X332152Y104383D01*
X332107Y104388D01*
G03X331925Y104396I-174J-1893D01*
G01X329343D01*
X328057D01*
X327311Y103650D01*
Y101528D01*
X326979Y101196D01*
X315448D01*
X315424Y101202D01*
X308244D01*
X307549Y101897D01*
Y102887D01*
Y114049D01*
G02X307608Y114191I200J0D01*
G01X307730Y114313D01*
G02X307872Y114372I142J-141D01*
G01X314581D01*
G03X314723Y114431I0J200D01*
G01X315327Y115035D01*
G02X315469Y115094I142J-141D01*
G37*
G36*
G01X307731Y120851D02*
X313148D01*
G02X313290Y120792I0J-200D01*
G01X314911Y119171D01*
G03X315053Y119112I142J141D01*
G01X316568D01*
G02X316710Y119053I0J-200D01*
G01X317183Y118580D01*
G02X317242Y118438I-141J-142D01*
G01Y116276D01*
G02X317119Y116091I-200J0D01*
G01X317062Y116068D01*
X316944Y116091D01*
X316940Y116096D01*
X315468D01*
G03X314654Y115777I1J-1202D01*
G02X314518Y115724I-136J147D01*
G01X307672D01*
G02X307530Y115783I0J200D01*
G01X307515Y115798D01*
X307485Y115871D01*
Y120605D01*
G02X307544Y120747I200J0D01*
G01X307589Y120792D01*
G02X307731Y120851I142J-141D01*
G37*
G36*
G01X309108Y421690D02*
X320652D01*
X322830Y419512D01*
Y410583D01*
X321196Y408949D01*
X308564D01*
X304947D01*
X304221Y409675D01*
Y419785D01*
X306126Y421690D01*
X309108D01*
G37*
G36*
G01X364398Y469053D02*
X369358D01*
X369374Y469037D01*
X369819D01*
X372102Y466754D01*
X380799D01*
X381814Y465739D01*
Y458596D01*
X396465D01*
Y449570D01*
X394916Y448021D01*
X384946D01*
X382887Y445962D01*
Y445880D01*
X381756Y444749D01*
X367694D01*
X366029Y443084D01*
Y438941D01*
X365590Y438502D01*
X340306D01*
X334453Y444355D01*
X296555D01*
X296177Y444733D01*
Y448862D01*
X296660Y449345D01*
X338988D01*
X344898Y443435D01*
X357421D01*
X357422Y443434D01*
X363215D01*
X363976Y444195D01*
Y452584D01*
G03X363917Y452726I-200J0D01*
G01X363313Y453330D01*
G02X363254Y453472I141J142D01*
G01Y454528D01*
X363281Y454555D01*
X367121D01*
G02X367263Y454496I0J-200D01*
G01X368892Y452866D01*
G03X369034Y452807I142J141D01*
G01X372165D01*
G03X372307Y452866I0J200D01*
G01X372430Y452989D01*
G03X372489Y453131I-141J142D01*
G01Y463837D01*
G03X372430Y463979I-200J0D01*
G01X372354Y464055D01*
G03X372212Y464114I-142J-141D01*
G01X368667D01*
G03X368525Y464055I0J-200D01*
G01X368291Y463821D01*
G02X368149Y463762I-142J141D01*
G01X363796D01*
X363723Y463792D01*
X363712Y463803D01*
Y468367D01*
X364398Y469053D01*
G37*
G36*
G01X310045Y1071455D02*
G03I-400J0D01*
G37*
G36*
G01X302565D02*
G03I-400J0D01*
G37*
G36*
G01X310045D02*
G03I-400J0D01*
G37*
G36*
G01X302565D02*
G03I-400J0D01*
G37*
G36*
G01X310045Y1258465D02*
G03I-400J0D01*
G37*
G36*
G01X302565D02*
G03I-400J0D01*
G37*
G36*
G01X318834Y119235D02*
X322280D01*
X325116Y122071D01*
X331163D01*
X331533Y121701D01*
Y116118D01*
X331052Y115637D01*
X321378D01*
X319022D01*
X318674Y115985D01*
Y119075D01*
X318834Y119235D01*
G37*
G36*
G01X317406Y210785D02*
X326846D01*
X328647Y208984D01*
X329743Y207888D01*
Y187037D01*
X328796Y186090D01*
X318024D01*
X316580Y187534D01*
Y209959D01*
X317406Y210785D01*
G37*
G36*
G01X330035Y223195D02*
X340060D01*
X340090Y223225D01*
X342613D01*
X345250Y225862D01*
X354192D01*
X354534Y225520D01*
Y213126D01*
X353822Y212414D01*
X346405D01*
X343551Y215268D01*
X340111D01*
X329134D01*
X327570D01*
X327124Y214822D01*
Y213258D01*
X325851Y211985D01*
X325439D01*
X324662D01*
X317035D01*
X316375Y212645D01*
Y226569D01*
X317051Y227245D01*
X327985D01*
X329745Y225485D01*
Y223485D01*
X330035Y223195D01*
G37*
G36*
G01X317525Y1071455D02*
G03I-400J0D01*
G37*
G36*
G01D02*
G03I-400J0D01*
G37*
G36*
G01Y1258465D02*
G03I-400J0D01*
G37*
G36*
G01X330765Y186998D02*
Y210417D01*
X328757Y212425D01*
Y214067D01*
X329149Y214459D01*
X337571D01*
X337779Y214251D01*
Y212947D01*
X337727Y212895D01*
Y212503D01*
Y211927D01*
X338272Y211382D01*
X338848D01*
X343074D01*
X344402Y210054D01*
Y205828D01*
Y187369D01*
X343247Y186214D01*
X331549D01*
X330765Y186998D01*
G37*
G36*
G01X370652Y1066535D02*
G02I-17700J0D01*
G37*
G36*
G01X328747Y1090158D02*
G03I-400J0D01*
G37*
G36*
G01Y1082677D02*
G03I-400J0D01*
G37*
G36*
G01Y1101378D02*
G03I-400J0D01*
G37*
G36*
G01Y1108859D02*
G03I-400J0D01*
G37*
G36*
G01Y1116339D02*
G03I-400J0D01*
G37*
G36*
G01Y1123819D02*
G03I-400J0D01*
G37*
G36*
G01Y1131300D02*
G03I-400J0D01*
G37*
G36*
G01Y1198621D02*
G03I-400J0D01*
G37*
G36*
G01Y1206102D02*
G03I-400J0D01*
G37*
G36*
G01Y1221062D02*
G03I-400J0D01*
G37*
G36*
G01Y1213582D02*
G03I-400J0D01*
G37*
G36*
G01Y1228543D02*
G03I-400J0D01*
G37*
G36*
G01X370652Y1263386D02*
G02I-17700J0D01*
G37*
G36*
G01X328747Y1239762D02*
G03I-400J0D01*
G37*
G36*
G01Y1247243D02*
G03I-400J0D01*
G37*
G36*
G01X346679Y86514D02*
X355394D01*
X355747Y86161D01*
Y73377D01*
X355301Y72931D01*
X346903D01*
X346568Y73266D01*
Y86403D01*
X346679Y86514D01*
G37*
G36*
G01X362815Y397747D02*
Y391404D01*
X362648Y391237D01*
X356338D01*
X356158Y391417D01*
Y397681D01*
X356325Y397848D01*
X362714D01*
X362815Y397747D01*
G37*
G36*
G01X385097Y446558D02*
X419609D01*
X419735Y446432D01*
Y431809D01*
X419302Y431376D01*
X407632D01*
X406847Y430591D01*
Y426913D01*
X406304Y426370D01*
X388437D01*
X387837Y425770D01*
Y415233D01*
X387833Y415229D01*
Y400678D01*
X389958Y398553D01*
Y394595D01*
X389768Y394405D01*
X380907D01*
X380883Y394429D01*
Y397123D01*
X380309Y397697D01*
X372003D01*
X371842Y397858D01*
Y410288D01*
X370083Y412047D01*
X364340D01*
X362507Y410214D01*
Y405785D01*
X361316Y404594D01*
X360419D01*
G03X360277Y404535I0J-200D01*
G01X359400Y403658D01*
G03X359341Y403516I141J-142D01*
G01Y402260D01*
G02X359326Y402183I-200J-1D01*
G01X359093Y401620D01*
G03X359017Y401384I1386J-577D01*
G01X359011Y401356D01*
X358984Y401308D01*
X358954Y401278D01*
Y399147D01*
G02X358895Y399005I-200J0D01*
G01X358835Y398945D01*
G02X358693Y398886I-142J141D01*
G01X358443D01*
G02X358301Y398945I0J200D01*
G01X358106Y399140D01*
G02X358047Y399282I141J142D01*
G01Y401859D01*
G03X357988Y402001I-200J0D01*
G01X357985Y402003D01*
Y402159D01*
G03X357927Y402299I-200J-1D01*
G01X356412Y403815D01*
G02X356353Y403956I141J142D01*
G01Y428530D01*
Y436739D01*
X356997Y437383D01*
X357795D01*
X366426D01*
X367050Y438007D01*
Y442600D01*
X367912Y443462D01*
X382001D01*
X385097Y446558D01*
G37*
G36*
G01X355144Y397254D02*
X354943Y397053D01*
X352644D01*
X351803Y396212D01*
X350246D01*
X350222Y396188D01*
X345959D01*
X345677Y396470D01*
Y400288D01*
X348871Y403482D01*
X349627D01*
X355144Y397965D01*
Y397254D01*
G37*
G36*
G01X356984Y401826D02*
Y398942D01*
X356913Y398871D01*
X356077D01*
X355788D01*
X350736Y403923D01*
Y408358D01*
X352281Y409903D01*
X354757D01*
X355346Y409314D01*
Y403464D01*
X356984Y401826D01*
G37*
G36*
G01X357497Y451151D02*
G02X357556Y451293I200J0D01*
G01X359177Y452914D01*
G03X359236Y453056I-141J142D01*
G01Y454571D01*
G02X359295Y454713I200J0D01*
G01X359768Y455186D01*
G02X359910Y455245I142J-141D01*
G01X362072D01*
G02X362257Y455122I0J-200D01*
G01X362280Y455065D01*
X362257Y454947D01*
X362252Y454943D01*
Y453471D01*
G03X362571Y452657I1202J1D01*
G02X362624Y452521I-147J-136D01*
G01Y445675D01*
G02X362565Y445533I-200J0D01*
G01X362550Y445518D01*
X362477Y445488D01*
X358116D01*
X358088Y445516D01*
X355957D01*
X355446Y446027D01*
Y449100D01*
X357497Y451151D01*
G37*
G36*
G01X369279Y496318D02*
Y486878D01*
X367478Y485077D01*
X366382Y483981D01*
X345531D01*
X344584Y484928D01*
Y495700D01*
X346028Y497144D01*
X368453D01*
X369279Y496318D01*
G37*
G36*
G01X357454Y1218396D02*
Y1218470D01*
X358901Y1219917D01*
X359346D01*
X361609Y1217654D01*
X363611D01*
X365799Y1215466D01*
Y1214018D01*
X360756Y1208975D01*
X355414D01*
X352094Y1212295D01*
Y1213036D01*
X357454Y1218396D01*
G37*
G36*
G01X375056Y89438D02*
X389121D01*
G02X389263Y89379I0J-200D01*
G01X389266Y89376D01*
Y74039D01*
G03X389324Y73898I200J0D01*
G01X389371Y73851D01*
G02Y73568I-141J-141D01*
G01X389184Y73381D01*
G02X389042Y73322I-142J141D01*
G01X385227D01*
X385224Y73319D01*
X364879D01*
G02X364737Y73378I0J200D01*
G01X364669Y73446D01*
G02X364610Y73588I141J142D01*
G01Y86280D01*
G02X364669Y86422I200J0D01*
G01X364737Y86490D01*
G02X364879Y86549I142J-141D01*
G01X370190D01*
G03X370332Y86608I0J200D01*
G01X371165Y87441D01*
G03X371224Y87583I-141J142D01*
G01Y88917D01*
G02X371283Y89059I200J0D01*
G01X371603Y89379D01*
G02X371745Y89438I142J-141D01*
G01X374716D01*
G02X374857Y89379I-1J-200D01*
G01X374955D01*
X374983Y89408D01*
X375056Y89438D01*
G37*
G36*
G01X374708Y95055D02*
X389724D01*
X389744Y95035D01*
X393749D01*
X394462Y94322D01*
Y74773D01*
X393601Y73912D01*
X390990D01*
X390726D01*
X390267Y74371D01*
Y90663D01*
X390144Y90786D01*
X389438D01*
X386683D01*
X374945D01*
X374906Y90747D01*
X374629Y91024D01*
Y94976D01*
X374708Y95055D01*
G37*
G36*
G01X362605Y176789D02*
X377032D01*
X377795Y176026D01*
Y174795D01*
X378558Y174032D01*
X381666D01*
X382253Y173445D01*
Y161423D01*
X381549Y160719D01*
X363250D01*
Y160720D01*
X361254D01*
X360493Y161481D01*
Y176203D01*
X361079Y176789D01*
X362605D01*
G37*
G36*
G01X389524Y219609D02*
X391166D01*
X391558Y219217D01*
Y210795D01*
X391350Y210587D01*
X390046D01*
X389994Y210639D01*
X389602D01*
X389582Y210619D01*
X388720D01*
X388481Y210380D01*
Y209518D01*
Y204802D01*
X378012Y194333D01*
Y189191D01*
X381649Y185554D01*
X386414D01*
X386962Y185006D01*
Y183690D01*
X387957Y182695D01*
X389891D01*
X390278Y182308D01*
X392492D01*
X392670Y182130D01*
Y181714D01*
X392357Y181401D01*
X389147D01*
X388746Y181000D01*
X388701D01*
X387408Y179707D01*
X361849D01*
X360537Y181019D01*
Y216698D01*
X361440Y217601D01*
X387516D01*
X389524Y219609D01*
G37*
G36*
G01X387884Y234621D02*
Y221520D01*
X386083Y219719D01*
X384987Y218623D01*
X362146D01*
X360418Y220351D01*
Y252516D01*
X361729Y253827D01*
X383969D01*
X387884Y249912D01*
Y234621D01*
G37*
G36*
G01X362764Y277007D02*
X370193D01*
X382644D01*
X384501Y275150D01*
X387080D01*
X387355Y274875D01*
Y272398D01*
X386805Y271848D01*
X384261D01*
X384157Y271952D01*
X380477Y268272D01*
Y265554D01*
X377279Y262356D01*
X362695D01*
X362007Y263044D01*
Y276250D01*
X362764Y277007D01*
G37*
G36*
G01X371203Y471921D02*
Y483798D01*
X370423Y484578D01*
Y495368D01*
Y496794D01*
X370732Y497103D01*
X380769D01*
X381682Y496190D01*
Y481973D01*
X381638Y481929D01*
X379134D01*
X378914Y481709D01*
Y481488D01*
Y471761D01*
Y468882D01*
Y468185D01*
X378673Y467944D01*
X372392D01*
X371203Y469133D01*
Y470108D01*
Y470402D01*
Y471921D01*
G37*
G36*
G01X373800Y774000D02*
X381000D01*
X382000Y775000D01*
X392200D01*
X392500Y775300D01*
Y775900D01*
X392200Y776200D01*
X388400D01*
X383600Y781000D01*
X372700D01*
X372100Y780400D01*
Y774600D01*
X372600Y774100D01*
X372700Y774000D01*
X373800D01*
G37*
G36*
G01X372900Y773100D02*
X380900D01*
X382000Y774200D01*
X392100D01*
X392500Y773800D01*
Y773300D01*
X392200Y773000D01*
X387000D01*
X380300Y766300D01*
X373000D01*
X372300Y767000D01*
Y772500D01*
X372900Y773100D01*
G37*
G36*
G01X492382Y54588D02*
X520615D01*
X520833Y54370D01*
Y52809D01*
X520615Y52591D01*
X492382D01*
G03X486445Y46654I0J-5937D01*
G01Y7874D01*
G02X480571Y2000I-5874J0D01*
G01X385689D01*
G02X379815Y7874I0J5874D01*
G01Y46324D01*
X381812D01*
Y7874D01*
G03X385687Y3998I3876J0D01*
G01X480571D01*
G03X484448Y7874I0J3877D01*
G01Y46654D01*
G02X492382Y54588I7934J0D01*
G37*
G36*
G01X394619Y276354D02*
X412192D01*
X413018Y275528D01*
Y258570D01*
Y233325D01*
X404884Y225191D01*
Y224596D01*
Y223752D01*
Y220921D01*
X402584Y218621D01*
X400584D01*
X400294Y218331D01*
Y205660D01*
X399707Y205073D01*
X392875D01*
X392367Y205581D01*
Y220421D01*
X389084Y223704D01*
Y234821D01*
X389250Y234987D01*
Y250246D01*
X392414Y253410D01*
X392450D01*
X394670Y255630D01*
Y268925D01*
X391661Y271934D01*
X389357D01*
X388841Y272450D01*
Y274738D01*
X389064Y274961D01*
X393226D01*
X394619Y276354D01*
G37*
G36*
G01X421179Y446952D02*
X426169D01*
X426220Y446901D01*
Y430343D01*
X428093Y428470D01*
X437134D01*
X437805Y427799D01*
Y378592D01*
X435862Y376649D01*
X422562D01*
X420497Y374584D01*
X405128D01*
X399666Y380046D01*
X396470D01*
X393455Y383061D01*
X388896D01*
X388715Y383242D01*
Y385317D01*
X388172Y385860D01*
X378430D01*
X378228Y386062D01*
Y393183D01*
X378520Y393475D01*
X393609D01*
X393877Y393743D01*
G02X394019Y393802I142J-141D01*
G01X404952D01*
X404954Y393800D01*
X420516D01*
X421314Y394598D01*
Y406210D01*
X417747Y409777D01*
Y426628D01*
X420968Y429849D01*
X421094Y429974D01*
Y446867D01*
X421179Y446952D01*
G37*
G36*
G01X404853Y395002D02*
X392153D01*
X391628Y395527D01*
Y398368D01*
X391130Y398866D01*
X388855Y401141D01*
Y420740D01*
Y422259D01*
Y424461D01*
X389721Y425327D01*
X407215D01*
X408031Y426143D01*
Y429356D01*
X408636Y429961D01*
X409376D01*
X415625D01*
X416510Y429076D01*
Y409012D01*
X419990Y405532D01*
Y404385D01*
Y401684D01*
Y395828D01*
X419164Y395002D01*
X419041D01*
X404853D01*
G37*
G36*
G01X397515Y960770D02*
X406403D01*
G02X406545Y960711I0J-200D01*
G01X408627Y958629D01*
G03X408769Y958570I142J141D01*
G01X421923D01*
X448519D01*
X448617Y958472D01*
X454893Y952196D01*
Y923472D01*
X448072Y916651D01*
X391114D01*
X390114Y917651D01*
Y933651D01*
X390614Y934151D01*
X426173D01*
X427612Y935590D01*
Y941365D01*
X425006Y943971D01*
X407922D01*
G02X407780Y944030I0J200D01*
G01X406887Y944923D01*
G02X406828Y945065I141J142D01*
G01Y951203D01*
G03X406769Y951345I-200J0D01*
G01X403250Y954864D01*
G03X403108Y954923I-142J-141D01*
G01X398509D01*
G02X398367Y954982I0J200D01*
G01X397937Y955412D01*
G02X397878Y955554I141J142D01*
G01Y956704D01*
G03X397819Y956846I-200J0D01*
G01X396942Y957723D01*
G03X396800Y957782I-142J-141D01*
G01X396447D01*
G02X396323Y957825I0J200D01*
G03X395399Y958144I-925J-1182D01*
G01X394586D01*
X394562Y958169D01*
X392431D01*
G02X392289Y958228I0J200D01*
G01X392229Y958288D01*
G02X392170Y958430I141J142D01*
G01Y958680D01*
G02X392229Y958822I200J0D01*
G01X392424Y959017D01*
G02X392566Y959076I142J-141D01*
G01X395610D01*
G03X395752Y959135I0J200D01*
G01X396094Y959477D01*
X396139D01*
X397373Y960711D01*
G02X397515Y960770I142J-141D01*
G37*
G36*
G01X390114Y935151D02*
X425614D01*
X426114Y935651D01*
Y940151D01*
X425114Y941151D01*
X390114D01*
X389614Y940651D01*
Y935651D01*
X390114Y935151D01*
G37*
G36*
G01X440319Y1215174D02*
X400847D01*
X400754D01*
X397920D01*
X396111Y1213365D01*
Y1195772D01*
Y1195449D01*
X397066Y1194494D01*
X456028D01*
X456560Y1193962D01*
X464545Y1185977D01*
Y1183528D01*
Y1157735D01*
X464066Y1157256D01*
X463422D01*
X378696D01*
G02X378554Y1157315I0J200D01*
G01X376901Y1158968D01*
G02X376842Y1159110I141J142D01*
G01Y1176369D01*
Y1236953D01*
Y1237932D01*
G02X376923Y1238092I200J-1D01*
G03X388309Y1254294I-18772J25294D01*
G02X388442Y1254427I191J-58D01*
G01X388983Y1254968D01*
X444986D01*
X446112Y1253842D01*
Y1215746D01*
X445540Y1215174D01*
X440319D01*
G37*
G36*
G01X407198Y1274161D02*
X461782D01*
G02X461924Y1274102I0J-200D01*
G01X462614Y1273412D01*
G02X462673Y1273270I-141J-142D01*
G01Y1268272D01*
G02X462473Y1268072I-200J0D01*
G01X459701D01*
G03X459350Y1267930I-1J-502D01*
G02X459210Y1267872I-141J142D01*
G01X457611D01*
X457495Y1267986D01*
X457493Y1268068D01*
G03X456937Y1269371I-1901J-41D01*
G01X455465Y1270843D01*
G03X454120Y1271400I-1345J-1345D01*
G03X452218Y1269498I0J-1902D01*
G03X452775Y1268153I1902J0D01*
G01X453632Y1267297D01*
G02X453690Y1267156I-142J-141D01*
G01Y1264371D01*
G03X454192Y1263870I501J0D01*
G01X456992D01*
G03X457343Y1264012I1J502D01*
G02X457483Y1264070I141J-142D01*
G01X459210D01*
G02X459350Y1264012I-1J-200D01*
G03X459701Y1263870I350J360D01*
G01X462473D01*
G02X462673Y1263670I0J-200D01*
G01Y1262472D01*
G02X462473Y1262272I-200J0D01*
G01X459701D01*
G03X459200Y1261771I0J-501D01*
G01Y1258600D01*
G02X459149Y1258467I-200J0D01*
G03X458672Y1257208I1425J-1260D01*
G01Y1255571D01*
G03X459262Y1254194I1902J0D01*
G01X459293Y1254165D01*
X459324Y1254091D01*
X459429Y1253986D01*
X459492D01*
X459546Y1253971D01*
X459570Y1253956D01*
G03X460574Y1253670I1003J1615D01*
G03X461302Y1253814I2J1901D01*
G01X461339Y1253830D01*
X461419D01*
X461754Y1253690D01*
X461810Y1253633D01*
X461825Y1253596D01*
G03X462560Y1252813I1390J569D01*
G01X462613Y1252787D01*
X462673Y1252691D01*
Y1252233D01*
X462613Y1252137D01*
X462560Y1252111D01*
G03X461714Y1250760I656J-1351D01*
G03X461911Y1250016I1503J0D01*
G01X461938Y1249969D01*
X461937Y1249864D01*
X461736Y1249518D01*
G02X461563Y1249418I-173J100D01*
G01X460639D01*
G03X460138Y1248917I0J-501D01*
G01Y1246117D01*
G03X460566Y1245621I501J0D01*
G01X460641Y1245610D01*
X460738Y1245498D01*
Y1245032D01*
G03X461177Y1243970I1501J-1D01*
G01X462154Y1242993D01*
G03X462560Y1242704I1062J1062D01*
G01X462613Y1242679D01*
X462673Y1242583D01*
Y1219698D01*
G02X462473Y1219498I-200J0D01*
G01X462401D01*
X462347Y1219513D01*
X462323Y1219528D01*
G03X461319Y1219814I-1003J-1615D01*
G03X460315Y1219528I-1J-1901D01*
G01X460291Y1219513D01*
X460237Y1219498D01*
X460186D01*
X460070Y1219380D01*
Y1219349D01*
X460007Y1219290D01*
G03X459418Y1217913I1312J-1376D01*
G01Y1215529D01*
G02X459218Y1215329I-200J0D01*
G01X458126D01*
G02X457926Y1215529I0J200D01*
G01Y1217913D01*
G03X457337Y1219290I-1901J1D01*
G01X457306Y1219319D01*
X457274Y1219393D01*
X457170Y1219498D01*
X457107D01*
X457053Y1219513D01*
X457029Y1219528D01*
G03X456025Y1219814I-1003J-1615D01*
G03X455021Y1219528I-1J-1901D01*
G01X454997Y1219513D01*
X454943Y1219498D01*
X454892D01*
X454776Y1219380D01*
Y1219349D01*
X454713Y1219290D01*
G03X454124Y1217913I1312J-1376D01*
G01Y1215529D01*
G02X453924Y1215329I-200J0D01*
G01X448536D01*
G02X448394Y1215388I0J200D01*
G01X448283Y1215499D01*
G02X448224Y1215641I141J142D01*
G01Y1254815D01*
G03X448165Y1254957I-200J0D01*
G01X446839Y1256283D01*
G03X446697Y1256342I-142J-141D01*
G01X393274D01*
G02X393132Y1256401I0J200D01*
G01X392624Y1256909D01*
G02X392565Y1257051I141J142D01*
G01Y1273064D01*
G02X392624Y1273206I200J0D01*
G01X393520Y1274102D01*
G02X393662Y1274161I142J-141D01*
G01X401812D01*
G02X401954Y1274102I0J-200D01*
G01X402062Y1273994D01*
G02X402121Y1273852I-141J-142D01*
G01Y1270625D01*
G03X402180Y1270483I200J0D01*
G01X402582Y1270081D01*
G03X402724Y1270022I142J141D01*
G01X406451D01*
G03X406593Y1270081I0J200D01*
G01X406939Y1270427D01*
G03X406998Y1270569I-141J142D01*
G01Y1273961D01*
G02X407198Y1274161I200J0D01*
G37*
G36*
G01X386336Y1330953D02*
X446670D01*
G02X446812Y1330894I0J-200D01*
G01X449003Y1328703D01*
G02X449005Y1328701I-140J-142D01*
G02X449062Y1328561I-143J-140D01*
G01Y1299664D01*
G03X449262Y1299464I200J0D01*
G01X451638D01*
X451653Y1299462D01*
G03X451706Y1299455I239J1605D01*
G01X451759Y1299449D01*
G03X451886Y1299444I127J1618D01*
G01X451893D01*
G03X452019Y1299449I-1J1623D01*
G01X452072Y1299455D01*
G03X452125Y1299462I-186J1612D01*
G01X452140Y1299464D01*
X452432D01*
G02X452572Y1299407I0J-200D01*
G01X452573Y1299406D01*
X454148Y1297831D01*
G02X454150Y1297829I-140J-142D01*
G02X454207Y1297689I-143J-140D01*
G01Y1289427D01*
X454177Y1289353D01*
X454148Y1289325D01*
X445297Y1280474D01*
X445234Y1280445D01*
X445199Y1280442D01*
G03X443850Y1279091I146J-1495D01*
G01X443847Y1279056D01*
X443818Y1278995D01*
X443482Y1278659D01*
G02X443340Y1278600I-142J141D01*
G01X441747D01*
G02X441608Y1278656I0J200D01*
G01X441412Y1278846D01*
G02X441356Y1278946I139J144D01*
G01X441346Y1278989D01*
X441345Y1279008D01*
Y1279009D01*
G03X438345I-1500J-62D01*
G01Y1279008D01*
X438344Y1278989D01*
X438334Y1278946D01*
G02X438278Y1278846I-195J44D01*
G01X438082Y1278656D01*
G02X437943Y1278600I-139J144D01*
G01X436247D01*
G02X436108Y1278656I0J200D01*
G01X435912Y1278846D01*
G02X435856Y1278946I139J144D01*
G01X435846Y1278989D01*
X435845Y1279008D01*
Y1279009D01*
G03X432845I-1500J-62D01*
G01Y1279008D01*
X432844Y1278989D01*
X432834Y1278946D01*
G02X432778Y1278846I-195J44D01*
G01X432582Y1278656D01*
G02X432443Y1278600I-139J144D01*
G01X430747D01*
G02X430608Y1278656I0J200D01*
G01X430412Y1278846D01*
G02X430356Y1278946I139J144D01*
G01X430346Y1278989D01*
X430345Y1279008D01*
Y1279009D01*
G03X427345I-1500J-62D01*
G01Y1279008D01*
X427344Y1278989D01*
X427334Y1278946D01*
G02X427278Y1278846I-195J44D01*
G01X427082Y1278656D01*
G02X426943Y1278600I-139J144D01*
G01X389475D01*
X389401Y1278630D01*
X389373Y1278659D01*
X383993Y1284039D01*
G02X383934Y1284181I141J142D01*
G01Y1295259D01*
G03X383933Y1295280I-200J1D01*
G01X383928Y1295325D01*
X383981Y1295476D01*
G02X384041Y1295564I189J-65D01*
G01X384048Y1295569D01*
X384285Y1295734D01*
G02X384440Y1295766I115J-164D01*
G01X384471Y1295760D01*
X384488Y1295755D01*
X384492Y1295753D01*
G03X385091Y1295650I601J1700D01*
G01X385133D01*
G03X385871Y1295827I-42J1803D01*
G01X385890Y1295836D01*
X385978Y1295859D01*
X386031Y1295853D01*
X386181Y1295812D01*
X386238Y1295772D01*
X386259Y1295743D01*
G03X386341Y1295636I1328J933D01*
G03X387587Y1295052I1246J1037D01*
G03Y1298298I0J1623D01*
G01X387586D01*
G03X387459Y1298293I0J-1623D01*
G01X387405Y1298287D01*
G03X387355Y1298280I200J-1610D01*
G01X387311Y1298273D01*
X387227Y1298298D01*
X386963Y1298526D01*
G02X386894Y1298677I131J151D01*
G01Y1299630D01*
G02X386963Y1299781I200J0D01*
G01X387226Y1300008D01*
X387310Y1300033D01*
X387354Y1300026D01*
G03X387587Y1300008I241J1604D01*
G03X389210Y1301631I0J1623D01*
G01Y1301663D01*
X389217Y1301693D01*
Y1301695D01*
G03X389266Y1302086I-1573J396D01*
G01Y1302089D01*
G03X387644Y1303712I-1623J0D01*
G03X386185Y1302799I0J-1622D01*
G01X386170Y1302768D01*
X386093Y1302693D01*
X386066Y1302667D01*
X385822Y1302563D01*
G02X385780Y1302550I-80J183D01*
G02X385678Y1302558I-36J197D01*
G03X385095Y1302656I-586J-1705D01*
G01X385061Y1302655D01*
X385059D01*
G03X384484Y1302551I29J-1802D01*
G01X384471Y1302546D01*
X384400Y1302531D01*
X384319Y1302548D01*
X384285Y1302572D01*
X384020Y1302756D01*
G02X383934Y1302920I114J164D01*
G01Y1328551D01*
G02X383993Y1328693I200J0D01*
G01X386194Y1330894D01*
G02X386336Y1330953I142J-141D01*
G37*
G36*
G01X388208Y1296675D02*
G03I-621J0D01*
G37*
G36*
G01X388265Y1302089D02*
G03I-621J0D01*
G37*
G36*
G01X409083Y1406700D02*
X423017D01*
G02X423159Y1406641I0J-200D01*
G01X427941Y1401859D01*
G02X428000Y1401717I-141J-142D01*
G01Y1376983D01*
G02X427941Y1376841I-200J0D01*
G01X426296Y1375196D01*
X426157Y1375182D01*
X426097Y1375220D01*
G03X425283Y1375460I-814J-1262D01*
G03X423781Y1373958I0J-1502D01*
G03X424021Y1373144I1502J0D01*
G01X424059Y1373084D01*
X424045Y1372945D01*
X422659Y1371559D01*
G03X422600Y1371417I141J-142D01*
G01Y1356883D01*
G02X422541Y1356741I-200J0D01*
G01X421059Y1355259D01*
G02X420917Y1355200I-142J141D01*
G01X417749D01*
G02X417575Y1355302I0J200D01*
G03X417199Y1355799I-1974J-1103D01*
G01X416059Y1356940D01*
G02X416000Y1357081I141J142D01*
G01Y1366817D01*
G02X416059Y1366959I200J0D01*
G01X418041Y1368941D01*
G03X418100Y1369083I-141J142D01*
G01Y1369691D01*
G02X418163Y1369837I200J0D01*
G01X418405Y1370065D01*
X418481Y1370093D01*
X418523Y1370091D01*
G03X418610Y1370088I95J1499D01*
G03Y1373092I0J1502D01*
G03X418523Y1373089I8J-1502D01*
G01X418481Y1373087D01*
X418405Y1373115D01*
X418163Y1373343D01*
G02X418100Y1373489I137J146D01*
G01Y1378117D01*
G03X418041Y1378259I-200J0D01*
G01X415959Y1380341D01*
G03X415817Y1380400I-142J-141D01*
G01X414903D01*
G02X414731Y1380498I0J200D01*
G03X412143I-1294J-761D01*
G02X411971Y1380400I-172J102D01*
G01X409653D01*
G02X409484Y1380494I1J200D01*
G03X406940I-1272J-799D01*
G02X406771Y1380400I-170J106D01*
G01X404483D01*
G02X404313Y1380496I1J200D01*
G03X401745I-1284J-781D01*
G02X401575Y1380400I-171J104D01*
G01X392283D01*
G02X392141Y1380459I0J200D01*
G01X390659Y1381941D01*
G02X390600Y1382083I141J142D01*
G01Y1396417D01*
G02X390659Y1396559I200J0D01*
G01X392041Y1397941D01*
G02X392183Y1398000I142J-141D01*
G01X395417D01*
G02X395559Y1397941I0J-200D01*
G01X396040Y1397460D01*
G02X396098Y1397319I-142J-141D01*
G01Y1395081D01*
G02X396040Y1394940I-200J0D01*
G01X394059Y1392959D01*
G03X394000Y1392817I141J-142D01*
G01Y1392299D01*
G02X393941Y1392158I-200J1D01*
G01X393757Y1391973D01*
G03X393698Y1391832I141J-142D01*
G01Y1388868D01*
G03X393757Y1388727I200J1D01*
G01X393941Y1388542D01*
G02X394000Y1388401I-141J-142D01*
G01Y1387683D01*
G03X394059Y1387541I200J0D01*
G01X395741Y1385859D01*
G03X395883Y1385800I142J141D01*
G01X401271D01*
G02X401429Y1385722I0J-200D01*
G01X401651Y1385434D01*
X401670Y1385345D01*
X401658Y1385299D01*
G03X401609Y1384920I1453J-380D01*
G03X404613I1502J0D01*
G03X404564Y1385299I-1502J-1D01*
G01X404552Y1385345D01*
X404571Y1385434D01*
X404793Y1385722D01*
G02X404951Y1385800I158J-122D01*
G01X411602D01*
G02X411761Y1385721I0J-200D01*
G01X411983Y1385431D01*
X412000Y1385340D01*
X411988Y1385295D01*
G03X411935Y1384899I1449J-395D01*
G03X414939I1502J0D01*
G03X414886Y1385295I-1502J1D01*
G01X414874Y1385340D01*
X414891Y1385431D01*
X415113Y1385721D01*
G02X415272Y1385800I159J-121D01*
G01X421517D01*
G03X421659Y1385859I0J200D01*
G01X423041Y1387241D01*
G03X423100Y1387383I-141J142D01*
G01Y1387984D01*
X423102Y1387985D01*
Y1391832D01*
G03X423043Y1391973I-200J-1D01*
G01X421873Y1393143D01*
G03X421732Y1393202I-142J-141D01*
G01X418015D01*
X418002Y1393215D01*
Y1395898D01*
G02X418202Y1396098I199J0D01*
G01X420232D01*
G03X420373Y1396157I-1J200D01*
G01X420458Y1396241D01*
G02X420599Y1396300I142J-141D01*
G01X420717D01*
G03X420859Y1396359I0J200D01*
G01X421241Y1396741D01*
G03X421300Y1396883I-141J142D01*
G01Y1397084D01*
X421302Y1397085D01*
Y1400215D01*
X421300Y1400216D01*
Y1400717D01*
G03X421241Y1400859I-200J0D01*
G01X420534Y1401566D01*
X420508Y1401675D01*
X420526Y1401729D01*
G03X420602Y1402200I-1426J472D01*
G03X419100Y1403702I-1502J0D01*
G03X417598Y1402201I0J-1502D01*
G01Y1402161D01*
X417568Y1402088D01*
X417339Y1401860D01*
G02X417198Y1401802I-141J142D01*
G01X409081D01*
G02X408940Y1401860I0J200D01*
G01X408559Y1402241D01*
G02X408500Y1402383I141J142D01*
G01Y1406117D01*
G02X408559Y1406259I200J0D01*
G01X408941Y1406641D01*
G02X409083Y1406700I142J-141D01*
G37*
G36*
G01X380415Y1563100D02*
X384817D01*
G02X384959Y1563041I0J-200D01*
G01X385541Y1562459D01*
G02X385600Y1562317I-141J-142D01*
G01Y1558383D01*
G02X385541Y1558241I-200J0D01*
G01X385159Y1557859D01*
G02X385017Y1557800I-142J141D01*
G01X381383D01*
G03X381241Y1557741I0J-200D01*
G01X380759Y1557259D01*
G03X380700Y1557117I141J-142D01*
G01Y1557074D01*
X380644Y1557016D01*
G03X380116Y1555700I1373J-1315D01*
G03X380644Y1554384I1901J-1D01*
G02X380700Y1554246I-144J-139D01*
G01Y1553154D01*
G02X380644Y1553016I-200J1D01*
G03X380116Y1551700I1373J-1315D01*
G03X380644Y1550384I1901J-1D01*
G02X380700Y1550246I-144J-139D01*
G01Y1549154D01*
G02X380644Y1549016I-200J1D01*
G03X380116Y1547700I1373J-1315D01*
G03X381201Y1545982I1901J-1D01*
G02X381257Y1545943I-85J-181D01*
G01X381270Y1545930D01*
X381343Y1545900D01*
X381403D01*
X381433Y1545890D01*
G03X382017Y1545798I584J1810D01*
G01X384442D01*
G03X385026Y1545890I0J1902D01*
G01X385056Y1545900D01*
X385317D01*
G02X385459Y1545841I0J-200D01*
G01X385641Y1545659D01*
G02X385700Y1545517I-141J-142D01*
G01Y1539083D01*
G03X385759Y1538941I200J0D01*
G01X385949Y1538751D01*
G02X386008Y1538610I-141J-142D01*
G01Y1538568D01*
X386124Y1538450D01*
X386167D01*
G02X386308Y1538392I0J-200D01*
G01X386641Y1538059D01*
G03X386783Y1538000I142J141D01*
G01X390717D01*
G02X390859Y1537941I0J-200D01*
G01X391341Y1537459D01*
G02X391400Y1537317I-141J-142D01*
G01Y1533383D01*
G02X391341Y1533241I-200J0D01*
G01X390959Y1532859D01*
G02X390817Y1532800I-142J141D01*
G01X378762D01*
G02X378562Y1533000I0J200D01*
G01Y1561246D01*
G02X378620Y1561388I200J1D01*
G01X380274Y1563041D01*
G02X380415Y1563100I142J-141D01*
G37*
G36*
G01X419109Y458336D02*
Y460127D01*
X418987Y460249D01*
X404822D01*
X403967Y459394D01*
Y453553D01*
X404212Y453308D01*
X407650D01*
X407895Y453553D01*
Y457135D01*
X408846Y458086D01*
X419033D01*
X419109Y458162D01*
Y458336D01*
G37*
G36*
G01X419778Y447491D02*
Y449363D01*
X418286Y450855D01*
X400512D01*
X400033Y450376D01*
Y447596D01*
X400171Y447458D01*
X419745D01*
X419778Y447491D01*
G37*
G36*
G01X411580Y576490D02*
X469904D01*
X470812Y575582D01*
Y542587D01*
X470237Y542012D01*
X416502D01*
X414824Y540334D01*
Y527560D01*
X414840Y527544D01*
Y527227D01*
X416755Y525312D01*
X454414D01*
X455313Y524413D01*
Y523475D01*
Y503072D01*
X455223Y502982D01*
X452910D01*
X452750Y502822D01*
Y492675D01*
X452563Y492488D01*
X445072D01*
X444823Y492737D01*
Y517700D01*
X443096Y519427D01*
X400319D01*
X397373Y522373D01*
Y549140D01*
Y554327D01*
X399679Y556633D01*
X408452D01*
X410413Y558594D01*
Y575323D01*
X411580Y576490D01*
G37*
G36*
G01X402705Y725878D02*
X471104D01*
G02X471246Y725819I0J-200D01*
G01X472059Y725006D01*
G02X472118Y724864I-141J-142D01*
G01Y656116D01*
G02X472059Y655974I-200J0D01*
G01X461626Y645541D01*
G02X461484Y645482I-142J141D01*
G01X443141D01*
G02X442999Y645541I0J200D01*
G01X442972Y645568D01*
X442942Y645641D01*
Y657273D01*
G02X443001Y657415I200J0D01*
G01X443028Y657442D01*
X443058Y657515D01*
Y658422D01*
G02X443117Y658563I200J-1D01*
G01X453754Y669201D01*
G03X453812Y669342I-142J141D01*
G01Y694265D01*
G03X453754Y694406I-200J0D01*
G01X453697Y694464D01*
G02X453638Y694605I141J142D01*
G01Y715457D01*
G03X453579Y715599I-200J0D01*
G01X452746Y716432D01*
G03X452604Y716491I-142J-141D01*
G01X418869D01*
G03X418727Y716432I0J-200D01*
G01X418118Y715823D01*
G03X418059Y715681I141J-142D01*
G01Y667642D01*
G03X418118Y667500I200J0D01*
G01X424940Y660678D01*
G02X424999Y660536I-141J-142D01*
G01Y643423D01*
G03X425058Y643281I200J0D01*
G01X428677Y639662D01*
G02X428736Y639520I-141J-142D01*
G01Y628031D01*
G02X428677Y627889I-200J0D01*
G01X428658Y627870D01*
X420070D01*
X420049Y627848D01*
X404621D01*
G02X404479Y627907I0J200D01*
G01X397757Y634629D01*
G02X397698Y634771I141J142D01*
G01Y720871D01*
G02X397757Y721013I200J0D01*
G01X402563Y725819D01*
G02X402705Y725878I142J-141D01*
G37*
G36*
G01X400000Y771200D02*
X416500D01*
X416700Y771000D01*
Y754700D01*
X416400Y754400D01*
X400100D01*
X399900Y754600D01*
Y771100D01*
X400000Y771200D01*
G37*
G36*
G01X403200Y778600D02*
X403600D01*
X403910Y778910D01*
Y783810D01*
X409400Y789300D01*
Y795900D01*
X408400Y796900D01*
X403300D01*
X402745Y796345D01*
Y786508D01*
X402857Y786396D01*
Y778943D01*
X403200Y778600D01*
G37*
G36*
G01X399200D02*
X401600D01*
X401927Y778927D01*
Y785773D01*
X401700Y786000D01*
Y796779D01*
X400705Y797774D01*
X395994D01*
X395200Y796980D01*
Y790318D01*
X398900Y786618D01*
Y778900D01*
X399200Y778600D01*
G37*
G36*
G01X403468Y851859D02*
Y841450D01*
X402795Y840777D01*
X397551D01*
X396968Y841360D01*
Y851679D01*
X397597Y852308D01*
X403019D01*
X403468Y851859D01*
G37*
G36*
G01X413349Y887279D02*
Y890459D01*
X413479Y890589D01*
X415669D01*
X415879Y890379D01*
Y877079D01*
X417326Y875632D01*
X419181Y873777D01*
Y839538D01*
X418553Y838910D01*
X405689D01*
X405195Y839404D01*
Y858744D01*
X407121Y860670D01*
X414245Y867794D01*
X414659Y868209D01*
Y885969D01*
X413349Y887279D01*
G37*
G36*
G01X407189Y890129D02*
X412898Y884420D01*
Y883030D01*
X412739Y882871D01*
X409569D01*
X409357Y883084D01*
Y884082D01*
X405039Y888400D01*
Y890409D01*
Y890729D01*
X405079Y890769D01*
X406989D01*
X407189Y890569D01*
Y890129D01*
G37*
G36*
G01X405578Y893888D02*
X403729Y892039D01*
Y888769D01*
X403719Y888760D01*
X403617Y888658D01*
X400235D01*
X399835Y889058D01*
Y906072D01*
Y907672D01*
X400321Y908158D01*
X425321D01*
X425809Y907670D01*
Y906491D01*
Y892671D01*
X418219Y885081D01*
Y878299D01*
X417949Y878029D01*
X417409D01*
X417029Y878409D01*
Y891459D01*
X415904Y892584D01*
X415899D01*
X414564Y893919D01*
X414464Y894019D01*
X405708D01*
X405578Y893889D01*
Y893888D01*
G37*
G36*
G01X406099Y966216D02*
X403165D01*
G02X403023Y966275I0J200D01*
G01X402450Y966848D01*
G02X402391Y966990I141J142D01*
G01Y974355D01*
X402403Y974367D01*
Y977829D01*
X402410Y977836D01*
Y983234D01*
X403269Y984093D01*
X422245D01*
X423816Y982522D01*
Y976992D01*
G02X423875Y976850I-141J-142D01*
G01Y961528D01*
G02X423816Y961386I-200J0D01*
G01X423227Y960797D01*
G02X423085Y960738I-142J141D01*
G01X408414D01*
G02X408272Y960797I0J200D01*
G01X406776Y962293D01*
G02X406717Y962435I141J142D01*
G01Y965598D01*
G03X406658Y965740I-200J0D01*
G01X406241Y966157D01*
G03X406099Y966216I-142J-141D01*
G37*
G36*
G01X527406Y1104797D02*
X528798D01*
X529430Y1104165D01*
X529625Y1103970D01*
Y1098766D01*
X529367Y1098508D01*
G03X522625Y1086654I7050J-11854D01*
G03X525091Y1078784I13791J0D01*
G01Y1053556D01*
X522349Y1050814D01*
X396153D01*
G02X396011Y1050873I0J200D01*
G01X394141Y1052743D01*
G02X394082Y1052885I141J142D01*
G01Y1096005D01*
Y1097717D01*
X394870Y1098505D01*
X399872D01*
X400223Y1098154D01*
Y1096229D01*
Y1058207D01*
Y1057492D01*
X401589Y1056126D01*
X401990Y1055725D01*
X416896D01*
X416964D01*
X416987Y1055748D01*
X419925D01*
X420475D01*
X420862Y1056135D01*
Y1058821D01*
Y1071074D01*
G02X420921Y1071216I200J0D01*
G01X421135Y1071430D01*
G02X421277Y1071489I142J-141D01*
G01X441969D01*
G03X442111Y1071548I0J200D01*
G01X443469Y1072906D01*
G03X443528Y1073048I-141J142D01*
G01Y1097741D01*
G02X443491Y1097793I142J140D01*
G01X443480Y1097820D01*
G02X443470Y1097881I190J62D01*
G01Y1099671D01*
G02X443528Y1099812I200J0D01*
G01X443564Y1099848D01*
G02X443614Y1099884I140J-142D01*
G02X443705Y1099906I91J-178D01*
G01X464861D01*
G02X465003Y1099847I0J-200D01*
G01X465777Y1099073D01*
G02X465836Y1098931I-141J-142D01*
G01Y1072748D01*
G03X465895Y1072606I200J0D01*
G01X467123Y1071377D01*
X488133D01*
X488556Y1070954D01*
Y1058768D01*
Y1057735D01*
X489917Y1056374D01*
X490298Y1055993D01*
X490752Y1055539D01*
X507934D01*
X508388Y1055993D01*
X508889Y1056494D01*
Y1056868D01*
X508948Y1056927D01*
Y1058999D01*
Y1088285D01*
X508959Y1088312D01*
Y1092847D01*
X508953Y1092853D01*
Y1099722D01*
X509128Y1099897D01*
X523862D01*
X524404D01*
X526963Y1102456D01*
Y1102998D01*
Y1104354D01*
X527406Y1104797D01*
G37*
G36*
G01X401704Y1059146D02*
Y1069654D01*
X402767Y1070717D01*
X418682D01*
X419651Y1069748D01*
Y1059792D01*
Y1058250D01*
X418513Y1057112D01*
X402934D01*
X401704Y1058342D01*
Y1059146D01*
G37*
G36*
G01X434189Y1120863D02*
X436878D01*
X437082Y1120659D01*
X447768D01*
X447784Y1120643D01*
Y1112626D01*
X447725Y1112567D01*
X441849D01*
X441675Y1112393D01*
Y1107201D01*
X441156Y1106682D01*
Y1101290D01*
X442278Y1100168D01*
Y1073191D01*
X441724Y1072637D01*
X402527D01*
X401695Y1073469D01*
Y1104852D01*
G03X401697Y1104896I-1498J90D01*
G03X401695Y1104940I-1500J-46D01*
G01Y1120497D01*
X402061Y1120863D01*
X404750D01*
X404954Y1120659D01*
X415640D01*
X415656Y1120643D01*
Y1112626D01*
X415597Y1112567D01*
X409721D01*
X409547Y1112393D01*
Y1107309D01*
X409035Y1106797D01*
Y1101558D01*
X410178Y1100415D01*
Y1097323D01*
X411016Y1096485D01*
X429390D01*
X433823Y1100918D01*
Y1120497D01*
X434189Y1120863D01*
G37*
G36*
G01X402408Y1156179D02*
X529775D01*
X529848Y1156149D01*
X529876Y1156121D01*
X547546D01*
G02X547688Y1156062I0J-200D01*
G01X549193Y1154557D01*
G02X549252Y1154415I-141J-142D01*
G01Y1126777D01*
G02X549193Y1126635I-200J0D01*
G01X548309Y1125751D01*
G02X548167Y1125692I-142J141D01*
G01X527188D01*
G03X527046Y1125633I0J-200D01*
G01X526321Y1124908D01*
G02X526179Y1124849I-142J141D01*
G01X518527D01*
X518454Y1124819D01*
X518446Y1124811D01*
Y1120677D01*
G03X518505Y1120535I200J0D01*
G01X518508Y1120532D01*
G03X518650Y1120473I142J141D01*
G01X522874D01*
G02X523016Y1120414I0J-200D01*
G01X523112Y1120318D01*
G03X523254Y1120259I142J141D01*
G01X525437D01*
G02X525579Y1120200I0J-200D01*
G01X525651Y1120128D01*
G02X525710Y1119986I-141J-142D01*
G01Y1119595D01*
G02X525652Y1119453I-200J-1D01*
G01X525546Y1119347D01*
G02X525404Y1119288I-142J141D01*
G01X523011D01*
G03X522869Y1119229I0J-200D01*
G01X522069Y1118429D01*
G03X522010Y1118287I141J-142D01*
G01Y1115480D01*
G03X522069Y1115338I200J0D01*
G01X522433Y1114974D01*
G03X522575Y1114915I142J141D01*
G01X525563D01*
X525568Y1114910D01*
Y1114100D01*
X525538Y1114027D01*
X525521Y1114010D01*
X522615D01*
G03X522473Y1113951I0J-200D01*
G01X522069Y1113547D01*
G03X522010Y1113405I141J-142D01*
G01Y1113045D01*
G02X521951Y1112903I-200J0D01*
G01X521891Y1112843D01*
G02X521749Y1112784I-142J141D01*
G01X514955D01*
X514932Y1112807D01*
Y1121516D01*
G03X514873Y1121658I-200J0D01*
G01X514536Y1121995D01*
G03X514394Y1122054I-142J-141D01*
G01X502494D01*
G03X502352Y1121995I0J-200D01*
G01X502309Y1121952D01*
G02X502167Y1121893I-142J141D01*
G01X500115D01*
G02X499973Y1121952I0J200D01*
G01X499406Y1122519D01*
G02X499347Y1122661I141J142D01*
G01Y1124884D01*
X499230Y1125001D01*
X499203D01*
X498571Y1125633D01*
G03X498429Y1125692I-142J-141D01*
G01X495060D01*
G03X494918Y1125633I0J-200D01*
G01X494193Y1124908D01*
G02X494051Y1124849I-142J141D01*
G01X486399D01*
X486326Y1124819D01*
X486318Y1124811D01*
Y1120677D01*
G03X486377Y1120535I200J0D01*
G01X486380Y1120532D01*
G03X486522Y1120473I142J141D01*
G01X490746D01*
G02X490888Y1120414I0J-200D01*
G01X490984Y1120318D01*
G03X491126Y1120259I142J141D01*
G01X493309D01*
G02X493451Y1120200I0J-200D01*
G01X493523Y1120128D01*
G02X493582Y1119986I-141J-142D01*
G01Y1119595D01*
G02X493524Y1119453I-200J-1D01*
G01X493418Y1119347D01*
G02X493276Y1119288I-142J141D01*
G01X490883D01*
G03X490741Y1119229I0J-200D01*
G01X489941Y1118429D01*
G03X489882Y1118287I141J-142D01*
G01Y1115480D01*
G03X489941Y1115338I200J0D01*
G01X490305Y1114974D01*
G03X490447Y1114915I142J141D01*
G01X493435D01*
X493440Y1114910D01*
Y1114100D01*
X493410Y1114027D01*
X493393Y1114010D01*
X490487D01*
G03X490345Y1113951I0J-200D01*
G01X489941Y1113547D01*
G03X489882Y1113405I141J-142D01*
G01Y1113045D01*
G02X489823Y1112903I-200J0D01*
G01X489763Y1112843D01*
G02X489621Y1112784I-142J141D01*
G01X482827D01*
X482804Y1112807D01*
Y1121516D01*
G03X482745Y1121658I-200J0D01*
G01X482408Y1121995D01*
G03X482266Y1122054I-142J-141D01*
G01X470366D01*
G03X470224Y1121995I0J-200D01*
G01X470181Y1121952D01*
G02X470039Y1121893I-142J141D01*
G01X467904D01*
X464105Y1125692D01*
X461601D01*
G03X461459Y1125633I0J-200D01*
G01X460734Y1124908D01*
G02X460592Y1124849I-142J141D01*
G01X452940D01*
X452867Y1124819D01*
X452859Y1124811D01*
Y1120677D01*
G03X452918Y1120535I200J0D01*
G01X452921Y1120532D01*
G03X453063Y1120473I142J141D01*
G01X457287D01*
G02X457429Y1120414I0J-200D01*
G01X457525Y1120318D01*
G03X457667Y1120259I142J141D01*
G01X459850D01*
G02X459992Y1120200I0J-200D01*
G01X460064Y1120128D01*
G02X460123Y1119986I-141J-142D01*
G01Y1119595D01*
G02X460065Y1119453I-200J-1D01*
G01X459959Y1119347D01*
G02X459817Y1119288I-142J141D01*
G01X457424D01*
G03X457282Y1119229I0J-200D01*
G01X456482Y1118429D01*
G03X456423Y1118287I141J-142D01*
G01Y1115480D01*
G03X456482Y1115338I200J0D01*
G01X456846Y1114974D01*
G03X456988Y1114915I142J141D01*
G01X459976D01*
X459981Y1114910D01*
Y1114100D01*
X459951Y1114027D01*
X459934Y1114010D01*
X457028D01*
G03X456886Y1113951I0J-200D01*
G01X456482Y1113547D01*
G03X456423Y1113405I141J-142D01*
G01Y1113045D01*
G02X456364Y1112903I-200J0D01*
G01X456304Y1112843D01*
G02X456162Y1112784I-142J141D01*
G01X449368D01*
X449345Y1112807D01*
Y1121516D01*
G03X449286Y1121658I-200J0D01*
G01X448949Y1121995D01*
G03X448807Y1122054I-142J-141D01*
G01X436907D01*
G03X436765Y1121995I0J-200D01*
G01X436722Y1121952D01*
G02X436580Y1121893I-142J141D01*
G01X434528D01*
G02X434386Y1121952I0J200D01*
G01X433819Y1122519D01*
G02X433760Y1122661I141J142D01*
G01Y1124884D01*
X433643Y1125001D01*
X433616D01*
X432984Y1125633D01*
G03X432842Y1125692I-142J-141D01*
G01X429473D01*
G03X429331Y1125633I0J-200D01*
G01X428606Y1124908D01*
G02X428464Y1124849I-142J141D01*
G01X420812D01*
X420739Y1124819D01*
X420731Y1124811D01*
Y1120677D01*
G03X420790Y1120535I200J0D01*
G01X420793Y1120532D01*
G03X420935Y1120473I142J141D01*
G01X425159D01*
G02X425301Y1120414I0J-200D01*
G01X425397Y1120318D01*
G03X425539Y1120259I142J141D01*
G01X427722D01*
G02X427864Y1120200I0J-200D01*
G01X427936Y1120128D01*
G02X427995Y1119986I-141J-142D01*
G01Y1119595D01*
G02X427937Y1119453I-200J-1D01*
G01X427831Y1119347D01*
G02X427689Y1119288I-142J141D01*
G01X425296D01*
G03X425154Y1119229I0J-200D01*
G01X424354Y1118429D01*
G03X424295Y1118287I141J-142D01*
G01Y1115480D01*
G03X424354Y1115338I200J0D01*
G01X424718Y1114974D01*
G03X424860Y1114915I142J141D01*
G01X427848D01*
X427853Y1114910D01*
Y1114100D01*
X427823Y1114027D01*
X427806Y1114010D01*
X424900D01*
G03X424758Y1113951I0J-200D01*
G01X424354Y1113547D01*
G03X424295Y1113405I141J-142D01*
G01Y1113045D01*
G02X424236Y1112903I-200J0D01*
G01X424176Y1112843D01*
G02X424034Y1112784I-142J141D01*
G01X417240D01*
X417217Y1112807D01*
Y1121516D01*
G03X417158Y1121658I-200J0D01*
G01X416821Y1121995D01*
G03X416679Y1122054I-142J-141D01*
G01X404779D01*
G03X404637Y1121995I0J-200D01*
G01X404594Y1121952D01*
G02X404452Y1121893I-142J141D01*
G01X402400D01*
G02X402258Y1121952I0J200D01*
G01X401691Y1122519D01*
G02X401632Y1122661I141J142D01*
G01Y1133251D01*
G02X401666Y1133364I200J1D01*
G03Y1148684I-11313J7660D01*
G02X401632Y1148797I166J112D01*
G01Y1155403D01*
G02X401691Y1155545I200J0D01*
G01X402266Y1156120D01*
G02X402408Y1156179I142J-141D01*
G37*
G36*
G01X398218Y1213880D02*
X448003D01*
X454132Y1207751D01*
X473528D01*
X479657Y1213880D01*
X529237D01*
X529554Y1213563D01*
Y1196392D01*
X529269Y1196107D01*
X471047D01*
X470430Y1196724D01*
Y1200705D01*
X469469Y1201666D01*
X457102D01*
X456352Y1200916D01*
Y1196107D01*
X397845D01*
X397228Y1196724D01*
Y1212890D01*
X398218Y1213880D01*
G37*
G36*
G01X404602Y1351568D02*
G03I-621J0D01*
G37*
G36*
G01X409558D02*
G03I-621J0D01*
G37*
G36*
G01X397983Y1400800D02*
X418555D01*
X418588Y1400788D01*
G03X419100Y1400698I512J1411D01*
G03X419282Y1400709I1J1502D01*
G01X419328Y1400715D01*
X419415Y1400685D01*
X420241Y1399859D01*
G02X420300Y1399717I-141J-142D01*
G01Y1397583D01*
G02X420241Y1397441I-200J0D01*
G01X419959Y1397159D01*
G02X419817Y1397100I-142J141D01*
G01X417583D01*
G03X417441Y1397041I0J-200D01*
G01X417059Y1396659D01*
G03X417000Y1396517I141J-142D01*
G01Y1394697D01*
X416992Y1394669D01*
G03X416928Y1394237I1438J-434D01*
G03X416992Y1393805I1502J2D01*
G01X417000Y1393777D01*
Y1392883D01*
G03X417059Y1392741I200J0D01*
G01X417541Y1392259D01*
G03X417683Y1392200I142J141D01*
G01X421317D01*
G02X421459Y1392141I0J-200D01*
G01X422041Y1391559D01*
G02X422100Y1391417I-141J-142D01*
G01Y1388483D01*
G02X422041Y1388341I-200J0D01*
G01X421859Y1388159D01*
G02X421717Y1388100I-142J141D01*
G01X416083D01*
G02X415941Y1388159I0J200D01*
G01X415459Y1388641D01*
G02X415400Y1388783I141J142D01*
G01Y1390717D01*
G03X415341Y1390859I-200J0D01*
G01X414359Y1391841D01*
G03X414217Y1391900I-142J-141D01*
G01X401183D01*
G03X401041Y1391841I0J-200D01*
G01X400259Y1391059D01*
G03X400200Y1390917I141J-142D01*
G01Y1389083D01*
G02X400141Y1388941I-200J0D01*
G01X399759Y1388559D01*
G02X399617Y1388500I-142J141D01*
G01X395483D01*
G02X395341Y1388559I0J200D01*
G01X394759Y1389141D01*
G02X394700Y1389283I141J142D01*
G01Y1391417D01*
G02X394759Y1391559I200J0D01*
G01X397041Y1393841D01*
G03X397100Y1393983I-141J142D01*
G01Y1399917D01*
G02X397159Y1400059I200J0D01*
G01X397841Y1400741D01*
G02X397983Y1400800I142J-141D01*
G37*
G36*
G01X400156Y1550922D02*
X413717D01*
G02X413859Y1550863I0J-200D01*
G01X413964Y1550758D01*
G02X414023Y1550616I-141J-142D01*
G01Y1537500D01*
G02X413947Y1537344I-200J1D01*
G01X413665Y1537120D01*
X413577Y1537100D01*
X413532Y1537111D01*
G03X412902Y1537184I-631J-2694D01*
G03X411984Y1537027I1J-2767D01*
G02X411851I-66J188D01*
G03X410933Y1537184I-919J-2610D01*
G03X409637Y1536861I1J-2767D01*
G01X409615Y1536850D01*
X409568Y1536838D01*
X408361D01*
X408314Y1536850D01*
X408292Y1536861D01*
G03X406996Y1537184I-1297J-2444D01*
G03X406078Y1537027I1J-2767D01*
G02X405946I-66J189D01*
G03X405028Y1537184I-919J-2610D01*
G03X404110Y1537027I1J-2767D01*
G02X403977I-66J188D01*
G03X403059Y1537184I-919J-2610D01*
G03X402141Y1537027I1J-2767D01*
G02X402008I-67J188D01*
G03X401090Y1537184I-919J-2610D01*
G03X400381Y1537091I2J-2767D01*
G01X400336Y1537079D01*
X400246Y1537097D01*
X399957Y1537319D01*
G02X399879Y1537478I122J159D01*
G01Y1550645D01*
G02X399938Y1550787I200J0D01*
G01X400014Y1550863D01*
G02X400156Y1550922I142J-141D01*
G37*
G36*
G01X395891Y1540463D02*
X398781D01*
X398854Y1540433D01*
X398878Y1540410D01*
Y1536552D01*
G03X398936Y1536411I200J0D01*
G01X398943Y1536404D01*
X398973Y1536331D01*
Y1536235D01*
X398951Y1536171D01*
X398929Y1536145D01*
G03X398324Y1534417I2161J-1727D01*
G01Y1534067D01*
G02X398124Y1533867I-200J0D01*
G01X394153D01*
G02X394011Y1533926I0J200D01*
G01X393505Y1534432D01*
G02X393446Y1534574I141J142D01*
G01Y1538018D01*
G02X393505Y1538160I200J0D01*
G01X395749Y1540404D01*
G02X395891Y1540463I142J-141D01*
G37*
G36*
G01X419076Y453904D02*
Y456122D01*
Y456569D01*
X418973Y456672D01*
X418526D01*
X410101D01*
X409897Y456468D01*
Y453598D01*
X410141Y453354D01*
X418526D01*
X419076Y453904D01*
G37*
G36*
G01X422264Y447997D02*
Y464238D01*
X422121Y464381D01*
X420310D01*
X420147Y464218D01*
Y453126D01*
Y452381D01*
X421124Y451404D01*
Y448058D01*
X421185Y447997D01*
X421218D01*
X422264D01*
G37*
G36*
G01X412365Y504100D02*
X443979D01*
X444014Y504065D01*
Y495162D01*
X443981Y495129D01*
X443859D01*
X443858Y495130D01*
X442058D01*
X442047Y495119D01*
X441310D01*
X439574Y493383D01*
Y492646D01*
Y491316D01*
X442255Y488635D01*
X467952D01*
X468805Y487782D01*
Y471500D01*
X468457Y471152D01*
X465367D01*
X465207Y471312D01*
Y474758D01*
X464059Y475906D01*
X434108D01*
X426831Y483183D01*
X419787D01*
X411861Y491109D01*
X411749D01*
X410725Y492133D01*
Y502460D01*
X412365Y504100D01*
G37*
G36*
G01X439497Y505169D02*
X412547D01*
X411159Y506557D01*
Y516979D01*
X412263Y518083D01*
X442807D01*
X443807Y517083D01*
Y506708D01*
Y505573D01*
X443403Y505169D01*
X442268D01*
X439497D01*
G37*
G36*
G01X470004Y540990D02*
X417225D01*
X416401Y540166D01*
Y527560D01*
X417471Y526490D01*
X469414D01*
X470804Y527880D01*
Y540390D01*
X470204Y540990D01*
X470004D01*
G37*
G36*
G01X444751Y617175D02*
X445132Y617556D01*
Y621314D01*
X445392Y621574D01*
X448823D01*
X449190Y621207D01*
Y620701D01*
Y603687D01*
Y602087D01*
X448704Y601601D01*
X423704D01*
X423216Y602089D01*
Y603268D01*
Y617088D01*
X430806Y624678D01*
Y631460D01*
X431076Y631730D01*
X431616D01*
X431996Y631350D01*
Y618300D01*
X433121Y617175D01*
X433126D01*
X444751D01*
G37*
G36*
G01X420485Y626868D02*
X428496D01*
X428666Y626698D01*
Y625318D01*
X428056Y624708D01*
X420459D01*
X420278Y624889D01*
Y626661D01*
X420485Y626868D01*
G37*
G36*
G01X435676Y621118D02*
Y619629D01*
X435461Y619414D01*
X433456D01*
X433146Y619724D01*
Y632680D01*
X431699Y634127D01*
X429844Y635982D01*
Y643299D01*
X426476Y646667D01*
Y661365D01*
X419142Y668699D01*
Y678870D01*
Y688442D01*
Y693681D01*
X420882Y695421D01*
X451323D01*
X452811Y693933D01*
Y693384D01*
Y684189D01*
Y678689D01*
Y669674D01*
X441756Y658619D01*
Y648942D01*
Y648207D01*
Y646582D01*
X440213Y645039D01*
X438588D01*
X437780Y644231D01*
X435642Y642093D01*
X434368Y640819D01*
Y639342D01*
X434366Y639340D01*
Y623790D01*
Y622675D01*
X434370Y622672D01*
Y622424D01*
X435676Y621118D01*
G37*
G36*
G01X442836Y703199D02*
X425786D01*
X425088Y703897D01*
Y713292D01*
X425495Y713699D01*
X442336D01*
X443336Y712699D01*
Y710699D01*
Y703699D01*
X442836Y703199D01*
G37*
G36*
G01X410515Y836663D02*
X417337D01*
X418010Y835990D01*
Y830582D01*
Y828528D01*
X417831Y828349D01*
X417517Y828035D01*
X410200D01*
X409886Y828349D01*
X409527Y828708D01*
Y830841D01*
Y836406D01*
X409784Y836663D01*
X410515D01*
G37*
G36*
G01X420289Y881689D02*
X420491Y881891D01*
X429396D01*
X430179Y882674D01*
Y910673D01*
X431345Y911839D01*
X449311D01*
X449388Y911762D01*
X453121D01*
X454522Y910361D01*
Y842465D01*
X453571Y841514D01*
X448671D01*
X433326D01*
X421142D01*
X420289Y842367D01*
Y881689D01*
G37*
G36*
G01X428540Y882891D02*
X420529D01*
X420359Y883061D01*
Y884441D01*
X420969Y885051D01*
X428566D01*
X428747Y884870D01*
Y883098D01*
X428540Y882891D01*
G37*
G36*
G01X411180Y1099832D02*
X411186Y1099838D01*
G02X411328Y1099897I142J-141D01*
G01X428684D01*
G02X428826Y1099838I0J-200D01*
G01X428887Y1099777D01*
G02X428946Y1099635I-141J-142D01*
G01Y1097686D01*
G02X428746Y1097486I-200J0D01*
G01X411669D01*
G02X411528Y1097545I1J200D01*
G01X411238Y1097835D01*
G02X411180Y1097976I142J141D01*
G01Y1099832D01*
G37*
G36*
G01X427468Y1565662D02*
X438686D01*
G02X438827Y1565603I-1J-200D01*
G01X441113Y1563317D01*
G02X441172Y1563176I-141J-142D01*
G01Y1560885D01*
G03X441187Y1560808I200J-1D01*
G01X441216Y1560740D01*
G02X441231Y1560663I-185J-76D01*
G01Y1553142D01*
G03X441290Y1553000I200J0D01*
G01X441329Y1552961D01*
G02X441331Y1552959I-140J-142D01*
G02X441388Y1552819I-143J-140D01*
G01Y1548445D01*
X441358Y1548371D01*
X441329Y1548343D01*
X432781Y1539795D01*
G02X432639Y1539736I-142J141D01*
G01X422485D01*
G02X422352Y1539795I9J200D01*
G01X422128Y1540020D01*
X421804Y1540344D01*
G02X421760Y1540562I141J142D01*
G01X421784Y1540619D01*
X421884Y1540686D01*
X425829D01*
G02X425931Y1540657I-2J-200D01*
G03X426701Y1540445I769J1290D01*
G03X427950Y1541113I0J1502D01*
G02X428080Y1541199I167J-111D01*
G03X428476Y1541409I-143J748D01*
G01X430582Y1543515D01*
G03X430748Y1543762I-537J540D01*
G01X432445Y1547859D01*
G03X432502Y1548150I-704J289D01*
G01Y1548708D01*
G02X432702Y1548908I200J0D01*
G01X433034D01*
G03X433234Y1549108I-1J201D01*
G01Y1551208D01*
G03X433034Y1551408I-201J0D01*
G01X432610D01*
G02X432410Y1551608I0J200D01*
G01Y1552039D01*
G03X432187Y1552577I-760J0D01*
G01X431574Y1553191D01*
G02X431516Y1553332I142J141D01*
G01Y1556903D01*
G02X431574Y1557044I200J0D01*
G01X432787Y1558257D01*
G02X432928Y1558316I142J-141D01*
G01X436070D01*
G03X436572Y1558817I0J502D01*
G01Y1562417D01*
G03X436070Y1562918I-501J0D01*
G01X432070D01*
G03X431568Y1562417I0J-502D01*
G01Y1559275D01*
G02X431510Y1559134I-200J0D01*
G01X430216Y1557839D01*
G03X430174Y1557795I529J-547D01*
G01X430150Y1557766D01*
X430088Y1557732D01*
X429753Y1557684D01*
X429683Y1557699D01*
X429652Y1557719D01*
G03X429378Y1557800I-273J-420D01*
G01X425378D01*
G03X424876Y1557299I0J-502D01*
G01Y1557160D01*
G02X424676Y1556960I-199J0D01*
G01X423171D01*
G03X422633Y1556736I1J-761D01*
G01X422133Y1556236D01*
G03X421910Y1555698I537J-538D01*
G01Y1553511D01*
G03X422133Y1552973I760J0D01*
G01X423040Y1552066D01*
G03X423578Y1551842I539J537D01*
G01X425926D01*
G02X426126Y1551642I0J-200D01*
G01Y1549162D01*
G03X426326Y1548962I200J0D01*
G01X426838D01*
G02X427038Y1548762I-1J-201D01*
G01Y1547822D01*
G02X426838Y1547622I-200J0D01*
G01X425390D01*
G02X425190Y1547822I0J200D01*
G01Y1547858D01*
X424137D01*
G03X423247Y1546961I0J-890D01*
G01X423248D01*
Y1546086D01*
G02X423048Y1545886I-200J0D01*
G01X422326D01*
G02X422224Y1545915I2J200D01*
G03X422194Y1545932I-756J-1298D01*
G01X422171Y1545945D01*
X422130Y1545985D01*
G03X421989Y1546044I-142J-141D01*
G01X421947D01*
X421917Y1546054D01*
G03X421454Y1546127I-463J-1429D01*
G03X421272Y1546116I-1J-1502D01*
G01X421226Y1546110D01*
X421140Y1546140D01*
X419758Y1547522D01*
G02X419699Y1547664I141J142D01*
G01Y1557810D01*
G02X419758Y1557952I200J0D01*
G01X421623Y1559817D01*
G03X421667Y1559882I-140J142D01*
G01X421711Y1559988D01*
X421739Y1560016D01*
X427326Y1565603D01*
G02X427468Y1565662I142J-141D01*
G37*
G36*
G01X429378Y1553198D02*
G03X429674Y1553294I0J504D01*
G01X429700Y1553314D01*
X429760Y1553333D01*
X429792D01*
G02X429992Y1553133I0J-200D01*
G01Y1552934D01*
G03X430216Y1552396I761J1D01*
G01X430589Y1552022D01*
G02X430647Y1551872I-142J-141D01*
G01X430633Y1551535D01*
X430596Y1551461D01*
X430564Y1551434D01*
G03X430247Y1550747I573J-681D01*
G01X430248D01*
Y1549569D01*
X430247D01*
G03X430845Y1548722I890J-6D01*
G01X430906Y1548701D01*
X430980Y1548597D01*
Y1548341D01*
G02X430964Y1548265I-200J2D01*
G01X429414Y1544521D01*
G02X429370Y1544456I-184J77D01*
G01X427926Y1543012D01*
X427767Y1543008D01*
X427708Y1543062D01*
G03X426701Y1543449I-1006J-1115D01*
G03X425931Y1543237I-1J-1502D01*
G02X425829Y1543208I-104J171D01*
G01X424920D01*
G02X424729Y1543351I1J200D01*
G01X424702Y1543441D01*
G02X424766Y1543653I191J58D01*
G03X424854Y1543733I-804J972D01*
G01X425541Y1544420D01*
G03X425865Y1544976I-892J892D01*
G01X425883Y1545042D01*
X425989Y1545122D01*
X427058D01*
G02X427258Y1544922I0J-200D01*
G01Y1544886D01*
X428311D01*
G03X429201Y1545783I0J890D01*
G01X429200D01*
Y1546961D01*
X429201D01*
G03X428678Y1547778I-890J6D01*
G01X428624Y1547802D01*
X428560Y1547901D01*
Y1548722D01*
X428614Y1548815D01*
X428662Y1548842D01*
G03X429113Y1549622I-439J774D01*
G01X429112D01*
Y1550800D01*
X429113D01*
G03X428626Y1551600I-890J6D01*
G01X428575Y1551625D01*
X428516Y1551721D01*
Y1551945D01*
G03X428293Y1552483I-760J0D01*
G01X427921Y1552856D01*
G02X427877Y1553074I141J142D01*
G01X427901Y1553131D01*
X428000Y1553198D01*
X429378D01*
G37*
G36*
G01X428402Y464026D02*
G03I-620J0D01*
G37*
G36*
G01X436127Y625762D02*
Y626729D01*
X436286Y626888D01*
X439456D01*
X439668Y626675D01*
Y625677D01*
X443986Y621359D01*
Y619653D01*
X443769Y619436D01*
X442453D01*
X436127Y625762D01*
G37*
G36*
G01X465470Y115094D02*
X466526D01*
X466553Y115067D01*
Y111227D01*
G02X466494Y111085I-200J0D01*
G01X464864Y109456D01*
G03X464805Y109314I141J-142D01*
G01Y106183D01*
G03X464864Y106041I200J0D01*
G01X464987Y105918D01*
G03X465129Y105859I142J141D01*
G01X475835D01*
G03X475977Y105918I0J200D01*
G01X476053Y105994D01*
G03X476112Y106136I-141J142D01*
G01Y109681D01*
G03X476053Y109823I-200J0D01*
G01X475819Y110057D01*
G02X475760Y110199I141J142D01*
G01Y114552D01*
X475790Y114625D01*
X475801Y114636D01*
X481385D01*
X482727D01*
X482791Y114572D01*
X482907Y114456D01*
G02X482966Y114314I-141J-142D01*
G01Y105226D01*
G02X482907Y105084I-200J0D01*
G01X482236Y104413D01*
X482153Y104383D01*
X482108Y104388D01*
G03X481926Y104396I-174J-1893D01*
G01X479344D01*
X478058D01*
X477312Y103650D01*
Y101528D01*
X476980Y101196D01*
X465449D01*
X465425Y101202D01*
X458245D01*
X457550Y101897D01*
Y102887D01*
Y114049D01*
G02X457609Y114191I200J0D01*
G01X457731Y114313D01*
G02X457873Y114372I142J-141D01*
G01X464582D01*
G03X464724Y114431I0J200D01*
G01X465328Y115035D01*
G02X465470Y115094I142J-141D01*
G37*
G36*
G01X457732Y120851D02*
X463149D01*
G02X463291Y120792I0J-200D01*
G01X464912Y119171D01*
G03X465054Y119112I142J141D01*
G01X466569D01*
G02X466711Y119053I0J-200D01*
G01X467184Y118580D01*
G02X467243Y118438I-141J-142D01*
G01Y116276D01*
G02X467120Y116091I-200J0D01*
G01X467063Y116068D01*
X466945Y116091D01*
X466941Y116096D01*
X465469D01*
G03X464655Y115777I1J-1202D01*
G02X464519Y115724I-136J147D01*
G01X457673D01*
G02X457531Y115783I0J200D01*
G01X457516Y115798D01*
X457486Y115871D01*
Y120605D01*
G02X457545Y120747I200J0D01*
G01X457590Y120792D01*
G02X457732Y120851I142J-141D01*
G37*
G36*
G01X454071Y370694D02*
G03I-608J0D01*
G37*
G36*
G01X442502Y427220D02*
Y454981D01*
X442829Y455308D01*
X446736D01*
X447306Y454738D01*
Y427163D01*
X447078Y426935D01*
X446532D01*
X442787D01*
X442502Y427220D01*
G37*
G36*
G01X455454Y974622D02*
G03I-639J0D01*
G37*
G36*
G01X454763Y1003266D02*
X455082D01*
G02X455142Y1003257I1J-200D01*
G01X455224Y1003231D01*
X455248Y1003216D01*
G03X456209Y1002928I962J1463D01*
G01X456210D01*
G03X456806Y1003032I1J1752D01*
G01X456821Y1003038D01*
X456856Y1003044D01*
G02X457020Y1003001I36J-197D01*
G01X457053Y1002973D01*
X457091Y1002893D01*
Y1001349D01*
G02X457032Y1001207I-200J0D01*
G01X456408Y1000583D01*
X456380Y1000554D01*
X456306Y1000524D01*
X456218Y1000436D01*
Y1000394D01*
X456159Y1000335D01*
X454650Y998825D01*
G03X454591Y998683I141J-142D01*
G01Y993849D01*
G02X454532Y993707I-200J0D01*
G01X454150Y993325D01*
X454122Y993296D01*
X454048Y993266D01*
X448674D01*
G02X448532Y993325I0J200D01*
G01X448150Y993707D01*
X448121Y993735D01*
X448091Y993809D01*
Y1001683D01*
G02X448150Y1001825I200J0D01*
G01X449532Y1003207D01*
G02X449674Y1003266I142J-141D01*
G01X450518D01*
G03X450591Y1003264I78J1500D01*
G03X450664Y1003266I-5J1502D01*
G01X451777D01*
X451875Y1003202D01*
X451900Y1003148D01*
G03X454640I1370J615D01*
G01X454665Y1003202D01*
X454763Y1003266D01*
G37*
G36*
G01X458360Y1000424D02*
Y1002180D01*
X458352Y1002188D01*
Y1003129D01*
X458390Y1003167D01*
X458936D01*
X461211D01*
X462535Y1004491D01*
Y1006792D01*
Y1007854D01*
X465122Y1010441D01*
X466959D01*
X467000Y1010400D01*
Y1010016D01*
X466900Y1009916D01*
X465445D01*
X464079Y1008550D01*
X464035Y1008506D01*
Y1006706D01*
Y1003869D01*
X461596Y1001430D01*
X460567D01*
X460360Y1001223D01*
Y1000687D01*
X461523Y999524D01*
X462214D01*
X464078Y1001387D01*
G02X464785Y1001680I707J-706D01*
G02X465785Y1000680I0J-1000D01*
G02X465492Y999973I-999J0D01*
G01X463317Y997798D01*
Y995100D01*
X462172Y993955D01*
X457665D01*
X457220Y994400D01*
Y999522D01*
X457458D01*
X458360Y1000424D01*
G37*
G36*
G01X452510Y1301067D02*
G03I-621J0D01*
G37*
G36*
G01Y1306023D02*
G03I-621J0D01*
G37*
G36*
G01X468835Y119235D02*
X472281D01*
X475117Y122071D01*
X481164D01*
X481534Y121701D01*
Y116118D01*
X481053Y115637D01*
X471379D01*
X469023D01*
X468675Y115985D01*
Y119075D01*
X468835Y119235D01*
G37*
G36*
G01X467407Y210785D02*
X476847D01*
X478648Y208984D01*
X479744Y207888D01*
Y187037D01*
X478797Y186090D01*
X468025D01*
X466581Y187534D01*
Y209959D01*
X467407Y210785D01*
G37*
G36*
G01X480036Y223195D02*
X490061D01*
X490091Y223225D01*
X492614D01*
X495251Y225862D01*
X504193D01*
X504535Y225520D01*
Y213126D01*
X503823Y212414D01*
X496406D01*
X493552Y215268D01*
X490112D01*
X479135D01*
X477571D01*
X477125Y214822D01*
Y213258D01*
X475852Y211985D01*
X475440D01*
X474663D01*
X467036D01*
X466376Y212645D01*
Y226569D01*
X467052Y227245D01*
X477986D01*
X479746Y225485D01*
Y223485D01*
X480036Y223195D01*
G37*
G36*
G01X463591Y464484D02*
Y465626D01*
G02X463650Y465768I200J0D01*
G01X465271Y467389D01*
G03X465330Y467531I-141J142D01*
G01Y469046D01*
G02X465389Y469188I200J0D01*
G01X465862Y469661D01*
G02X466004Y469720I142J-141D01*
G01X468166D01*
G02X468351Y469597I0J-200D01*
G01X468374Y469540D01*
X468351Y469422D01*
X468346Y469418D01*
Y467946D01*
G03X468665Y467132I1202J1D01*
G02X468718Y466996I-147J-136D01*
G01Y460578D01*
Y456711D01*
X468102Y456095D01*
X460771D01*
X460002Y456864D01*
Y460895D01*
X463591Y464484D01*
G37*
G36*
G01X469348Y467947D02*
Y469003D01*
X469375Y469030D01*
X473215D01*
G02X473357Y468971I0J-200D01*
G01X474986Y467341D01*
G03X475128Y467282I142J141D01*
G01X478259D01*
G03X478401Y467341I0J200D01*
G01X478524Y467464D01*
G03X478583Y467606I-141J142D01*
G01Y478312D01*
G03X478524Y478454I-200J0D01*
G01X478448Y478530D01*
G03X478306Y478589I-142J-141D01*
G01X474761D01*
G03X474619Y478530I0J-200D01*
G01X474385Y478296D01*
G02X474243Y478237I-142J141D01*
G01X469890D01*
X469817Y478267D01*
X469806Y478278D01*
Y483862D01*
Y485204D01*
X469870Y485268D01*
X469986Y485384D01*
G02X470128Y485443I142J-141D01*
G01X479216D01*
X481711D01*
X483246Y483908D01*
Y479457D01*
Y467926D01*
X483240Y467902D01*
Y460722D01*
X482545Y460027D01*
X481555D01*
X470393D01*
G02X470251Y460086I0J200D01*
G01X470129Y460208D01*
G02X470070Y460350I141J142D01*
G01Y467059D01*
G03X470011Y467201I-200J0D01*
G01X469407Y467805D01*
G02X469348Y467947I141J142D01*
G37*
G36*
G01X468657Y1024441D02*
X469139D01*
X482246D01*
X482585Y1024102D01*
Y1022980D01*
Y1010435D01*
X482385Y1010235D01*
X468485D01*
X468385Y1010335D01*
X468353Y1010367D01*
Y1021367D01*
Y1024137D01*
X468657Y1024441D01*
G37*
G36*
G01X499776Y1120863D02*
X502465D01*
X502669Y1120659D01*
X513355D01*
X513371Y1120643D01*
Y1112626D01*
X513312Y1112567D01*
X507436D01*
X507262Y1112393D01*
Y1107201D01*
X506743Y1106682D01*
Y1101290D01*
X507865Y1100168D01*
Y1073191D01*
X507311Y1072637D01*
X468114D01*
X467282Y1073469D01*
Y1104852D01*
G03X467284Y1104896I-1498J90D01*
G03X467282Y1104940I-1500J-46D01*
G01Y1120497D01*
X467648Y1120863D01*
X470337D01*
X470541Y1120659D01*
X481227D01*
X481243Y1120643D01*
Y1112626D01*
X481184Y1112567D01*
X475308D01*
X475134Y1112393D01*
Y1107309D01*
X474622Y1106797D01*
Y1101558D01*
X475765Y1100415D01*
Y1097323D01*
X476603Y1096485D01*
X494977D01*
X499410Y1100918D01*
Y1120497D01*
X499776Y1120863D01*
G37*
G36*
G01X486822Y1254968D02*
X537714D01*
G03X550507Y1234560I36104J8418D01*
G01Y1159110D01*
G02X550448Y1158968I-200J0D01*
G01X548795Y1157315D01*
G02X548653Y1157256I-142J141D01*
G01X467571D01*
X467259Y1157568D01*
Y1190849D01*
X470397Y1193987D01*
X530235D01*
X530942Y1194694D01*
Y1214153D01*
X529921Y1215174D01*
X487072D01*
X486084Y1216162D01*
Y1254230D01*
X486822Y1254968D01*
G37*
G36*
G01X530406Y1256342D02*
X485751D01*
X484953Y1255544D01*
Y1215751D01*
X484531Y1215329D01*
X480733D01*
X468004D01*
X465320D01*
X464803Y1215846D01*
Y1273497D01*
X465540Y1274234D01*
X467941D01*
X533764D01*
X534784Y1273214D01*
Y1271068D01*
Y1268253D01*
Y1256968D01*
X534158Y1256342D01*
X530406D01*
G37*
G36*
G01X480766Y186998D02*
Y210417D01*
X478758Y212425D01*
Y214067D01*
X479150Y214459D01*
X487572D01*
X487780Y214251D01*
Y212947D01*
X487728Y212895D01*
Y212503D01*
Y211843D01*
X488189Y211382D01*
X488849D01*
X493075D01*
X494403Y210054D01*
Y205828D01*
Y187369D01*
X493248Y186214D01*
X481550D01*
X480766Y186998D01*
G37*
G36*
G01X483104Y444517D02*
G03I-620J0D01*
G37*
G36*
G01X496809Y592103D02*
X483602D01*
X483317Y591818D01*
Y556112D01*
Y555516D01*
X483704Y555129D01*
X484055Y554778D01*
X492162D01*
X492741Y554199D01*
X497360D01*
X498358Y555197D01*
Y590554D01*
X496809Y592103D01*
G37*
G36*
G01X488043Y614747D02*
X486252D01*
X486130Y614625D01*
Y600460D01*
X486985Y599605D01*
X492826D01*
X493071Y599850D01*
Y603288D01*
X492826Y603533D01*
X489244D01*
X488293Y604484D01*
Y614671D01*
X488217Y614747D01*
X488043D01*
G37*
G36*
G01X492475Y614714D02*
X490257D01*
X489810D01*
X489707Y614611D01*
Y614164D01*
Y605739D01*
X489911Y605535D01*
X492781D01*
X493025Y605779D01*
Y614164D01*
X492475Y614714D01*
G37*
G36*
G01X498298Y617902D02*
X482141D01*
X481998Y617759D01*
Y615948D01*
X482161Y615785D01*
X493253D01*
X493998D01*
X494975Y616762D01*
X498262D01*
X498400Y616900D01*
Y617800D01*
X498298Y617902D01*
G37*
G36*
G01X490377Y1058603D02*
X489834Y1059146D01*
Y1069654D01*
X490897Y1070717D01*
X506812D01*
X507781Y1069748D01*
Y1059792D01*
Y1059119D01*
Y1057984D01*
X506833Y1057036D01*
X491944D01*
X491213Y1057767D01*
X490377Y1058603D01*
G37*
G36*
G01X476766Y1099832D02*
X476773Y1099838D01*
G02X476915Y1099897I142J-141D01*
G01X494271D01*
G02X494413Y1099838I0J-200D01*
G01X494474Y1099777D01*
G02X494533Y1099635I-141J-142D01*
G01Y1097686D01*
G02X494333Y1097486I-200J0D01*
G01X477256D01*
G02X477115Y1097545I1J200D01*
G01X476825Y1097835D01*
G02X476766Y1097976I141J142D01*
G01Y1099832D01*
G37*
G36*
G01X496680Y86514D02*
X505395D01*
X505748Y86161D01*
Y73377D01*
X505302Y72931D01*
X496904D01*
X496569Y73266D01*
Y86403D01*
X496680Y86514D01*
G37*
G36*
G01X507100Y488854D02*
Y499374D01*
Y501186D01*
X507687Y501773D01*
X514519D01*
X515027Y501265D01*
Y499252D01*
Y487471D01*
Y486284D01*
X515726Y485585D01*
X516913D01*
X518310Y484188D01*
Y483142D01*
Y475515D01*
X517650Y474855D01*
X504856D01*
X504208Y475503D01*
Y487623D01*
X504954Y488369D01*
X506615D01*
X507100Y488854D01*
G37*
G36*
G01X505196Y545147D02*
Y533484D01*
X508479Y530201D01*
Y529803D01*
Y518852D01*
G02X508420Y518710I-200J0D01*
G01X508372Y518662D01*
G03X508313Y518520I141J-142D01*
G01Y504632D01*
G02X508254Y504490I-200J0D01*
G01X507175Y503411D01*
G02X507033Y503352I-142J141D01*
G01X493546D01*
G02X493404Y503411I0J200D01*
G01X492738Y504077D01*
G02X492679Y504219I141J142D01*
G01Y532166D01*
X494784Y534271D01*
Y534788D01*
Y535061D01*
X494812Y535089D01*
X497153D01*
X497269Y535205D01*
Y535259D01*
Y544824D01*
Y545347D01*
X497608Y545686D01*
X498131D01*
X504657D01*
X505196Y545147D01*
G37*
G36*
G01X499878Y615406D02*
X514722D01*
X515251Y614877D01*
Y607251D01*
X514500Y606500D01*
Y594000D01*
X515251Y593249D01*
Y573133D01*
X518750Y569634D01*
X525050D01*
X525872Y570456D01*
X527881Y572466D01*
Y577231D01*
X528429Y577779D01*
X529745D01*
X530740Y578774D01*
Y580708D01*
X531127Y581095D01*
Y583479D01*
X531192Y583544D01*
X531997D01*
X532034Y583507D01*
Y579964D01*
X532435Y579563D01*
Y579518D01*
X533728Y578225D01*
Y570737D01*
X531528Y568537D01*
Y556856D01*
X531557Y556827D01*
Y551391D01*
X533322Y549626D01*
X536649D01*
X537652Y548623D01*
Y536737D01*
X536904Y535989D01*
X510047D01*
X508039Y533981D01*
X506397D01*
X506005Y534373D01*
Y542795D01*
X506213Y543003D01*
X507517D01*
X507569Y542951D01*
X507961D01*
X508633D01*
X509062Y543380D01*
Y544052D01*
X509082Y544072D01*
Y548298D01*
X509076D01*
X508208Y549166D01*
X501083D01*
X499841Y550408D01*
Y554389D01*
X499823Y554407D01*
Y615351D01*
X499878Y615406D01*
G37*
G36*
G01X498888Y615416D02*
X497016D01*
X495524Y613924D01*
Y596533D01*
X495977Y596080D01*
X498697D01*
X498921Y596304D01*
Y615383D01*
X498888Y615416D01*
G37*
G36*
G01X516036Y621858D02*
X499478D01*
X499427Y621807D01*
Y616817D01*
X499512Y616732D01*
X516405D01*
X520832Y612305D01*
X540082D01*
X540691Y612914D01*
Y624584D01*
X539170Y626105D01*
X520283D01*
X516036Y621858D01*
G37*
G36*
G01X519159Y638140D02*
X491398D01*
X491071Y638467D01*
Y642374D01*
X491641Y642944D01*
X519216D01*
X519444Y642716D01*
Y642170D01*
Y638425D01*
X519159Y638140D01*
G37*
G36*
G01X492166Y843206D02*
G03I-639J0D01*
G37*
G36*
G01X524858Y89379D02*
X524956D01*
G02X525097Y89438I142J-141D01*
G01X539122D01*
G02X539264Y89379I0J-200D01*
G01X539266Y89376D01*
Y74039D01*
G03X539325Y73898I200J1D01*
G01X539372Y73851D01*
G02Y73568I-141J-141D01*
G01X539185Y73381D01*
G02X539043Y73322I-142J141D01*
G01X535228D01*
X535225Y73319D01*
X514880D01*
G02X514738Y73378I0J200D01*
G01X514670Y73446D01*
G02X514611Y73588I141J142D01*
G01Y86280D01*
G02X514670Y86422I200J0D01*
G01X514738Y86490D01*
G02X514880Y86549I142J-141D01*
G01X520191D01*
G03X520333Y86608I0J200D01*
G01X521166Y87441D01*
G03X521225Y87583I-141J142D01*
G01Y88917D01*
G02X521284Y89059I200J0D01*
G01X521604Y89379D01*
G02X521746Y89438I142J-141D01*
G01X524717D01*
G02X524858Y89379I-1J-200D01*
G37*
G36*
G01X512606Y176789D02*
X527033D01*
X527796Y176026D01*
Y174795D01*
X528559Y174032D01*
X531667D01*
X532254Y173445D01*
Y161423D01*
X531550Y160719D01*
X513251D01*
Y160720D01*
X511255D01*
X510494Y161481D01*
Y176203D01*
X511080Y176789D01*
X512606D01*
G37*
G36*
G01X539525Y219609D02*
X541167D01*
X541559Y219217D01*
Y210795D01*
X541351Y210587D01*
X540047D01*
X539995Y210639D01*
X539603D01*
X538795D01*
X538482Y210326D01*
Y209518D01*
Y204802D01*
X528013Y194333D01*
Y189191D01*
X531650Y185554D01*
X536415D01*
X536963Y185006D01*
Y183690D01*
X537958Y182695D01*
X539892D01*
X540279Y182308D01*
X542493D01*
X542671Y182130D01*
Y181714D01*
X542358Y181401D01*
X539148D01*
X538747Y181000D01*
X538702D01*
X537409Y179707D01*
X511850D01*
X510538Y181019D01*
Y216698D01*
X511441Y217601D01*
X537517D01*
X539525Y219609D01*
G37*
G36*
G01X537885Y234621D02*
Y221520D01*
X536084Y219719D01*
X534988Y218623D01*
X512147D01*
X510419Y220351D01*
Y252516D01*
X511730Y253827D01*
X533970D01*
X537885Y249912D01*
Y234621D01*
G37*
G36*
G01X512765Y277007D02*
X520194D01*
X532645D01*
X534502Y275150D01*
X537081D01*
X537356Y274875D01*
Y272398D01*
X536806Y271848D01*
X534262D01*
X534158Y271952D01*
X530478Y268272D01*
Y265554D01*
X527280Y262356D01*
X512696D01*
X512008Y263044D01*
Y276250D01*
X512765Y277007D01*
G37*
G36*
G01X515758Y299467D02*
X526042D01*
X530478Y295031D01*
Y278899D01*
X530237Y278658D01*
X513487D01*
X512215Y279930D01*
Y295924D01*
X515758Y299467D01*
G37*
G36*
G01X531229Y448919D02*
X525229D01*
X524145D01*
X522583D01*
X522330Y448666D01*
Y443698D01*
X523070Y442958D01*
X524701D01*
X531145D01*
X531729Y443542D01*
Y448419D01*
X531229Y448919D01*
G37*
G36*
G01X516855Y453982D02*
X514215D01*
X513556Y454641D01*
Y457485D01*
Y458933D01*
X513551Y458937D01*
Y459774D01*
X512830Y460495D01*
X508841D01*
X508125Y459779D01*
Y459195D01*
Y457910D01*
Y455716D01*
Y451556D01*
X508660Y451021D01*
X517445D01*
X517456Y451032D01*
Y453381D01*
X516855Y453982D01*
G37*
G36*
G01X621292Y554616D02*
X634114D01*
G02X634254Y554559I0J-200D01*
G01X634255Y554558D01*
X635477Y553336D01*
X635492Y553300D01*
G03X635762Y553030I463J193D01*
G01X635798Y553015D01*
X636120Y552693D01*
X636289Y552524D01*
X640791D01*
X640932Y552383D01*
Y551756D01*
Y551373D01*
G02X640873Y551231I-200J0D01*
G01X640788Y551146D01*
X640760Y551117D01*
X640686Y551087D01*
X635526D01*
G03X635384Y551028I0J-200D01*
G01X633270Y548914D01*
X633242Y548885D01*
X633168Y548855D01*
X631759D01*
G03X631617Y548796I0J-200D01*
G01X623908Y541087D01*
X623880Y541058D01*
X623806Y541028D01*
X613111D01*
X613099Y541029D01*
G03X612972Y541041I-321J-2722D01*
G01X612971D01*
G03X612785Y541048I-196J-2735D01*
G01X612783D01*
G03X612597Y541041I10J-2742D01*
G01X612596D01*
G03X612469Y541029I194J-2734D01*
G01X612457Y541028D01*
X611011D01*
X610999Y541029D01*
G03X610872Y541041I-321J-2722D01*
G01X610871D01*
G03X610685Y541048I-196J-2735D01*
G01X610683D01*
G03X610497Y541041I10J-2742D01*
G01X610496D01*
G03X610369Y541029I194J-2734D01*
G01X610357Y541028D01*
X593940D01*
G03X593798Y540969I0J-200D01*
G01X580234Y527405D01*
G03X580175Y527263I141J-142D01*
G01Y474821D01*
G02X580116Y474679I-200J0D01*
G01X556468Y451030D01*
G02X556326Y450971I-142J141D01*
G01X533708D01*
X533686Y450949D01*
G02X533544Y450890I-142J141D01*
G01X529883D01*
G02X529741Y450949I0J200D01*
G01X529719Y450971D01*
X527520D01*
Y450993D01*
X519202D01*
G02X519002Y451193I0J200D01*
G01Y453803D01*
G02X519202Y454003I200J0D01*
G01X521783D01*
G03X521925Y454062I0J200D01*
G01X524758Y456895D01*
G03X524817Y457037I-141J142D01*
G01Y462233D01*
G02X524874Y462373I200J0D01*
G01X524875Y462374D01*
X525614Y463113D01*
G03X525673Y463255I-141J142D01*
G01Y467488D01*
G02X525732Y467630I200J0D01*
G01X528155Y470053D01*
G02X528297Y470112I142J-141D01*
G01X542871D01*
G03X543013Y470171I0J200D01*
G01X545545Y472703D01*
G03X545604Y472845I-141J142D01*
G01Y487807D01*
G03X545545Y487949I-200J0D01*
G01X544320Y489174D01*
G03X544178Y489233I-142J-141D01*
G01X519949D01*
G03X519807Y489174I0J-200D01*
G01X517905Y487272D01*
X517877Y487243D01*
X517803Y487213D01*
X516228D01*
G02X516028Y487413I0J200D01*
G01Y495744D01*
G02X516100Y495897I200J-1D01*
G01X516369Y496123D01*
X516453Y496146D01*
X516497Y496138D01*
X516500Y496137D01*
X516501D01*
G03X516756Y496116I250J1480D01*
G03X517266Y496205I1J1501D01*
G02X517378Y496212I68J-188D01*
G03X517422Y496207I44J195D01*
G01X517709D01*
X518709D01*
X518913Y496411D01*
Y497411D01*
Y500592D01*
G02X518970Y500732I200J0D01*
G01X518971Y500733D01*
X519831Y501593D01*
G02X519833Y501595I142J-140D01*
G02X519973Y501652I140J-143D01*
G01X537704D01*
G03X537846Y501711I0J200D01*
G01X541433Y505298D01*
G03X541492Y505440I-141J142D01*
G01Y528321D01*
G02X541549Y528461I200J0D01*
G01X541550Y528462D01*
X564196Y551108D01*
G02X564198Y551110I142J-140D01*
G02X564338Y551167I140J-143D01*
G01X597747D01*
G02X597818Y551154I0J-200D01*
G01X597915Y551117D01*
X597942Y551095D01*
G03X599110Y550664I1169J1371D01*
G03X600278Y551095I-1J1802D01*
G01X600305Y551117D01*
X600402Y551154D01*
G02X600473Y551167I71J-187D01*
G01X614704D01*
G02X614772Y551155I0J-200D01*
G01X614862Y551123D01*
X614888Y551103D01*
G03X616130Y550671I1243J1571D01*
G03X617396Y551122I0J2002D01*
G01X617424Y551144D01*
X617487Y551167D01*
X617677D01*
G03X617819Y551226I0J200D01*
G01X621150Y554557D01*
G02X621152Y554559I142J-140D01*
G02X621292Y554616I140J-143D01*
G37*
G36*
G01X519510Y475886D02*
Y485326D01*
X521311Y487127D01*
X522407Y488223D01*
X543258D01*
X544205Y487276D01*
Y476504D01*
X542761Y475060D01*
X520336D01*
X519510Y475886D01*
G37*
G36*
G01X509679Y518969D02*
Y532070D01*
X511480Y533871D01*
X512576Y534967D01*
X535417D01*
X538860Y531524D01*
Y520887D01*
Y504757D01*
X537702Y503599D01*
X511288D01*
X509679Y505208D01*
Y518969D01*
G37*
G36*
G01X519932Y627231D02*
X539984D01*
X540920Y628167D01*
Y641266D01*
X540370Y641816D01*
X525757D01*
X524739Y640798D01*
Y633084D01*
X524231Y632576D01*
X520140D01*
X519589Y632025D01*
Y630928D01*
Y627574D01*
X519932Y627231D01*
G37*
G36*
G01X519384Y665867D02*
G03I-572J0D01*
G37*
G36*
G01X521488Y704864D02*
X527509D01*
G02X527651Y704805I0J-200D01*
G01X527942Y704514D01*
G02X528001Y704372I-141J-142D01*
G01Y694482D01*
G02X527942Y694340I-200J0D01*
G01X527574Y693972D01*
G02X527432Y693913I-142J141D01*
G01X517562D01*
G02X517420Y693972I0J200D01*
G01X517067Y694325D01*
G02X517008Y694467I141J142D01*
G01Y695264D01*
X517017Y695292D01*
G03Y696222I-1532J465D01*
G01X517008Y696250D01*
Y700800D01*
X517019Y700831D01*
G03X517106Y701351I-1515J521D01*
G03X517019Y701871I-1602J-1D01*
G01X517008Y701902D01*
Y703474D01*
G02X517067Y703616I200J0D01*
G01X518256Y704805D01*
G02X518398Y704864I142J-141D01*
G01X520780D01*
X520800Y704860D01*
G03X521134Y704824I338J1566D01*
G03X521468Y704860I-4J1602D01*
G01X521488Y704864D01*
G37*
G36*
G01X521359Y846133D02*
G03I-639J0D01*
G37*
G36*
G01X594744Y54588D02*
X623251D01*
X623486Y54353D01*
Y52826D01*
X623251Y52591D01*
X594744D01*
G03X588807Y46654I0J-5937D01*
G01Y7874D01*
G02X582933Y2000I-5874J0D01*
G01X535689D01*
G02X529815Y7874I0J5874D01*
G01Y46178D01*
X531812D01*
Y7874D01*
G03X535687Y3998I3876J0D01*
G01X582933D01*
G03X586810Y7874I0J3877D01*
G01Y46654D01*
G02X594744Y54588I7934J0D01*
G37*
G36*
G01X524709Y95055D02*
X539725D01*
X539745Y95035D01*
X543750D01*
X544463Y94322D01*
Y74773D01*
X543602Y73912D01*
X540991D01*
X540727D01*
X540268Y74371D01*
Y90663D01*
X540145Y90786D01*
X539439D01*
X536684D01*
X524946D01*
X524907Y90747D01*
X524630Y91024D01*
Y94976D01*
X524709Y95055D01*
G37*
G36*
G01X544620Y276354D02*
X562193D01*
X563019Y275528D01*
Y258570D01*
X561406Y256957D01*
Y232172D01*
X554885Y225651D01*
Y220921D01*
X552585Y218621D01*
X550585D01*
X550295Y218331D01*
Y205660D01*
X549708Y205073D01*
X542876D01*
X542368Y205581D01*
Y220421D01*
X539085Y223704D01*
Y234821D01*
X539251Y234987D01*
Y250246D01*
X542415Y253410D01*
X542451D01*
X544671Y255630D01*
Y268925D01*
X541662Y271934D01*
X539358D01*
X538842Y272450D01*
Y274738D01*
X539065Y274961D01*
X543227D01*
X544620Y276354D01*
G37*
G36*
G01X623961Y581389D02*
X627479Y577871D01*
X640110D01*
G02X640252Y577812I0J-200D01*
G01X640738Y577326D01*
G02X640797Y577184I-141J-142D01*
G01Y563277D01*
G02X640738Y563135I-200J0D01*
G01X640605Y563002D01*
G02X640463Y562943I-142J141D01*
G01X626276D01*
G02X626134Y563002I0J200D01*
G01X623320Y565816D01*
G03X623178Y565875I-142J-141D01*
G01X617463D01*
G02X617336Y565920I-1J200D01*
G03X614800I-1268J-1548D01*
G02X614673Y565875I-126J155D01*
G01X598011D01*
G03X597869Y565816I0J-200D01*
G01X596603Y564550D01*
G03X596544Y564408I141J-142D01*
G01Y558946D01*
G02X596485Y558804I-200J0D01*
G01X593850Y556169D01*
G02X593708Y556110I-142J141D01*
G01X559893D01*
G03X559751Y556051I0J-200D01*
G01X555806Y552106D01*
G02X555664Y552047I-142J141D01*
G01X534756D01*
G02X534614Y552106I0J200D01*
G01X533755Y552965D01*
G02X533696Y553107I141J142D01*
G01Y567243D01*
G02X533755Y567385I200J0D01*
G01X535251Y568881D01*
G02X535393Y568940I142J-141D01*
G01X538556D01*
G03X538698Y568999I0J200D01*
G01X539115Y569416D01*
G03X539174Y569558I-141J142D01*
G01Y572492D01*
G02X539233Y572634I200J0D01*
G01X539806Y573207D01*
G02X539948Y573266I142J-141D01*
G01X547230D01*
G03X547372Y573325I0J200D01*
G01X555206Y581159D01*
X555250D01*
X555421Y581330D01*
G02X555563Y581389I142J-141D01*
G01X556613Y582439D01*
X622911D01*
X623961Y581389D01*
G37*
G36*
G01X534958Y792043D02*
X534990Y792057D01*
X535390D01*
G02X535590Y791857I0J-200D01*
G01Y790082D01*
G02X535561Y789979I-200J1D01*
G03X535380Y789327I1080J-651D01*
G01Y784978D01*
G02X535321Y784837I-200J1D01*
G01X534707Y784223D01*
G03X534338Y783331I892J-891D01*
G01Y781242D01*
G02X534176Y781138I-176J96D01*
G01X534131D01*
X534014Y781022D01*
Y778840D01*
Y778756D01*
X534132Y778640D01*
X534676D01*
G02X534838Y778536I-14J-200D01*
G01Y778363D01*
G02X534779Y778222I-200J1D01*
G01X534086Y777528D01*
G03X533863Y776990I537J-538D01*
G01X533862Y776907D01*
X533745Y776790D01*
X533002D01*
G03X532522Y776290I22J-501D01*
G01Y774888D01*
Y773489D01*
G03X533024Y772988I501J0D01*
G01X535652D01*
G02X535693Y772980I-18J-200D01*
G01X536050Y772623D01*
X536080Y772545D01*
X536078Y772502D01*
G03X536076Y772428I1500J-78D01*
G03X537578Y770926I1502J0D01*
G03X537955Y770974I0J1502D01*
G01X537992Y770938D01*
G03X538530Y770714I539J537D01*
G01X540510D01*
G02X540651Y770656I0J-200D01*
G01X541610Y769697D01*
G02X541668Y769556I-142J-141D01*
G01Y765161D01*
G02X541610Y765020I-200J0D01*
G01X540333Y763743D01*
G02X540191Y763684I-142J141D01*
G01X535144D01*
G03X534642Y763182I0J-502D01*
G01Y758382D01*
G03X535144Y757880I502J0D01*
G01X540744D01*
G03X541246Y758382I0J502D01*
G01Y762419D01*
G02X541305Y762561I200J0D01*
G01X542968Y764225D01*
G03X543118Y764437I-537J539D01*
G01X543135Y764473D01*
X543193Y764525D01*
X543493Y764633D01*
X543569Y764630D01*
X543604Y764615D01*
G03X543805Y764572I203J459D01*
G01X549406D01*
G03X549908Y765074I0J502D01*
G01Y769212D01*
G02X549967Y769354I200J0D01*
G01X550199Y769587D01*
G03X550422Y770125I-537J538D01*
G01Y773848D01*
G03X550199Y774386I-760J0D01*
G01X549158Y775427D01*
G03X548620Y775650I-538J-537D01*
G01X542726D01*
G02X542526Y775850I0J200D01*
G01Y776057D01*
Y776289D01*
G03X542024Y776790I-501J0D01*
G01X540372D01*
G02X540210Y776894I14J200D01*
G01Y778536D01*
G02X540372Y778640I176J-96D01*
G01X540916D01*
X541034Y778756D01*
Y778830D01*
Y780938D01*
Y781022D01*
X540916Y781138D01*
X540885D01*
G02X540743Y781198I1J200D01*
G01X540740Y781201D01*
X540710Y781273D01*
Y781543D01*
X540725Y781595D01*
X540739Y781618D01*
G03X540938Y782588I-1290J770D01*
G03X540739Y783159I-1489J-199D01*
G02X540710Y783262I171J104D01*
G01Y785033D01*
G03X540550Y785649I-1261J1D01*
G01X540551Y785654D01*
G02X540581Y785748I200J-12D01*
G01X540763Y786033D01*
G02X540932Y786126I169J-107D01*
G01X541150D01*
G03X541630Y786626I-22J501D01*
G01Y788063D01*
G02X541645Y788139I200J0D01*
G01X541686Y788240D01*
X541711Y788267D01*
G03X542130Y789326I-1133J1061D01*
G01Y791857D01*
G02X542330Y792057I200J0D01*
G01X542782D01*
G02X542922Y792000I0J-200D01*
G01X542923Y791999D01*
X543000Y791922D01*
G02X543002Y791920I-140J-142D01*
G02X543059Y791780I-143J-140D01*
G01Y784108D01*
G03X543118Y783966I200J0D01*
G01X544109Y782975D01*
G02X544168Y782833I-141J-142D01*
G01Y782478D01*
X544163Y782456D01*
X544149Y782392D01*
X544148Y782391D01*
X544130Y782351D01*
G03X543965Y781602I1637J-753D01*
G01Y781600D01*
G03X545074Y779936I1803J0D01*
G01X545075D01*
X545112Y779920D01*
X546262Y778770D01*
G03X546404Y778711I142J141D01*
G01X551479D01*
G02X551513Y778708I-1J-200D01*
G02X551619Y778654I-34J-197D01*
G01X554370Y775903D01*
G02X554429Y775761I-141J-142D01*
G01Y761560D01*
G02X554370Y761418I-200J0D01*
G01X546746Y753794D01*
X546718Y753765D01*
X546644Y753735D01*
X531187D01*
G02X531045Y753794I0J200D01*
G01X528963Y755876D01*
X528934Y755904D01*
X528904Y755978D01*
Y787999D01*
G02X528961Y788139I200J0D01*
G01X528962Y788140D01*
X529341Y788519D01*
G03X529384Y788584I-142J141D01*
G01X529412Y788651D01*
G02X529454Y788715I185J-76D01*
G01X529457Y788718D01*
X529458Y788719D01*
X531542Y790803D01*
X531605Y790832D01*
X531640Y790835D01*
G03X532936Y791886I-139J1496D01*
G01Y791887D01*
G02X533127Y792027I191J-60D01*
G01X534879D01*
G03X534958Y792043I1J200D01*
G37*
G36*
G01X539874Y276095D02*
X540613D01*
X540639Y276122D01*
X542840D01*
X544292Y277574D01*
X545927D01*
X545961Y277540D01*
X553132D01*
X553164Y277572D01*
X560895D01*
X562710Y279387D01*
Y287118D01*
Y296369D01*
X561884Y297195D01*
X545652D01*
X543537Y295080D01*
Y282733D01*
X541354Y280550D01*
X539564Y278760D01*
Y276405D01*
X539874Y276095D01*
G37*
G36*
G01X545876Y850319D02*
G03I-639J0D01*
G37*
G36*
G01X550651Y876914D02*
X557565D01*
X559051Y878400D01*
X560828D01*
X561862Y877366D01*
Y873263D01*
X561636Y873037D01*
X550716D01*
X550328Y873425D01*
Y876591D01*
X550651Y876914D01*
G37*
G36*
G01X551880Y1036482D02*
X560269D01*
G02X560411Y1036423I0J-200D01*
G01X560799Y1036035D01*
G02X560858Y1035893I-141J-142D01*
G01Y1034919D01*
G02X560745Y1034739I-200J0D01*
G01X560347Y1034547D01*
G02X560229Y1034505I-259J541D01*
G02X560182Y1034499I-49J194D01*
G01X558494D01*
X558491Y1034502D01*
X554259D01*
G03X554118Y1034444I0J-200D01*
G01X553576Y1033902D01*
G03X553518Y1033761I142J-141D01*
G01Y1033716D01*
X553506Y1033704D01*
Y1031185D01*
X553518Y1031174D01*
Y1030998D01*
G03X553576Y1030857I200J0D01*
G01X554191Y1030242D01*
G03X554332Y1030184I141J142D01*
G01X554425D01*
G02X554566Y1030125I-1J-200D01*
G01X555444Y1029247D01*
G02X555503Y1029105I-141J-142D01*
G01Y1026105D01*
X555473Y1026032D01*
X555445Y1026004D01*
X551707D01*
G02X551565Y1026063I0J200D01*
G01X551104Y1026524D01*
G02X551045Y1026666I141J142D01*
G01Y1035647D01*
G02X551104Y1035789I200J0D01*
G01X551738Y1036423D01*
G02X551880Y1036482I142J-141D01*
G37*
G36*
G01X560538Y1033551D02*
G03X560665Y1033594I-450J1537D01*
G01X560721Y1033616D01*
X560836Y1033591D01*
X560945Y1033482D01*
G02X561004Y1033340I-141J-142D01*
G01Y1032168D01*
G03X561063Y1032026I200J0D01*
G01X561484Y1031605D01*
G03X561626Y1031546I142J141D01*
G01X561819D01*
G02X561960Y1031487I-1J-200D01*
G01X562003Y1031445D01*
G03X562144Y1031386I142J141D01*
G01X562704D01*
G02X562845Y1031328I0J-200D01*
G01X562968Y1031205D01*
G02X563026Y1031064I-142J-141D01*
G01Y1029295D01*
X563041Y1029281D01*
Y1028832D01*
G03X563100Y1028690I200J0D01*
G01X563413Y1028377D01*
G03X563555Y1028318I142J141D01*
G01X565376D01*
G02X565518Y1028259I0J-200D01*
G01X565691Y1028086D01*
G02X565750Y1027944I-141J-142D01*
G01Y1027861D01*
X565735Y1027809D01*
X565721Y1027785D01*
G03X565691Y1027680I170J-105D01*
G01Y1026159D01*
G02X565632Y1026017I-200J0D01*
G01X564128Y1024513D01*
G03X564069Y1024371I141J-142D01*
G01Y1023313D01*
G02X564010Y1023171I-200J0D01*
G01X564009Y1023170D01*
Y1019903D01*
G02X563950Y1019761I-200J0D01*
G01X563599Y1019410D01*
X563571Y1019381D01*
X563497Y1019351D01*
X558378D01*
G02X558236Y1019410I0J200D01*
G01X557923Y1019723D01*
G02X557904Y1019745I141J141D01*
G02X557864Y1019866I160J120D01*
G01Y1030462D01*
X557848D01*
Y1030624D01*
G03X557789Y1030766I-200J0D01*
G01X557429Y1031126D01*
G03X557287Y1031185I-142J-141D01*
G01X554747D01*
G02X554605Y1031244I0J200D01*
G01X554578Y1031271D01*
G02X554519Y1031413I141J142D01*
G01Y1033346D01*
G02X554578Y1033488I200J0D01*
G01X554591Y1033501D01*
X557466D01*
X557478Y1033499D01*
G03X557681Y1033486I203J1578D01*
G01X560088D01*
G03X560538Y1033551I-2J1602D01*
G37*
G36*
G01X567832Y115094D02*
X568888D01*
X568915Y115067D01*
Y111227D01*
G02X568856Y111085I-200J0D01*
G01X567226Y109456D01*
G03X567167Y109314I141J-142D01*
G01Y106183D01*
G03X567226Y106041I200J0D01*
G01X567349Y105918D01*
G03X567491Y105859I142J141D01*
G01X578197D01*
G03X578339Y105918I0J200D01*
G01X578415Y105994D01*
G03X578474Y106136I-141J142D01*
G01Y109681D01*
G03X578415Y109823I-200J0D01*
G01X578181Y110057D01*
G02X578122Y110199I141J142D01*
G01Y114552D01*
X578152Y114625D01*
X578163Y114636D01*
X583747D01*
X585089D01*
X585153Y114572D01*
X585269Y114456D01*
G02X585328Y114314I-141J-142D01*
G01Y105226D01*
G02X585269Y105084I-200J0D01*
G01X584598Y104413D01*
X584515Y104383D01*
X584470Y104388D01*
G03X584288Y104396I-174J-1893D01*
G01X581706D01*
X580420D01*
X579674Y103650D01*
Y101528D01*
X579342Y101196D01*
X567811D01*
X567787Y101202D01*
X560607D01*
X559912Y101897D01*
Y102887D01*
Y114049D01*
G02X559971Y114191I200J0D01*
G01X560093Y114313D01*
G02X560235Y114372I142J-141D01*
G01X566944D01*
G03X567086Y114431I0J200D01*
G01X567690Y115035D01*
G02X567832Y115094I142J-141D01*
G37*
G36*
G01X560094Y120851D02*
X565511D01*
G02X565653Y120792I0J-200D01*
G01X567274Y119171D01*
G03X567416Y119112I142J141D01*
G01X568931D01*
G02X569073Y119053I0J-200D01*
G01X569546Y118580D01*
G02X569605Y118438I-141J-142D01*
G01Y116276D01*
G02X569482Y116091I-200J0D01*
G01X569425Y116068D01*
X569307Y116091D01*
X569303Y116096D01*
X567831D01*
G03X567017Y115777I1J-1202D01*
G02X566881Y115724I-136J147D01*
G01X560035D01*
G02X559893Y115783I0J200D01*
G01X559878Y115798D01*
X559848Y115871D01*
Y120605D01*
G02X559907Y120747I200J0D01*
G01X559952Y120792D01*
G02X560094Y120851I142J-141D01*
G37*
G36*
G01X571197Y119235D02*
X574643D01*
X577479Y122071D01*
X583526D01*
X583896Y121701D01*
Y116118D01*
X583415Y115637D01*
X573741D01*
X571385D01*
X571037Y115985D01*
Y119075D01*
X571197Y119235D01*
G37*
G36*
G01X569769Y210785D02*
X579209D01*
X581010Y208984D01*
X582106Y207888D01*
Y187037D01*
X581159Y186090D01*
X570387D01*
X568943Y187534D01*
Y209959D01*
X569769Y210785D01*
G37*
G36*
G01X582398Y223195D02*
X592423D01*
X592453Y223225D01*
X594976D01*
X597613Y225862D01*
X606555D01*
X606897Y225520D01*
Y213126D01*
X606185Y212414D01*
X598768D01*
X595914Y215268D01*
X592474D01*
X581497D01*
X579933D01*
X579487Y214822D01*
Y213258D01*
X578214Y211985D01*
X577802D01*
X577025D01*
X569398D01*
X568738Y212645D01*
Y226569D01*
X569414Y227245D01*
X580348D01*
X582108Y225485D01*
Y223485D01*
X582398Y223195D01*
G37*
G36*
G01X582903Y953307D02*
Y934407D01*
X582203Y933707D01*
X562503D01*
X562003Y934207D01*
Y942607D01*
X562203Y942807D01*
X569203D01*
X569803Y942207D01*
Y936907D01*
X570403Y936307D01*
X575703D01*
X576303Y936907D01*
Y953407D01*
Y953807D01*
X575303Y954807D01*
Y958407D01*
X575603Y958707D01*
X582603D01*
X582903Y958407D01*
Y956307D01*
Y953307D01*
G37*
G36*
G01X562603Y953607D02*
X569203D01*
X570203Y952607D01*
Y951107D01*
X571203Y950107D01*
X574903D01*
X575203Y949807D01*
Y945607D01*
X575003Y945407D01*
X562403D01*
X562103Y945707D01*
Y953107D01*
X562603Y953607D01*
G37*
G36*
G01X569103Y963807D02*
X573603D01*
X574203Y963207D01*
Y954507D01*
X574301Y954409D01*
Y954392D01*
X575301Y953392D01*
Y951205D01*
X575205Y951109D01*
X571801D01*
X571603Y951307D01*
Y953507D01*
X568303Y956807D01*
Y963007D01*
X569103Y963807D01*
G37*
G36*
G01X564904Y1017168D02*
X569463D01*
G02X569605Y1017109I0J-200D01*
G01X569631Y1017083D01*
X569661Y1017010D01*
Y1001850D01*
G02X569602Y1001708I-200J0D01*
G01X569399Y1001505D01*
G02X569257Y1001446I-142J141D01*
G01X565581D01*
Y1001447D01*
X565182D01*
G02X565040Y1001506I0J200D01*
G01X564727Y1001819D01*
G02X564669Y1001960I142J141D01*
G01Y1016933D01*
G02X564727Y1017074I200J0D01*
G01X564762Y1017109D01*
G02X564904Y1017168I142J-141D01*
G37*
G36*
G01X571364Y1013048D02*
X586337D01*
G02X586478Y1012989I-1J-200D01*
G01X586513Y1012954D01*
G02X586572Y1012812I-141J-142D01*
G01Y1008253D01*
G02X586513Y1008111I-200J0D01*
G01X586487Y1008085D01*
X586414Y1008055D01*
X571254D01*
G02X571112Y1008114I0J200D01*
G01X570909Y1008317D01*
G02X570850Y1008459I141J142D01*
G01Y1012135D01*
X570851D01*
Y1012534D01*
G02X570910Y1012676I200J0D01*
G01X571223Y1012989D01*
G02X571364Y1013048I142J-141D01*
G37*
G36*
G01X558190Y1017056D02*
X563319D01*
G02X563461Y1016997I0J-200D01*
G01X563608Y1016850D01*
G02X563667Y1016708I-141J-142D01*
G01Y1002279D01*
G02X563608Y1002137I-200J0D01*
G01X563024Y1001553D01*
G02X562882Y1001494I-142J141D01*
G01X559311D01*
X557636D01*
X556991Y1002139D01*
Y1016642D01*
X557405Y1017056D01*
X558190D01*
G37*
G36*
G01X571364Y1025648D02*
X586337D01*
G02X586478Y1025589I-1J-200D01*
G01X586513Y1025554D01*
G02X586572Y1025412I-141J-142D01*
G01Y1020770D01*
X586547Y1020746D01*
X578012D01*
X577988Y1020720D01*
X571797D01*
G03X571656Y1020662I0J-200D01*
G01X571649Y1020655D01*
X571254D01*
G02X571112Y1020714I0J200D01*
G01X570909Y1020917D01*
G02X570850Y1021059I141J142D01*
G01Y1024735D01*
X570851D01*
Y1025134D01*
G02X570910Y1025276I200J0D01*
G01X571223Y1025589D01*
G02X571364Y1025648I142J-141D01*
G37*
G36*
G01X567661Y1028234D02*
X568762D01*
G02X568904Y1028175I0J-200D01*
G01X569166Y1027912D01*
G02X569225Y1027771I-141J-142D01*
G01Y1019455D01*
G02X569166Y1019313I-200J0D01*
G01X568619Y1018766D01*
G02X568477Y1018707I-142J141D01*
G01X565984D01*
G02X565842Y1018766I0J200D01*
G01X565639Y1018969D01*
G02X565580Y1019111I141J142D01*
G01Y1024435D01*
G02X565639Y1024577I200J0D01*
G01X566919Y1025857D01*
G03X566978Y1025999I-141J142D01*
G01Y1027551D01*
G02X567037Y1027692I200J-1D01*
G01X567519Y1028175D01*
G02X567661Y1028234I142J-141D01*
G37*
G36*
G01X578439Y1019744D02*
X586242D01*
G02X586384Y1019685I0J-200D01*
G01X586401Y1019668D01*
G02X586460Y1019526I-141J-142D01*
G01Y1014397D01*
G02X586401Y1014255I-200J0D01*
G01X586254Y1014108D01*
G02X586112Y1014049I-142J141D01*
G01X571683D01*
G02X571541Y1014108I0J200D01*
G01X570957Y1014692D01*
G02X570898Y1014834I141J142D01*
G01Y1018405D01*
G02X570957Y1018547I200J0D01*
G01X572070Y1019660D01*
G02X572212Y1019719I142J-141D01*
G01X578415D01*
X578439Y1019744D01*
G37*
G36*
G01Y1032344D02*
X586242D01*
G02X586384Y1032285I0J-200D01*
G01X586401Y1032268D01*
G02X586460Y1032126I-141J-142D01*
G01Y1026997D01*
G02X586401Y1026855I-200J0D01*
G01X586254Y1026708D01*
G02X586112Y1026649I-142J141D01*
G01X571963D01*
X569259Y1029353D01*
X564387D01*
X564370Y1029370D01*
X564028Y1029711D01*
Y1031371D01*
Y1032158D01*
X563790Y1032396D01*
X563395D01*
X563387Y1032388D01*
X562476D01*
X562445Y1032419D01*
X562350Y1032514D01*
Y1033411D01*
Y1033611D01*
X562417Y1033678D01*
X562617D01*
X563982D01*
X564337Y1033323D01*
X567474D01*
X568478Y1032319D01*
X572212D01*
X578415D01*
X578439Y1032344D01*
G37*
G36*
G01X591518Y1066535D02*
G02I-17700J0D01*
G37*
G36*
G01X559718Y1105784D02*
X574691D01*
G02X574832Y1105726I0J-200D01*
G01X574867Y1105691D01*
G02X574926Y1105549I-141J-142D01*
G01Y1100990D01*
G02X574867Y1100848I-200J0D01*
G01X574841Y1100822D01*
X574768Y1100792D01*
X559608D01*
G02X559466Y1100851I0J200D01*
G01X559263Y1101054D01*
G02X559204Y1101196I141J142D01*
G01Y1104872D01*
X559205D01*
Y1105271D01*
G02X559264Y1105413I200J0D01*
G01X559577Y1105726D01*
G02X559718Y1105784I141J-142D01*
G37*
G36*
G01X566793Y1112481D02*
X574596D01*
G02X574738Y1112422I0J-200D01*
G01X574755Y1112405D01*
G02X574814Y1112263I-141J-142D01*
G01Y1107134D01*
G02X574755Y1106992I-200J0D01*
G01X574608Y1106845D01*
G02X574466Y1106786I-142J141D01*
G01X560037D01*
G02X559895Y1106845I0J200D01*
G01X559311Y1107429D01*
G02X559252Y1107571I141J142D01*
G01Y1111142D01*
G02X559311Y1111284I200J0D01*
G01X560424Y1112397D01*
G02X560566Y1112456I142J-141D01*
G01X566769D01*
X566793Y1112481D01*
G37*
G36*
G01X559718Y1118384D02*
X574691D01*
G02X574833Y1118325I0J-200D01*
G01X574867Y1118291D01*
G02X574869Y1118289I-140J-142D01*
G02X574926Y1118149I-143J-140D01*
G01Y1113590D01*
G02X574895Y1113482I-200J-1D01*
G01X566366D01*
X566342Y1113458D01*
X560151D01*
G03X560010Y1113399I1J-200D01*
G01X560003Y1113392D01*
X559608D01*
G02X559466Y1113451I0J200D01*
G01X559263Y1113654D01*
X559234Y1113682D01*
X559204Y1113756D01*
Y1117472D01*
X559205D01*
Y1117871D01*
G02X559262Y1118011I200J0D01*
G01X559263Y1118012D01*
X559576Y1118325D01*
G02X559718Y1118384I142J-141D01*
G37*
G36*
G01X566793Y1125081D02*
X574596D01*
G02X574738Y1125022I0J-200D01*
G01X574755Y1125005D01*
G02X574814Y1124863I-141J-142D01*
G01Y1119734D01*
G02X574755Y1119592I-200J0D01*
G01X574608Y1119445D01*
G02X574466Y1119386I-142J141D01*
G01X560037D01*
G02X559895Y1119445I0J200D01*
G01X559311Y1120029D01*
G02X559252Y1120171I141J142D01*
G01Y1123742D01*
G02X559311Y1123884I200J0D01*
G01X560424Y1124997D01*
G02X560566Y1125056I142J-141D01*
G01X566769D01*
X566793Y1125081D01*
G37*
G36*
G01X559718Y1143584D02*
X574691D01*
G02X574832Y1143526I0J-200D01*
G01X574867Y1143491D01*
G02X574926Y1143349I-141J-142D01*
G01Y1138707D01*
X574901Y1138682D01*
X566366D01*
X566342Y1138658D01*
X560151D01*
G03X560010Y1138599I1J-200D01*
G01X560003Y1138592D01*
X559608D01*
G02X559466Y1138651I0J200D01*
G01X559263Y1138854D01*
G02X559204Y1138996I141J142D01*
G01Y1142672D01*
X559205D01*
Y1143071D01*
G02X559264Y1143213I200J0D01*
G01X559577Y1143526D01*
G02X559718Y1143584I141J-142D01*
G37*
G36*
G01Y1130984D02*
X574691D01*
G02X574832Y1130926I0J-200D01*
G01X574867Y1130891D01*
G02X574926Y1130749I-141J-142D01*
G01Y1126107D01*
X574901Y1126082D01*
X566366D01*
X566342Y1126058D01*
X560151D01*
G03X560010Y1125999I1J-200D01*
G01X560003Y1125992D01*
X559608D01*
G02X559466Y1126051I0J200D01*
G01X559263Y1126254D01*
G02X559204Y1126396I141J142D01*
G01Y1130072D01*
X559205D01*
Y1130471D01*
G02X559264Y1130613I200J0D01*
G01X559577Y1130926D01*
G02X559718Y1130984I141J-142D01*
G37*
G36*
G01X566793Y1137681D02*
X574596D01*
G02X574738Y1137622I0J-200D01*
G01X574755Y1137605D01*
G02X574814Y1137463I-141J-142D01*
G01Y1132334D01*
G02X574755Y1132192I-200J0D01*
G01X574608Y1132045D01*
G02X574466Y1131986I-142J141D01*
G01X560037D01*
G02X559895Y1132045I0J200D01*
G01X559311Y1132629D01*
G02X559252Y1132771I141J142D01*
G01Y1136342D01*
G02X559311Y1136484I200J0D01*
G01X560424Y1137597D01*
G02X560566Y1137656I142J-141D01*
G01X566769D01*
X566793Y1137681D01*
G37*
G36*
G01X559718Y1156184D02*
X574691D01*
G02X574832Y1156126I0J-200D01*
G01X574867Y1156091D01*
G02X574926Y1155949I-141J-142D01*
G01Y1151307D01*
X574901Y1151282D01*
X566366D01*
X566342Y1151258D01*
X560151D01*
G03X560010Y1151199I1J-200D01*
G01X560003Y1151192D01*
X559608D01*
G02X559466Y1151251I0J200D01*
G01X559263Y1151454D01*
G02X559204Y1151596I141J142D01*
G01Y1155272D01*
X559205D01*
Y1155671D01*
G02X559264Y1155813I200J0D01*
G01X559577Y1156126D01*
G02X559718Y1156184I141J-142D01*
G37*
G36*
G01X566793Y1150281D02*
X574596D01*
G02X574738Y1150222I0J-200D01*
G01X574755Y1150205D01*
G02X574814Y1150063I-141J-142D01*
G01Y1144934D01*
G02X574755Y1144792I-200J0D01*
G01X574608Y1144645D01*
G02X574466Y1144586I-142J141D01*
G01X560037D01*
G02X559895Y1144645I0J200D01*
G01X559311Y1145229D01*
G02X559252Y1145371I141J142D01*
G01Y1148942D01*
G02X559311Y1149084I200J0D01*
G01X560424Y1150197D01*
G02X560566Y1150256I142J-141D01*
G01X566769D01*
X566793Y1150281D01*
G37*
G36*
G01X559718Y1168784D02*
X574691D01*
G02X574832Y1168726I0J-200D01*
G01X574867Y1168691D01*
G02X574926Y1168549I-141J-142D01*
G01Y1163907D01*
X574901Y1163882D01*
X566366D01*
X566342Y1163858D01*
X560151D01*
G03X560010Y1163799I1J-200D01*
G01X560003Y1163792D01*
X559608D01*
G02X559466Y1163851I0J200D01*
G01X559263Y1164054D01*
G02X559204Y1164196I141J142D01*
G01Y1167872D01*
X559205D01*
Y1168271D01*
G02X559264Y1168413I200J0D01*
G01X559577Y1168726D01*
G02X559718Y1168784I141J-142D01*
G37*
G36*
G01X566793Y1175481D02*
X574596D01*
G02X574738Y1175422I0J-200D01*
G01X574755Y1175405D01*
G02X574814Y1175263I-141J-142D01*
G01Y1170134D01*
G02X574755Y1169992I-200J0D01*
G01X574608Y1169845D01*
G02X574466Y1169786I-142J141D01*
G01X560037D01*
G02X559895Y1169845I0J200D01*
G01X559311Y1170429D01*
G02X559252Y1170571I141J142D01*
G01Y1174142D01*
G02X559311Y1174284I200J0D01*
G01X560424Y1175397D01*
G02X560566Y1175456I142J-141D01*
G01X566769D01*
X566793Y1175481D01*
G37*
G36*
G01Y1162881D02*
X574596D01*
G02X574738Y1162822I0J-200D01*
G01X574755Y1162805D01*
G02X574814Y1162663I-141J-142D01*
G01Y1157534D01*
G02X574755Y1157392I-200J0D01*
G01X574608Y1157245D01*
G02X574466Y1157186I-142J141D01*
G01X560037D01*
G02X559895Y1157245I0J200D01*
G01X559311Y1157829D01*
G02X559252Y1157971I141J142D01*
G01Y1161542D01*
G02X559311Y1161684I200J0D01*
G01X560424Y1162797D01*
G02X560566Y1162856I142J-141D01*
G01X566769D01*
X566793Y1162881D01*
G37*
G36*
G01X559718Y1181384D02*
X574691D01*
G02X574832Y1181326I0J-200D01*
G01X574867Y1181291D01*
G02X574926Y1181149I-141J-142D01*
G01Y1176507D01*
X574901Y1176482D01*
X566366D01*
X566342Y1176458D01*
X560151D01*
G03X560010Y1176399I1J-200D01*
G01X560003Y1176392D01*
X559608D01*
G02X559466Y1176451I0J200D01*
G01X559263Y1176654D01*
G02X559204Y1176796I141J142D01*
G01Y1180472D01*
X559205D01*
Y1180871D01*
G02X559264Y1181013I200J0D01*
G01X559577Y1181326D01*
G02X559718Y1181384I141J-142D01*
G37*
G36*
G01X566793Y1188081D02*
X574596D01*
G02X574738Y1188022I0J-200D01*
G01X574755Y1188005D01*
G02X574814Y1187863I-141J-142D01*
G01Y1182734D01*
G02X574755Y1182592I-200J0D01*
G01X574608Y1182445D01*
G02X574466Y1182386I-142J141D01*
G01X560037D01*
G02X559895Y1182445I0J200D01*
G01X559311Y1183029D01*
G02X559252Y1183171I141J142D01*
G01Y1186742D01*
G02X559311Y1186884I200J0D01*
G01X560424Y1187997D01*
G02X560566Y1188056I142J-141D01*
G01X566769D01*
X566793Y1188081D01*
G37*
G36*
G01X591518Y1263386D02*
G02I-17700J0D01*
G37*
G36*
G01X583128Y186998D02*
Y210417D01*
X581120Y212425D01*
Y214067D01*
X581512Y214459D01*
X589934D01*
X590142Y214251D01*
Y212947D01*
X590090Y212895D01*
Y212503D01*
Y211757D01*
X590465Y211382D01*
X591211D01*
X595437D01*
X596765Y210054D01*
Y205828D01*
Y187369D01*
X595610Y186214D01*
X583912D01*
X583128Y186998D01*
G37*
G36*
G01X572810Y842346D02*
G03I-639J0D01*
G37*
G36*
G01X571803Y944107D02*
X574403D01*
X574803Y943707D01*
Y938107D01*
X574303Y937607D01*
X572103D01*
X571703Y938007D01*
Y944007D01*
X571803Y944107D01*
G37*
G36*
G01X584303Y948207D02*
X589203D01*
X589953Y947457D01*
Y943857D01*
X590303Y943507D01*
X590803Y943007D01*
X593303D01*
X593403Y942907D01*
Y934407D01*
X592703Y933707D01*
X584603D01*
X584003Y934307D01*
Y947907D01*
X584303Y948207D01*
G37*
G36*
G01X593103Y950107D02*
Y944707D01*
X592803Y944407D01*
X591303D01*
X591103Y944607D01*
Y948207D01*
X590103Y949207D01*
X584203D01*
X584003Y949407D01*
Y949907D01*
X584103Y950007D01*
X587703D01*
X588403Y950707D01*
X592903D01*
X593103Y950507D01*
Y950107D01*
G37*
G36*
G01X586203Y951207D02*
X584403D01*
X584203Y951407D01*
Y957507D01*
Y957907D01*
Y962660D01*
X584362Y962819D01*
X586747D01*
X586968Y962598D01*
Y958272D01*
X586603Y957907D01*
Y951407D01*
X586403Y951207D01*
X586203D01*
G37*
G36*
G01X577624Y1112589D02*
X587740D01*
G02X587882Y1112530I0J-200D01*
G01X588370Y1112042D01*
G02X588429Y1111900I-141J-142D01*
G01Y1104909D01*
G02X588370Y1104767I-200J0D01*
G01X587834Y1104231D01*
G02X587692Y1104172I-142J141D01*
G01X581566D01*
G02X581424Y1104231I0J200D01*
G01X581205Y1104450D01*
G02X581146Y1104592I141J142D01*
G01Y1106143D01*
G03X581087Y1106285I-200J0D01*
G01X580987Y1106385D01*
G03X580845Y1106444I-142J-141D01*
G01X577661D01*
G02X577519Y1106503I0J200D01*
G01X577168Y1106854D01*
G02X577109Y1106996I141J142D01*
G01Y1112075D01*
G02X577168Y1112217I200J0D01*
G01X577482Y1112531D01*
G02X577624Y1112589I141J-142D01*
G37*
G36*
G01X576869Y1104873D02*
X579660D01*
G02X579802Y1104815I1J-200D01*
G01X580054Y1104563D01*
G02X580113Y1104421I-141J-142D01*
G01Y1103859D01*
G03X580172Y1103717I200J0D01*
G01X580355Y1103534D01*
G03X580497Y1103475I142J141D01*
G01X580681D01*
G02X580822Y1103416I-1J-200D01*
G01X581010Y1103229D01*
G03X581151Y1103170I142J141D01*
G01X585800D01*
G02X586000Y1102970I0J-200D01*
G01Y1101540D01*
G02X585941Y1101398I-200J0D01*
G01X585830Y1101287D01*
G02X585688Y1101228I-142J141D01*
G01X577213D01*
G02X577071Y1101287I0J200D01*
G01X576524Y1101834D01*
G02X576465Y1101976I141J142D01*
G01Y1104469D01*
G02X576524Y1104611I200J0D01*
G01X576727Y1104814D01*
G02X576869Y1104873I142J-141D01*
G37*
G36*
G01X577624Y1125189D02*
X587740D01*
G02X587882Y1125130I0J-200D01*
G01X588334Y1124678D01*
G02X588393Y1124537I-141J-142D01*
G01Y1117472D01*
G02X588334Y1117331I-200J1D01*
G01X587834Y1116831D01*
G02X587692Y1116772I-142J141D01*
G01X586764D01*
G02X586622Y1116831I0J200D01*
G01X586199Y1117254D01*
G03X586057Y1117313I-142J-141D01*
G01X583142D01*
G03X583000Y1117254I0J-200D01*
G01X582881Y1117135D01*
G02X582740Y1117076I-142J141D01*
G01X581221D01*
X581148Y1117107D01*
X581146Y1117109D01*
Y1118743D01*
G03X581087Y1118885I-200J0D01*
G01X580987Y1118985D01*
G03X580845Y1119044I-142J-141D01*
G01X577661D01*
G02X577519Y1119103I0J200D01*
G01X577168Y1119454D01*
G02X577109Y1119596I141J142D01*
G01Y1124675D01*
G02X577168Y1124817I200J0D01*
G01X577482Y1125131D01*
G02X577624Y1125189I141J-142D01*
G37*
G36*
G01X576869Y1117473D02*
X579660D01*
G02X579802Y1117415I1J-200D01*
G01X580054Y1117163D01*
G02X580113Y1117021I-141J-142D01*
G01Y1116459D01*
G03X580172Y1116317I200J0D01*
G01X580355Y1116134D01*
G03X580497Y1116075I142J141D01*
G01X585703D01*
G02X585845Y1116016I0J-200D01*
G01X585941Y1115920D01*
G02X586000Y1115778I-141J-142D01*
G01Y1114140D01*
G02X585941Y1113998I-200J0D01*
G01X585830Y1113887D01*
G02X585688Y1113828I-142J141D01*
G01X577213D01*
G02X577071Y1113887I0J200D01*
G01X576524Y1114434D01*
G02X576465Y1114576I141J142D01*
G01Y1117069D01*
G02X576524Y1117211I200J0D01*
G01X576727Y1117414D01*
G02X576869Y1117473I142J-141D01*
G37*
G36*
G01X577624Y1137789D02*
X587740D01*
G02X587882Y1137730I0J-200D01*
G01X588334Y1137278D01*
G02X588393Y1137137I-141J-142D01*
G01Y1130072D01*
G02X588334Y1129931I-200J1D01*
G01X587834Y1129431D01*
G02X587692Y1129372I-142J141D01*
G01X586764D01*
G02X586622Y1129431I0J200D01*
G01X586199Y1129854D01*
G03X586057Y1129913I-142J-141D01*
G01X583142D01*
G03X583000Y1129854I0J-200D01*
G01X582881Y1129735D01*
G02X582740Y1129676I-142J141D01*
G01X581221D01*
X581148Y1129707D01*
X581146Y1129709D01*
Y1131343D01*
G03X581087Y1131485I-200J0D01*
G01X580987Y1131585D01*
G03X580845Y1131644I-142J-141D01*
G01X577661D01*
G02X577519Y1131703I0J200D01*
G01X577168Y1132054D01*
G02X577109Y1132196I141J142D01*
G01Y1137275D01*
G02X577168Y1137417I200J0D01*
G01X577482Y1137731D01*
G02X577624Y1137789I141J-142D01*
G37*
G36*
G01X576869Y1130073D02*
X579660D01*
G02X579802Y1130015I1J-200D01*
G01X580054Y1129763D01*
G02X580113Y1129621I-141J-142D01*
G01Y1129059D01*
G03X580172Y1128917I200J0D01*
G01X580355Y1128734D01*
G03X580497Y1128675I142J141D01*
G01X585703D01*
G02X585845Y1128616I0J-200D01*
G01X585941Y1128520D01*
G02X586000Y1128378I-141J-142D01*
G01Y1126740D01*
G02X585941Y1126598I-200J0D01*
G01X585830Y1126487D01*
G02X585688Y1126428I-142J141D01*
G01X577213D01*
G02X577071Y1126487I0J200D01*
G01X576524Y1127034D01*
G02X576465Y1127176I141J142D01*
G01Y1129669D01*
G02X576524Y1129811I200J0D01*
G01X576727Y1130014D01*
G02X576869Y1130073I142J-141D01*
G37*
G36*
G01Y1142673D02*
X579660D01*
G02X579802Y1142615I1J-200D01*
G01X580054Y1142363D01*
G02X580113Y1142221I-141J-142D01*
G01Y1141659D01*
G03X580172Y1141517I200J0D01*
G01X580355Y1141334D01*
G03X580497Y1141275I142J141D01*
G01X585703D01*
G02X585845Y1141216I0J-200D01*
G01X585941Y1141120D01*
G02X586000Y1140978I-141J-142D01*
G01Y1139340D01*
G02X585941Y1139198I-200J0D01*
G01X585830Y1139087D01*
G02X585688Y1139028I-142J141D01*
G01X577213D01*
G02X577071Y1139087I0J200D01*
G01X576524Y1139634D01*
G02X576465Y1139776I141J142D01*
G01Y1142269D01*
G02X576524Y1142411I200J0D01*
G01X576727Y1142614D01*
G02X576869Y1142673I142J-141D01*
G37*
G36*
G01X577624Y1162989D02*
X587740D01*
G02X587882Y1162930I0J-200D01*
G01X588334Y1162478D01*
G02X588393Y1162337I-141J-142D01*
G01Y1155272D01*
G02X588334Y1155131I-200J1D01*
G01X587834Y1154631D01*
G02X587692Y1154572I-142J141D01*
G01X586764D01*
G02X586622Y1154631I0J200D01*
G01X586199Y1155054D01*
G03X586057Y1155113I-142J-141D01*
G01X583142D01*
G03X583000Y1155054I0J-200D01*
G01X582881Y1154935D01*
G02X582740Y1154876I-142J141D01*
G01X581221D01*
X581148Y1154907D01*
X581146Y1154909D01*
Y1156543D01*
G03X581087Y1156685I-200J0D01*
G01X580987Y1156785D01*
G03X580845Y1156844I-142J-141D01*
G01X577661D01*
G02X577519Y1156903I0J200D01*
G01X577168Y1157254D01*
G02X577109Y1157396I141J142D01*
G01Y1162475D01*
G02X577168Y1162617I200J0D01*
G01X577482Y1162931D01*
G02X577624Y1162989I141J-142D01*
G37*
G36*
G01Y1150389D02*
X587740D01*
G02X587882Y1150330I0J-200D01*
G01X588334Y1149878D01*
G02X588393Y1149737I-141J-142D01*
G01Y1142672D01*
G02X588334Y1142531I-200J1D01*
G01X587834Y1142031D01*
G02X587692Y1141972I-142J141D01*
G01X586764D01*
G02X586622Y1142031I0J200D01*
G01X586199Y1142454D01*
G03X586057Y1142513I-142J-141D01*
G01X583142D01*
G03X583000Y1142454I0J-200D01*
G01X582881Y1142335D01*
G02X582740Y1142276I-142J141D01*
G01X581221D01*
X581148Y1142307D01*
X581146Y1142309D01*
Y1143943D01*
G03X581087Y1144085I-200J0D01*
G01X580987Y1144185D01*
G03X580845Y1144244I-142J-141D01*
G01X577661D01*
G02X577519Y1144303I0J200D01*
G01X577168Y1144654D01*
G02X577109Y1144796I141J142D01*
G01Y1149875D01*
G02X577168Y1150017I200J0D01*
G01X577482Y1150331D01*
G02X577624Y1150389I141J-142D01*
G37*
G36*
G01X576869Y1155273D02*
X579660D01*
G02X579802Y1155215I1J-200D01*
G01X580054Y1154963D01*
G02X580113Y1154821I-141J-142D01*
G01Y1154259D01*
G03X580172Y1154117I200J0D01*
G01X580355Y1153934D01*
G03X580497Y1153875I142J141D01*
G01X585703D01*
G02X585845Y1153816I0J-200D01*
G01X585941Y1153720D01*
G02X586000Y1153578I-141J-142D01*
G01Y1151940D01*
G02X585941Y1151798I-200J0D01*
G01X585830Y1151687D01*
G02X585688Y1151628I-142J141D01*
G01X577213D01*
G02X577071Y1151687I0J200D01*
G01X576524Y1152234D01*
G02X576465Y1152376I141J142D01*
G01Y1154869D01*
G02X576524Y1155011I200J0D01*
G01X576727Y1155214D01*
G02X576869Y1155273I142J-141D01*
G37*
G36*
G01X577624Y1175589D02*
X587740D01*
G02X587882Y1175530I0J-200D01*
G01X588370Y1175042D01*
G02X588429Y1174900I-141J-142D01*
G01Y1167909D01*
G02X588370Y1167767I-200J0D01*
G01X587834Y1167231D01*
G02X587692Y1167172I-142J141D01*
G01X586764D01*
G02X586622Y1167231I0J200D01*
G01X586199Y1167654D01*
G03X586057Y1167713I-142J-141D01*
G01X583142D01*
G03X583000Y1167654I0J-200D01*
G01X582577Y1167231D01*
G02X582435Y1167172I-142J141D01*
G01X581566D01*
G02X581424Y1167231I0J200D01*
G01X581205Y1167450D01*
G02X581146Y1167592I141J142D01*
G01Y1169143D01*
G03X581087Y1169285I-200J0D01*
G01X580987Y1169385D01*
G03X580845Y1169444I-142J-141D01*
G01X577661D01*
G02X577519Y1169503I0J200D01*
G01X577168Y1169854D01*
G02X577109Y1169996I141J142D01*
G01Y1175075D01*
G02X577168Y1175217I200J0D01*
G01X577482Y1175531D01*
G02X577624Y1175589I141J-142D01*
G37*
G36*
G01X576869Y1167873D02*
X579660D01*
G02X579802Y1167815I1J-200D01*
G01X580054Y1167563D01*
G02X580113Y1167421I-141J-142D01*
G01Y1166859D01*
G03X580172Y1166717I200J0D01*
G01X580355Y1166534D01*
G03X580497Y1166475I142J141D01*
G01X580681D01*
G02X580822Y1166416I-1J-200D01*
G01X581010Y1166229D01*
G03X581151Y1166170I142J141D01*
G01X582850D01*
G03X582991Y1166229I-1J200D01*
G01X583179Y1166416D01*
G02X583320Y1166475I142J-141D01*
G01X585703D01*
G02X585845Y1166416I0J-200D01*
G01X585941Y1166320D01*
G02X586000Y1166178I-141J-142D01*
G01Y1164540D01*
G02X585941Y1164398I-200J0D01*
G01X585830Y1164287D01*
G02X585688Y1164228I-142J141D01*
G01X577213D01*
G02X577071Y1164287I0J200D01*
G01X576524Y1164834D01*
G02X576465Y1164976I141J142D01*
G01Y1167469D01*
G02X576524Y1167611I200J0D01*
G01X576727Y1167814D01*
G02X576869Y1167873I142J-141D01*
G37*
G36*
G01X577624Y1188189D02*
X587740D01*
G02X587882Y1188130I0J-200D01*
G01X588334Y1187678D01*
G02X588393Y1187537I-141J-142D01*
G01Y1180472D01*
G02X588334Y1180331I-200J1D01*
G01X587834Y1179831D01*
G02X587692Y1179772I-142J141D01*
G01X586764D01*
G02X586622Y1179831I0J200D01*
G01X586199Y1180254D01*
G03X586057Y1180313I-142J-141D01*
G01X583142D01*
G03X583000Y1180254I0J-200D01*
G01X582881Y1180135D01*
G02X582740Y1180076I-142J141D01*
G01X581221D01*
X581148Y1180107D01*
X581146Y1180109D01*
Y1181743D01*
G03X581087Y1181885I-200J0D01*
G01X580987Y1181985D01*
G03X580845Y1182044I-142J-141D01*
G01X577661D01*
G02X577519Y1182103I0J200D01*
G01X577168Y1182454D01*
G02X577109Y1182596I141J142D01*
G01Y1187675D01*
G02X577168Y1187817I200J0D01*
G01X577482Y1188131D01*
G02X577624Y1188189I141J-142D01*
G37*
G36*
G01X576869Y1180473D02*
X579660D01*
G02X579802Y1180415I1J-200D01*
G01X580054Y1180163D01*
G02X580113Y1180021I-141J-142D01*
G01Y1179459D01*
G03X580172Y1179317I200J0D01*
G01X580355Y1179134D01*
G03X580497Y1179075I142J141D01*
G01X585703D01*
G02X585845Y1179016I0J-200D01*
G01X585941Y1178920D01*
G02X586000Y1178778I-141J-142D01*
G01Y1177140D01*
G02X585941Y1176998I-200J0D01*
G01X585830Y1176887D01*
G02X585688Y1176828I-142J141D01*
G01X577213D01*
G02X577071Y1176887I0J200D01*
G01X576524Y1177434D01*
G02X576465Y1177576I141J142D01*
G01Y1180069D01*
G02X576524Y1180211I200J0D01*
G01X576727Y1180414D01*
G02X576869Y1180473I142J-141D01*
G37*
G36*
G01X599042Y86514D02*
X607757D01*
X608110Y86161D01*
Y73377D01*
X607664Y72931D01*
X599266D01*
X598931Y73266D01*
Y86403D01*
X599042Y86514D01*
G37*
G36*
G01X598607Y600514D02*
X608010D01*
X608438Y600086D01*
Y589755D01*
X609542Y588651D01*
X612339D01*
X612925Y588065D01*
Y584209D01*
X612564Y583848D01*
X598740D01*
X598086Y584502D01*
Y599993D01*
X598607Y600514D01*
G37*
G36*
G01X592803Y951907D02*
X588903D01*
X588603Y952207D01*
Y953607D01*
X589003Y954007D01*
X592903D01*
X593003Y953907D01*
X593103Y953807D01*
Y952107D01*
X592903Y951907D01*
X592803D01*
G37*
G36*
G01X588203Y958207D02*
X592103D01*
X592353Y957957D01*
Y955907D01*
X592153Y955707D01*
X588303D01*
X588103Y955907D01*
Y958107D01*
X588203Y958207D01*
G37*
G36*
G01X588515Y1012136D02*
X591306D01*
G02X591448Y1012078I1J-200D01*
G01X591700Y1011826D01*
G02X591759Y1011684I-141J-142D01*
G01Y1011122D01*
G03X591818Y1010980I200J0D01*
G01X592001Y1010797D01*
G03X592143Y1010738I142J141D01*
G01X592327D01*
G02X592468Y1010679I-1J-200D01*
G01X592656Y1010492D01*
G03X592797Y1010434I141J142D01*
G01X597446D01*
G02X597646Y1010234I0J-200D01*
G01Y1008803D01*
G02X597587Y1008661I-200J0D01*
G01X597476Y1008550D01*
G02X597334Y1008491I-142J141D01*
G01X588859D01*
G02X588717Y1008550I0J200D01*
G01X588170Y1009097D01*
G02X588111Y1009239I141J142D01*
G01Y1011732D01*
G02X588170Y1011874I200J0D01*
G01X588373Y1012077D01*
G02X588515Y1012136I142J-141D01*
G37*
G36*
G01X601444Y1032508D02*
X605220D01*
G02X605362Y1032449I0J-200D01*
G01X605564Y1032247D01*
G02X605623Y1032105I-141J-142D01*
G01Y1024910D01*
G02X605564Y1024768I-200J0D01*
G01X605064Y1024268D01*
G02X604922Y1024209I-142J141D01*
G01X601697D01*
G02X601555Y1024268I0J200D01*
G01X601135Y1024688D01*
G02X601077Y1024829I142J141D01*
G01Y1032141D01*
G02X601135Y1032282I200J0D01*
G01X601302Y1032449D01*
G02X601444Y1032508I142J-141D01*
G37*
G36*
G01Y1019908D02*
X605220D01*
G02X605362Y1019849I0J-200D01*
G01X605564Y1019647D01*
G02X605623Y1019505I-141J-142D01*
G01Y1012310D01*
G02X605564Y1012168I-200J0D01*
G01X605064Y1011668D01*
G02X604922Y1011609I-142J141D01*
G01X601697D01*
G02X601555Y1011668I0J200D01*
G01X601135Y1012088D01*
G02X601077Y1012229I142J141D01*
G01Y1019541D01*
G02X601135Y1019682I200J0D01*
G01X601302Y1019849D01*
G02X601444Y1019908I142J-141D01*
G37*
G36*
G01X589270Y1019852D02*
X599386D01*
G02X599528Y1019793I0J-200D01*
G01X600016Y1019305D01*
G02X600075Y1019163I-141J-142D01*
G01Y1012172D01*
G02X600016Y1012030I-200J0D01*
G01X599480Y1011494D01*
G02X599338Y1011435I-142J141D01*
G01X593212D01*
G02X593070Y1011494I0J200D01*
G01X592851Y1011713D01*
G02X592792Y1011855I141J142D01*
G01Y1013406D01*
G03X592733Y1013548I-200J0D01*
G01X592633Y1013648D01*
G03X592491Y1013707I-142J-141D01*
G01X589307D01*
G02X589165Y1013766I0J200D01*
G01X588814Y1014117D01*
G02X588755Y1014259I141J142D01*
G01Y1019338D01*
G02X588814Y1019480I200J0D01*
G01X589128Y1019794D01*
G02X589270Y1019852I141J-142D01*
G37*
G36*
G01Y1032452D02*
X599386D01*
G02X599528Y1032393I0J-200D01*
G01X600016Y1031905D01*
G02X600075Y1031763I-141J-142D01*
G01Y1024772D01*
G02X600016Y1024630I-200J0D01*
G01X599480Y1024094D01*
G02X599338Y1024035I-142J141D01*
G01X593212D01*
G02X593070Y1024094I0J200D01*
G01X592851Y1024313D01*
G02X592792Y1024455I141J142D01*
G01Y1026006D01*
G03X592733Y1026148I-200J0D01*
G01X592633Y1026248D01*
G03X592491Y1026307I-142J-141D01*
G01X589307D01*
G02X589165Y1026366I0J200D01*
G01X588814Y1026717D01*
G02X588755Y1026859I141J142D01*
G01Y1031938D01*
G02X588814Y1032080I200J0D01*
G01X589128Y1032394D01*
G02X589270Y1032452I141J-142D01*
G37*
G36*
G01X588515Y1024736D02*
X591306D01*
G02X591448Y1024678I1J-200D01*
G01X591700Y1024426D01*
G02X591759Y1024284I-141J-142D01*
G01Y1023722D01*
G03X591818Y1023580I200J0D01*
G01X592001Y1023397D01*
G03X592143Y1023338I142J141D01*
G01X592327D01*
G02X592468Y1023279I-1J-200D01*
G01X592656Y1023092D01*
G03X592797Y1023034I141J142D01*
G01X597446D01*
G02X597646Y1022834I0J-200D01*
G01Y1021403D01*
G02X597587Y1021261I-200J0D01*
G01X597476Y1021150D01*
G02X597334Y1021091I-142J141D01*
G01X588859D01*
G02X588717Y1021150I0J200D01*
G01X588170Y1021697D01*
G02X588111Y1021839I141J142D01*
G01Y1024332D01*
G02X588170Y1024474I200J0D01*
G01X588373Y1024677D01*
G02X588515Y1024736I142J-141D01*
G37*
G36*
G01X589798Y1188245D02*
X592086D01*
X592625Y1187706D01*
Y1166474D01*
X592976Y1166123D01*
X593802Y1165297D01*
Y1104789D01*
X593418Y1104405D01*
G02X593396Y1104386I-141J141D01*
G02X593276Y1104346I-120J160D01*
G01X590051D01*
G02X589931Y1104386I0J200D01*
G02X589909Y1104405I119J160D01*
G01X589489Y1104825D01*
G02X589431Y1104966I142J141D01*
G01Y1112278D01*
G02X589462Y1112385I200J0D01*
G01Y1117452D01*
X589453Y1117461D01*
G02X589434Y1117483I141J141D01*
G02X589394Y1117603I160J120D01*
G01Y1124841D01*
G02X589434Y1124961I200J0D01*
G02X589453Y1124983I160J-119D01*
G01X589462Y1124992D01*
Y1130052D01*
X589453Y1130061D01*
G02X589434Y1130083I141J141D01*
G02X589394Y1130203I160J120D01*
G01Y1137441D01*
G02X589434Y1137561I200J0D01*
G02X589453Y1137583I160J-119D01*
G01X589462Y1137592D01*
Y1142652D01*
X589453Y1142661D01*
G02X589434Y1142683I141J141D01*
G02X589394Y1142803I160J120D01*
G01Y1150041D01*
G02X589434Y1150161I200J0D01*
G02X589453Y1150183I160J-119D01*
G01X589462Y1150192D01*
Y1155252D01*
X589453Y1155261D01*
G02X589434Y1155283I141J141D01*
G02X589394Y1155403I160J120D01*
G01Y1162641D01*
G02X589434Y1162761I200J0D01*
G02X589453Y1162783I160J-119D01*
G01X589462Y1162792D01*
Y1167859D01*
G02X589431Y1167966I169J107D01*
G01Y1175278D01*
G02X589462Y1175385I200J0D01*
G01Y1178989D01*
X589752Y1179279D01*
Y1180161D01*
X589729Y1180184D01*
Y1183102D01*
X589394Y1183437D01*
Y1187841D01*
G02X589434Y1187961I200J0D01*
G02X589453Y1187983I160J-119D01*
G01X589656Y1188186D01*
G02X589678Y1188205I141J-141D01*
G02X589798Y1188245I120J-160D01*
G37*
G36*
G01X598824Y1198622D02*
G03I-400J0D01*
G37*
G36*
G01Y1191142D02*
G03I-400J0D01*
G37*
G36*
G01Y1221063D02*
G03I-400J0D01*
G37*
G36*
G01Y1213583D02*
G03I-400J0D01*
G37*
G36*
G01Y1206103D02*
G03I-400J0D01*
G37*
G36*
G01Y1228542D02*
G03I-400J0D01*
G37*
G36*
G01X598823Y1239763D02*
G03I-400J0D01*
G37*
G36*
G01Y1247242D02*
G03I-400J0D01*
G37*
G36*
G01X627220Y89379D02*
X627318D01*
G02X627459Y89438I142J-141D01*
G01X641484D01*
G02X641626Y89379I0J-200D01*
G01X641628Y89376D01*
Y74039D01*
G03X641687Y73898I200J1D01*
G01X641734Y73851D01*
G02Y73568I-141J-141D01*
G01X641547Y73381D01*
G02X641405Y73322I-142J141D01*
G01X637590D01*
X637587Y73319D01*
X617242D01*
G02X617100Y73378I0J200D01*
G01X617032Y73446D01*
G02X616973Y73588I141J142D01*
G01Y86280D01*
G02X617032Y86422I200J0D01*
G01X617100Y86490D01*
G02X617242Y86549I142J-141D01*
G01X622553D01*
G03X622695Y86608I0J200D01*
G01X623528Y87441D01*
G03X623587Y87583I-141J142D01*
G01Y88917D01*
G02X623646Y89059I200J0D01*
G01X623966Y89379D01*
G02X624108Y89438I142J-141D01*
G01X627079D01*
G02X627220Y89379I-1J-200D01*
G37*
G36*
G01X614968Y176789D02*
X629395D01*
X630158Y176026D01*
Y174795D01*
X630921Y174032D01*
X634029D01*
X634616Y173445D01*
Y161423D01*
X633912Y160719D01*
X615613D01*
Y160720D01*
X613617D01*
X612856Y161481D01*
Y176203D01*
X613442Y176789D01*
X614968D01*
G37*
G36*
G01X641887Y219609D02*
X643529D01*
X643921Y219217D01*
Y210795D01*
X643713Y210587D01*
X642409D01*
X642357Y210639D01*
X641965D01*
X641958Y210632D01*
X641155D01*
X640844Y210321D01*
Y209518D01*
Y204802D01*
X630375Y194333D01*
Y189191D01*
X634012Y185554D01*
X638777D01*
X639325Y185006D01*
Y183690D01*
X640320Y182695D01*
X642254D01*
X642641Y182308D01*
X644855D01*
X645033Y182130D01*
Y181714D01*
X644720Y181401D01*
X641510D01*
X641109Y181000D01*
X641064D01*
X639771Y179707D01*
X614212D01*
X612900Y181019D01*
Y216698D01*
X613803Y217601D01*
X639879D01*
X641887Y219609D01*
G37*
G36*
G01X640247Y234621D02*
Y221520D01*
X638446Y219719D01*
X637350Y218623D01*
X614509D01*
X612781Y220351D01*
Y252516D01*
X614092Y253827D01*
X636332D01*
X640247Y249912D01*
Y234621D01*
G37*
G36*
G01X615127Y277007D02*
X622556D01*
X635007D01*
X636864Y275150D01*
X639443D01*
X639718Y274875D01*
Y272398D01*
X639168Y271848D01*
X636624D01*
X636520Y271952D01*
X632840Y268272D01*
Y265554D01*
X629642Y262356D01*
X615058D01*
X614370Y263044D01*
Y276250D01*
X615127Y277007D01*
G37*
G36*
G01X618120Y299467D02*
X628404D01*
X632840Y295031D01*
Y278899D01*
X632599Y278658D01*
X615849D01*
X614577Y279930D01*
Y295924D01*
X618120Y299467D01*
G37*
G36*
G01X610046Y1258465D02*
G03I-400J0D01*
G37*
G36*
G01X617526D02*
G03I-400J0D01*
G37*
G36*
G01X697106Y54588D02*
X723491D01*
Y52591D01*
X697106D01*
G03X691169Y46654I0J-5937D01*
G01Y7874D01*
G02X685295Y2000I-5874J0D01*
G01X638051D01*
G02X632177Y7874I0J5874D01*
G01Y46654D01*
G03X632173Y46884I-5937J12D01*
G01X634171D01*
G02X634174Y46655I-7931J-218D01*
G01Y7874D01*
G03X638049Y3998I3876J0D01*
G01X685295D01*
G03X689172Y7874I0J3877D01*
G01Y46654D01*
G02X697106Y54588I7934J0D01*
G37*
G36*
G01X627071Y95055D02*
X642087D01*
X642107Y95035D01*
X646112D01*
X646825Y94322D01*
Y74773D01*
X645964Y73912D01*
X643353D01*
X643089D01*
X642630Y74371D01*
Y90663D01*
X642507Y90786D01*
X641801D01*
X639046D01*
X627308D01*
X627269Y90747D01*
X626992Y91024D01*
Y94976D01*
X627071Y95055D01*
G37*
G36*
G01X632485Y1071455D02*
G03I-400J0D01*
G37*
G36*
G01D02*
G03I-400J0D01*
G37*
G36*
G01X625006Y1258465D02*
G03I-400J0D01*
G37*
G36*
G01X632487D02*
G03I-400J0D01*
G37*
G36*
G01X646982Y276354D02*
X664555D01*
X665381Y275528D01*
Y258570D01*
X663756Y256946D01*
Y231877D01*
X657247Y225368D01*
Y224586D01*
Y220921D01*
X654947Y218621D01*
X652947D01*
X652657Y218331D01*
Y205660D01*
X652070Y205073D01*
X645238D01*
X644730Y205581D01*
Y220421D01*
X641447Y223704D01*
Y234821D01*
X641613Y234987D01*
Y250246D01*
X644777Y253410D01*
X644813D01*
X647033Y255630D01*
Y268925D01*
X644024Y271934D01*
X641720D01*
X641204Y272450D01*
Y274738D01*
X641427Y274961D01*
X645589D01*
X646982Y276354D01*
G37*
G36*
G01X642236Y276095D02*
X642975D01*
X643001Y276122D01*
X645202D01*
X646654Y277574D01*
X648289D01*
X648323Y277540D01*
X655494D01*
X655526Y277572D01*
X663257D01*
X665072Y279387D01*
Y287118D01*
Y296369D01*
X664246Y297195D01*
X648014D01*
X645899Y295080D01*
Y282733D01*
X643716Y280550D01*
X641926Y278760D01*
Y276405D01*
X642236Y276095D01*
G37*
G36*
G01X639966Y1071455D02*
G03I-400J0D01*
G37*
G36*
G01D02*
G03I-400J0D01*
G37*
G36*
G01X647446D02*
G03I-400J0D01*
G37*
G36*
G01D02*
G03I-400J0D01*
G37*
G36*
G01X639967Y1258465D02*
G03I-400J0D01*
G37*
G36*
G01X647447D02*
G03I-400J0D01*
G37*
G36*
G01X670194Y115094D02*
X671250D01*
X671277Y115067D01*
Y111227D01*
G02X671218Y111085I-200J0D01*
G01X669588Y109456D01*
G03X669529Y109314I141J-142D01*
G01Y106183D01*
G03X669588Y106041I200J0D01*
G01X669711Y105918D01*
G03X669853Y105859I142J141D01*
G01X680559D01*
G03X680701Y105918I0J200D01*
G01X680777Y105994D01*
G03X680836Y106136I-141J142D01*
G01Y109681D01*
G03X680777Y109823I-200J0D01*
G01X680543Y110057D01*
G02X680484Y110199I141J142D01*
G01Y114552D01*
X680514Y114625D01*
X680525Y114636D01*
X686109D01*
X687451D01*
X687515Y114572D01*
X687631Y114456D01*
G02X687690Y114314I-141J-142D01*
G01Y105226D01*
G02X687631Y105084I-200J0D01*
G01X686960Y104413D01*
X686877Y104383D01*
X686832Y104388D01*
G03X686650Y104396I-174J-1893D01*
G01X684068D01*
X682782D01*
X682036Y103650D01*
Y101528D01*
X681704Y101196D01*
X670173D01*
X670149Y101202D01*
X662969D01*
X662274Y101897D01*
Y102887D01*
Y114049D01*
G02X662333Y114191I200J0D01*
G01X662455Y114313D01*
G02X662597Y114372I142J-141D01*
G01X669306D01*
G03X669448Y114431I0J200D01*
G01X670052Y115035D01*
G02X670194Y115094I142J-141D01*
G37*
G36*
G01X662456Y120851D02*
X667873D01*
G02X668015Y120792I0J-200D01*
G01X669636Y119171D01*
G03X669778Y119112I142J141D01*
G01X671293D01*
G02X671435Y119053I0J-200D01*
G01X671908Y118580D01*
G02X671967Y118438I-141J-142D01*
G01Y116276D01*
G02X671844Y116091I-200J0D01*
G01X671787Y116068D01*
X671669Y116091D01*
X671665Y116096D01*
X670193D01*
G03X669379Y115777I1J-1202D01*
G02X669243Y115724I-136J147D01*
G01X662397D01*
G02X662255Y115783I0J200D01*
G01X662240Y115798D01*
X662210Y115871D01*
Y120605D01*
G02X662269Y120747I200J0D01*
G01X662314Y120792D01*
G02X662456Y120851I142J-141D01*
G37*
G36*
G01X653631Y576428D02*
X661479D01*
X661885Y576022D01*
Y564567D01*
X661318Y564000D01*
X660000D01*
X659515Y563515D01*
X653485D01*
X653315Y563685D01*
Y576112D01*
X653631Y576428D01*
G37*
G36*
G01X662407Y1071455D02*
G03I-400J0D01*
G37*
G36*
G01D02*
G03I-400J0D01*
G37*
G36*
G01X654926D02*
G03I-400J0D01*
G37*
G36*
G01D02*
G03I-400J0D01*
G37*
G36*
G01X662408Y1258465D02*
G03I-400J0D01*
G37*
G36*
G01X654928D02*
G03I-400J0D01*
G37*
G36*
G01X673559Y119235D02*
X677005D01*
X679841Y122071D01*
X685888D01*
X686258Y121701D01*
Y116118D01*
X685777Y115637D01*
X676103D01*
X673747D01*
X673399Y115985D01*
Y119075D01*
X673559Y119235D01*
G37*
G36*
G01X672131Y210785D02*
X681571D01*
X683372Y208984D01*
X684468Y207888D01*
Y187037D01*
X683521Y186090D01*
X672749D01*
X671305Y187534D01*
Y209959D01*
X672131Y210785D01*
G37*
G36*
G01X685490Y186998D02*
Y210417D01*
X683482Y212425D01*
Y214067D01*
X683874Y214459D01*
X692296D01*
X692504Y214251D01*
Y212947D01*
X692452Y212895D01*
Y212503D01*
Y211832D01*
X692902Y211382D01*
X693573D01*
X697799D01*
X699127Y210054D01*
Y205828D01*
Y187369D01*
X697972Y186214D01*
X686274D01*
X685490Y186998D01*
G37*
G36*
G01X684760Y223195D02*
X694785D01*
X694815Y223225D01*
X697338D01*
X699975Y225862D01*
X708917D01*
X709259Y225520D01*
Y213126D01*
X708547Y212414D01*
X701130D01*
X698276Y215268D01*
X694836D01*
X683859D01*
X682295D01*
X681849Y214822D01*
Y213258D01*
X680576Y211985D01*
X680164D01*
X679387D01*
X671760D01*
X671100Y212645D01*
Y226569D01*
X671776Y227245D01*
X682710D01*
X684470Y225485D01*
Y223485D01*
X684760Y223195D01*
G37*
G36*
G01X684848Y1071455D02*
G03I-400J0D01*
G37*
G36*
G01D02*
G03I-400J0D01*
G37*
G36*
G01X677367D02*
G03I-400J0D01*
G37*
G36*
G01D02*
G03I-400J0D01*
G37*
G36*
G01X669887D02*
G03I-400J0D01*
G37*
G36*
G01D02*
G03I-400J0D01*
G37*
G36*
G01X677369Y1258465D02*
G03I-400J0D01*
G37*
G36*
G01X684850D02*
G03I-400J0D01*
G37*
G36*
G01X669888D02*
G03I-400J0D01*
G37*
G36*
G01X699808Y1071455D02*
G03I-400J0D01*
G37*
G36*
G01X692328Y1071454D02*
G03I-400J0D01*
G37*
G36*
G01D02*
G03I-400J0D01*
G37*
G36*
G01X699808Y1071455D02*
G03I-400J0D01*
G37*
G36*
G01X692329Y1258465D02*
G03I-400J0D01*
G37*
G36*
G01X699809D02*
G03I-400J0D01*
G37*
G36*
G01X701404Y86514D02*
X710119D01*
X710472Y86161D01*
Y73377D01*
X710026Y72931D01*
X701628D01*
X701293Y73266D01*
Y86403D01*
X701404Y86514D01*
G37*
G36*
G01X717330Y176789D02*
X731757D01*
X732520Y176026D01*
Y174795D01*
X733283Y174032D01*
X736391D01*
X736978Y173445D01*
Y161423D01*
X736274Y160719D01*
X717975D01*
Y160720D01*
X715979D01*
X715218Y161481D01*
Y176203D01*
X715804Y176789D01*
X717330D01*
G37*
G36*
G01X744249Y219609D02*
X745891D01*
X746283Y219217D01*
Y210883D01*
X746200Y210800D01*
X744488D01*
X744474Y210786D01*
X743496D01*
X743206Y210496D01*
Y209518D01*
Y204802D01*
X732737Y194333D01*
Y189191D01*
X736374Y185554D01*
X741139D01*
X741687Y185006D01*
Y183690D01*
X742682Y182695D01*
X744616D01*
X745003Y182308D01*
X747217D01*
X747395Y182130D01*
Y181714D01*
X747082Y181401D01*
X743872D01*
X743471Y181000D01*
X743426D01*
X742133Y179707D01*
X716574D01*
X715262Y181019D01*
Y216698D01*
X716165Y217601D01*
X742241D01*
X744249Y219609D01*
G37*
G36*
G01X742609Y234621D02*
Y221520D01*
X740808Y219719D01*
X739712Y218623D01*
X716871D01*
X715143Y220351D01*
Y252516D01*
X716454Y253827D01*
X738694D01*
X742609Y249912D01*
Y234621D01*
G37*
G36*
G01X717489Y277007D02*
X724918D01*
X737369D01*
X739226Y275150D01*
X741805D01*
X742080Y274875D01*
Y272398D01*
X741530Y271848D01*
X738986D01*
X738882Y271952D01*
X735202Y268272D01*
Y265554D01*
X732004Y262356D01*
X717420D01*
X716732Y263044D01*
Y276250D01*
X717489Y277007D01*
G37*
G36*
G01X720482Y299467D02*
X730766D01*
X735202Y295031D01*
Y278899D01*
X734961Y278658D01*
X718211D01*
X716939Y279930D01*
Y295924D01*
X720482Y299467D01*
G37*
G36*
G01X714769Y1071455D02*
G03I-400J0D01*
G37*
G36*
G01D02*
G03I-400J0D01*
G37*
G36*
G01X707289D02*
G03I-400J0D01*
G37*
G36*
G01D02*
G03I-400J0D01*
G37*
G36*
G01X707290Y1258465D02*
G03I-400J0D01*
G37*
G36*
G01X714770D02*
G03I-400J0D01*
G37*
G36*
G01X729821Y89438D02*
X743846D01*
G02X743988Y89379I0J-200D01*
G01X743990Y89376D01*
Y74039D01*
G03X744049Y73898I200J1D01*
G01X744096Y73851D01*
G02Y73568I-141J-141D01*
G01X743909Y73381D01*
G02X743767Y73322I-142J141D01*
G01X739952D01*
X739949Y73319D01*
X719521D01*
X719463Y73377D01*
X719462Y73378D01*
X719394Y73446D01*
X719393Y73447D01*
X719335Y73505D01*
Y86363D01*
X719393Y86421D01*
X719394Y86422D01*
X719462Y86490D01*
X719463Y86491D01*
X719521Y86549D01*
X724915D01*
G03X725057Y86608I0J200D01*
G01X725890Y87441D01*
G03X725949Y87583I-141J142D01*
G01Y88917D01*
G02X726008Y89059I200J0D01*
G01X726328Y89379D01*
G02X726470Y89438I142J-141D01*
G01X729441D01*
G02X729582Y89379I-1J-200D01*
G01X729680D01*
G02X729821Y89438I142J-141D01*
G37*
G36*
G01X729433Y95055D02*
X744449D01*
X744469Y95035D01*
X748474D01*
X749187Y94322D01*
Y74773D01*
X748326Y73912D01*
X745715D01*
X745451D01*
X744992Y74371D01*
Y90663D01*
X744869Y90786D01*
X744163D01*
X741408D01*
X729670D01*
X729631Y90747D01*
X729354Y91024D01*
Y94976D01*
X729433Y95055D01*
G37*
G36*
G01X730226Y429084D02*
X722378D01*
X721972Y429490D01*
Y440472D01*
X723491Y441991D01*
X730009D01*
X730542Y441458D01*
Y429400D01*
X730226Y429084D01*
G37*
G36*
G01X729730Y1071455D02*
G03I-400J0D01*
G37*
G36*
G01X722249D02*
G03I-400J0D01*
G37*
G36*
G01D02*
G03I-400J0D01*
G37*
G36*
G01X729730D02*
G03I-400J0D01*
G37*
G36*
G01X722250Y1258465D02*
G03I-400J0D01*
G37*
G36*
G01X729731D02*
G03I-400J0D01*
G37*
G36*
G01X799468Y54588D02*
X827614D01*
X827756Y54446D01*
Y52733D01*
X827614Y52591D01*
X799468D01*
G03X793531Y46654I0J-5937D01*
G01Y7874D01*
G02X787657Y2000I-5874J0D01*
G01X740413D01*
G02X734539Y7874I0J5874D01*
G01Y46655D01*
G03Y46724I-5937J34D01*
G01X736536D01*
G02Y46654I-7934J-35D01*
G01Y7874D01*
G03X740411Y3998I3876J0D01*
G01X787657D01*
G03X791534Y7874I0J3877D01*
G01Y46654D01*
G02X799468Y54588I7934J0D01*
G37*
G36*
G01X749344Y276354D02*
X766917D01*
X767743Y275528D01*
Y258570D01*
X766088Y256915D01*
Y231217D01*
X759609Y224738D01*
Y220921D01*
X757309Y218621D01*
X755309D01*
X755019Y218331D01*
Y205660D01*
X754432Y205073D01*
X747600D01*
X747092Y205581D01*
Y220421D01*
X743809Y223704D01*
Y234821D01*
X743975Y234987D01*
Y250246D01*
X747139Y253410D01*
X747175D01*
X749395Y255630D01*
Y268925D01*
X746386Y271934D01*
X744082D01*
X743566Y272450D01*
Y274738D01*
X743789Y274961D01*
X747951D01*
X749344Y276354D01*
G37*
G36*
G01X744598Y276095D02*
X745337D01*
X745363Y276122D01*
X747564D01*
X749016Y277574D01*
X750651D01*
X750685Y277540D01*
X757856D01*
X757888Y277572D01*
X765619D01*
X767434Y279387D01*
Y287118D01*
Y296369D01*
X766608Y297195D01*
X750376D01*
X748261Y295080D01*
Y282733D01*
X746078Y280550D01*
X744288Y278760D01*
Y276405D01*
X744598Y276095D01*
G37*
G36*
G01X746512Y442631D02*
X754413D01*
X754442Y442602D01*
X770731D01*
X774467Y438866D01*
X776274D01*
X784893D01*
X835276D01*
X843827D01*
X845418Y437275D01*
Y422129D01*
X844417Y421128D01*
X787679D01*
X785166Y423641D01*
X760431D01*
X754768Y429304D01*
X746512D01*
X743148D01*
X743014Y429438D01*
Y442468D01*
X743177Y442631D01*
X746512D01*
G37*
G36*
G01X801237Y477893D02*
X827377D01*
Y469277D01*
X827300Y469200D01*
X821788D01*
X819797Y467209D01*
Y451025D01*
X819449Y450677D01*
X816359D01*
X816199Y450837D01*
Y454283D01*
X815388Y455094D01*
X800018D01*
X798609Y453685D01*
X766382D01*
X763593Y450896D01*
X749660D01*
X748566Y451990D01*
Y452511D01*
X748111Y452966D01*
X747590D01*
X747574Y452982D01*
X743127D01*
X743011Y453098D01*
Y454360D01*
X743076Y454425D01*
X748414D01*
X752194Y458205D01*
X754452D01*
X759534Y463287D01*
X786631D01*
X801237Y477893D01*
G37*
G36*
G01X744690Y1071455D02*
G03I-400J0D01*
G37*
G36*
G01X737210D02*
G03I-400J0D01*
G37*
G36*
G01D02*
G03I-400J0D01*
G37*
G36*
G01X744690D02*
G03I-400J0D01*
G37*
G36*
G01X737211Y1258465D02*
G03I-400J0D01*
G37*
G36*
G01X744691D02*
G03I-400J0D01*
G37*
G36*
G01X772556Y115094D02*
X773612D01*
X773639Y115067D01*
Y111227D01*
G02X773580Y111085I-200J0D01*
G01X771950Y109456D01*
G03X771891Y109314I141J-142D01*
G01Y106183D01*
G03X771950Y106041I200J0D01*
G01X772073Y105918D01*
G03X772215Y105859I142J141D01*
G01X782921D01*
G03X783063Y105918I0J200D01*
G01X783139Y105994D01*
G03X783198Y106136I-141J142D01*
G01Y109681D01*
G03X783139Y109823I-200J0D01*
G01X782905Y110057D01*
G02X782846Y110199I141J142D01*
G01Y114552D01*
X782876Y114625D01*
X782887Y114636D01*
X788471D01*
X789813D01*
X789877Y114572D01*
X789993Y114456D01*
G02X790052Y114314I-141J-142D01*
G01Y105226D01*
G02X789993Y105084I-200J0D01*
G01X789322Y104413D01*
X789239Y104383D01*
X789194Y104388D01*
G03X789012Y104396I-174J-1893D01*
G01X786430D01*
X785144D01*
X784398Y103650D01*
Y101528D01*
X784066Y101196D01*
X772535D01*
X772511Y101202D01*
X765331D01*
X764636Y101897D01*
Y102887D01*
Y114049D01*
G02X764695Y114191I200J0D01*
G01X764817Y114313D01*
G02X764959Y114372I142J-141D01*
G01X771668D01*
G03X771810Y114431I0J200D01*
G01X772414Y115035D01*
G02X772556Y115094I142J-141D01*
G37*
G36*
G01X764818Y120851D02*
X770235D01*
G02X770377Y120792I0J-200D01*
G01X771998Y119171D01*
G03X772140Y119112I142J141D01*
G01X773655D01*
G02X773797Y119053I0J-200D01*
G01X774270Y118580D01*
G02X774329Y118438I-141J-142D01*
G01Y116276D01*
G02X774206Y116091I-200J0D01*
G01X774149Y116068D01*
X774031Y116091D01*
X774027Y116096D01*
X772555D01*
G03X771741Y115777I1J-1202D01*
G02X771605Y115724I-136J147D01*
G01X764759D01*
G02X764617Y115783I0J200D01*
G01X764602Y115798D01*
X764572Y115871D01*
Y120605D01*
G02X764631Y120747I200J0D01*
G01X764676Y120792D01*
G02X764818Y120851I142J-141D01*
G37*
G36*
G01X759652Y1071455D02*
G03I-400J0D01*
G37*
G36*
G01D02*
G03I-400J0D01*
G37*
G36*
G01X752171D02*
G03I-400J0D01*
G37*
G36*
G01D02*
G03I-400J0D01*
G37*
G36*
G01X759652Y1258465D02*
G03I-400J0D01*
G37*
G36*
G01X752172D02*
G03I-400J0D01*
G37*
G36*
G01X790157Y1490945D02*
G03I-19685J0D01*
G37*
G36*
G01X775921Y119235D02*
X779367D01*
X782203Y122071D01*
X788250D01*
X788620Y121701D01*
Y116118D01*
X788139Y115637D01*
X778465D01*
X776109D01*
X775761Y115985D01*
Y119075D01*
X775921Y119235D01*
G37*
G36*
G01X774493Y210785D02*
X783933D01*
X785734Y208984D01*
X786830Y207888D01*
Y187037D01*
X785883Y186090D01*
X775111D01*
X773667Y187534D01*
Y209959D01*
X774493Y210785D01*
G37*
G36*
G01X787122Y223195D02*
X797147D01*
X797177Y223225D01*
X799700D01*
X802337Y225862D01*
X811279D01*
X811621Y225520D01*
Y213126D01*
X810909Y212414D01*
X803492D01*
X800638Y215268D01*
X797198D01*
X786221D01*
X784657D01*
X784211Y214822D01*
Y213258D01*
X782938Y211985D01*
X782526D01*
X781749D01*
X774122D01*
X773462Y212645D01*
Y226569D01*
X774138Y227245D01*
X785072D01*
X786832Y225485D01*
Y223485D01*
X787122Y223195D01*
G37*
G36*
G01X771213Y422088D02*
X783255D01*
X784971D01*
X786540Y420519D01*
Y413954D01*
Y411954D01*
X786086Y411500D01*
X771086D01*
X770469Y412117D01*
Y414117D01*
Y417734D01*
Y421344D01*
X771213Y422088D01*
G37*
G36*
G01X774612Y1071455D02*
G03I-400J0D01*
G37*
G36*
G01D02*
G03I-400J0D01*
G37*
G36*
G01X767132D02*
G03I-400J0D01*
G37*
G36*
G01D02*
G03I-400J0D01*
G37*
G36*
G01X774612Y1258465D02*
G03I-400J0D01*
G37*
G36*
G01X767132D02*
G03I-400J0D01*
G37*
G36*
G01X787852Y186998D02*
Y210417D01*
X785844Y212425D01*
Y214067D01*
X786236Y214459D01*
X794658D01*
X794866Y214251D01*
Y212947D01*
X794814Y212895D01*
Y212503D01*
X794815Y212502D01*
Y211878D01*
X795311Y211382D01*
X795935D01*
X800161D01*
X801489Y210054D01*
Y205828D01*
Y187369D01*
X800334Y186214D01*
X788636D01*
X787852Y186998D01*
G37*
G36*
G01X827738Y1066535D02*
G02I-17700J0D01*
G37*
G36*
G01X785834Y1090158D02*
G03I-400J0D01*
G37*
G36*
G01Y1082677D02*
G03I-400J0D01*
G37*
G36*
G01Y1101378D02*
G03I-400J0D01*
G37*
G36*
G01Y1123819D02*
G03I-400J0D01*
G37*
G36*
G01Y1116339D02*
G03I-400J0D01*
G37*
G36*
G01Y1108859D02*
G03I-400J0D01*
G37*
G36*
G01Y1131300D02*
G03I-400J0D01*
G37*
G36*
G01Y1198621D02*
G03I-400J0D01*
G37*
G36*
G01Y1221062D02*
G03I-400J0D01*
G37*
G36*
G01Y1213582D02*
G03I-400J0D01*
G37*
G36*
G01Y1206102D02*
G03I-400J0D01*
G37*
G36*
G01Y1228543D02*
G03I-400J0D01*
G37*
G36*
G01X827738Y1263386D02*
G02I-17700J0D01*
G37*
G36*
G01X785834Y1239762D02*
G03I-400J0D01*
G37*
G36*
G01Y1247243D02*
G03I-400J0D01*
G37*
G36*
G01X804088Y1450320D02*
Y1446100D01*
G02X804029Y1445958I-200J0D01*
G01X804020Y1445949D01*
X803947Y1445919D01*
X798124D01*
G02X797982Y1445978I0J200D01*
G01X797906Y1446054D01*
G02X797847Y1446196I141J142D01*
G01Y1450184D01*
X797982Y1450320D01*
X804088D01*
G37*
G36*
G01X804076Y1459134D02*
X804086Y1459124D01*
Y1454991D01*
Y1452109D01*
X803338Y1451361D01*
X795096D01*
X795020Y1451437D01*
Y1451847D01*
Y1452047D01*
X795027Y1452054D01*
X797262D01*
X797851Y1452643D01*
Y1455105D01*
Y1458908D01*
G02X798034Y1459107I200J0D01*
G03X798242Y1459134I-184J2229D01*
G01X804076D01*
G37*
G36*
G01X803766Y86514D02*
X812481D01*
X812834Y86161D01*
Y73377D01*
X812388Y72931D01*
X803990D01*
X803655Y73266D01*
Y86403D01*
X803766Y86514D01*
G37*
G36*
G01X839764Y388583D02*
G03I-19685J0D01*
G37*
G36*
G01X814583Y444627D02*
Y445151D01*
G02X814642Y445293I200J0D01*
G01X816263Y446914D01*
G03X816322Y447056I-141J142D01*
G01Y448571D01*
G02X816381Y448713I200J0D01*
G01X816854Y449186D01*
G02X816996Y449245I142J-141D01*
G01X819158D01*
G02X819343Y449122I0J-200D01*
G01X819366Y449065D01*
X819343Y448947D01*
X819338Y448943D01*
Y447471D01*
G03X819657Y446657I1202J1D01*
G02X819710Y446521I-147J-136D01*
G01Y440516D01*
X819116Y439922D01*
X812471D01*
X812327Y440066D01*
Y442371D01*
X814583Y444627D01*
G37*
G36*
G01X826365Y491318D02*
Y481878D01*
X824564Y480077D01*
X823468Y478981D01*
X802617D01*
X801670Y479928D01*
Y490700D01*
X803114Y492144D01*
X825539D01*
X826365Y491318D01*
G37*
G36*
G01X814541Y1218396D02*
Y1218470D01*
X815988Y1219917D01*
X816433D01*
X818696Y1217654D01*
X820698D01*
X822886Y1215466D01*
Y1214018D01*
X817843Y1208975D01*
X812501D01*
X809181Y1212295D01*
Y1213036D01*
X814541Y1218396D01*
G37*
G36*
G01X853805Y1441464D02*
G03X854102Y1441922I-919J921D01*
G01X854117Y1441962D01*
X856793Y1444638D01*
G02X856935Y1444697I142J-141D01*
G01X872246D01*
G03X872388Y1444756I0J200D01*
G01X872710Y1445078D01*
G03X872769Y1445220I-141J142D01*
G01Y1447945D01*
G02X872828Y1448087I200J0D01*
G01X873016Y1448275D01*
G02X873158Y1448334I142J-141D01*
G01X874285D01*
G02X874427Y1448275I0J-200D01*
G01X874567Y1448135D01*
G02X874626Y1447993I-141J-142D01*
G01Y1444923D01*
G03X874685Y1444781I200J0D01*
G01X880293Y1439173D01*
G03X880435Y1439114I142J141D01*
G01X893158D01*
G03X893300Y1439173I0J200D01*
G01X898606Y1444479D01*
G02X898748Y1444538I142J-141D01*
G01X914375D01*
G03X914517Y1444597I0J200D01*
G01X914754Y1444834D01*
G03X914813Y1444976I-141J142D01*
G01Y1446997D01*
G03X914754Y1447139I-200J0D01*
G01X914752Y1447141D01*
X914722Y1447214D01*
Y1448111D01*
G02X914781Y1448253I200J0D01*
G01X914807Y1448279D01*
X916172D01*
G02X916315Y1448220I1J-200D01*
G01X916338Y1448196D01*
Y1444336D01*
G03X916479Y1443747I1301J0D01*
G02X916501Y1443656I-178J-91D01*
G01Y1443059D01*
G03X916560Y1442917I200J0D01*
G01X918625Y1440853D01*
G03X918767Y1440794I142J141D01*
G01X922492D01*
G03X922634Y1440853I0J200D01*
G01X928161Y1446380D01*
G02X928303Y1446439I142J-141D01*
G01X947008D01*
G02X947208Y1446239I0J-200D01*
G01Y1444764D01*
X947199Y1444735D01*
G03X947108Y1444139I1911J-597D01*
G03X947199Y1443543I2002J1D01*
G01X947208Y1443514D01*
Y1441839D01*
G03X947708Y1441338I501J0D01*
G01X950510D01*
G03X951012Y1441839I0J502D01*
G01Y1441938D01*
G02X951212Y1442138I200J0D01*
G01X952695D01*
G03X954696Y1444139I0J2001D01*
G01Y1444141D01*
G03X953919Y1445723I-2001J-1D01*
G01X953869Y1445762D01*
X953832Y1445885D01*
X953975Y1446304D01*
G02X954164Y1446439I189J-65D01*
G01X965755D01*
G03X965897Y1446498I0J200D01*
G01X966079Y1446680D01*
G02X966221Y1446739I142J-141D01*
G01X973166D01*
G02X973366Y1446539I0J-200D01*
G01Y1445017D01*
X973357Y1444988D01*
G03X973266Y1444392I1911J-597D01*
G03X973357Y1443796I2002J1D01*
G01X973366Y1443767D01*
Y1442092D01*
G03X973868Y1441590I502J0D01*
G01X976668D01*
G03X977170Y1442092I0J502D01*
G01Y1442190D01*
G02X977370Y1442390I200J0D01*
G01X978934D01*
G03X980936Y1444392I0J2002D01*
G03X980106Y1446015I-2002J0D01*
G01X980053Y1446053D01*
X980013Y1446176D01*
X980149Y1446600D01*
G02X980340Y1446739I191J-61D01*
G01X996232D01*
G02X996432Y1446539I0J-200D01*
G01Y1445017D01*
X996423Y1444988D01*
G03X996332Y1444392I1911J-597D01*
G03X996423Y1443796I2002J1D01*
G01X996432Y1443767D01*
Y1442092D01*
G03X996934Y1441590I502J0D01*
G01X999734D01*
G03X1000236Y1442092I0J502D01*
G01Y1442190D01*
G02X1000436Y1442390I200J0D01*
G01X1002194D01*
G03X1004196Y1444392I0J2002D01*
G03X1003366Y1446015I-2002J0D01*
G01X1003313Y1446053D01*
X1003273Y1446176D01*
X1003409Y1446600D01*
G02X1003600Y1446739I191J-61D01*
G01X1019264D01*
G02X1019464Y1446539I0J-200D01*
G01Y1445117D01*
X1019455Y1445088D01*
G03X1019364Y1444492I1911J-597D01*
G03X1019455Y1443896I2002J1D01*
G01X1019464Y1443867D01*
Y1442192D01*
G03X1019966Y1441690I502J0D01*
G01X1022766D01*
G03X1023268Y1442192I0J502D01*
G01Y1442290D01*
G02X1023468Y1442490I200J0D01*
G01X1025615D01*
G03X1027616Y1444490I0J2001D01*
G01Y1444492D01*
G03X1026894Y1446031I-2001J0D01*
G02X1026834Y1446253I128J154D01*
G01X1026961Y1446607D01*
G02X1027149Y1446739I188J-68D01*
G01X1040339D01*
G02X1040481Y1446680I0J-200D01*
G01X1040595Y1446566D01*
G02X1040654Y1446424I-141J-142D01*
G01Y1442383D01*
G03X1040713Y1442241I200J0D01*
G01X1042174Y1440780D01*
G03X1042316Y1440721I142J141D01*
G01X1042968D01*
G02X1043113Y1440658I-1J-200D01*
G01X1043342Y1440416D01*
X1043369Y1440340D01*
X1043367Y1440298D01*
G03X1043365Y1440213I1500J-78D01*
G03X1044867Y1438711I1502J0D01*
G01X1044869D01*
G03X1045684Y1438952I-1J1502D01*
G02X1045934Y1438926I109J-168D01*
G01X1048568Y1436292D01*
G02X1048627Y1436150I-141J-142D01*
G01Y1425914D01*
G02X1048569Y1425774I-200J1D01*
G01X1048542Y1425746D01*
G03X1048484Y1425606I142J-141D01*
G01Y1408378D01*
G02X1048425Y1408236I-200J0D01*
G01X1042117Y1401928D01*
G02X1041975Y1401869I-142J141D01*
G01X1000617D01*
G02X1000475Y1401928I0J200D01*
G01X996107Y1406296D01*
X996055D01*
X983814Y1418537D01*
G03X983672Y1418596I-142J-141D01*
G01X951511D01*
G03X951369Y1418537I0J-200D01*
G01X941664Y1408832D01*
G02X941522Y1408773I-142J141D01*
G01X820973D01*
G02X820831Y1408832I0J200D01*
G01X813967Y1415696D01*
G02X813908Y1415838I141J142D01*
G01Y1426708D01*
G03X813849Y1426850I-200J0D01*
G01X813280Y1427419D01*
G02X813267Y1427433I140J143D01*
G03X813054Y1427646I-1163J-950D01*
G01X813046Y1427653D01*
X808018Y1432681D01*
G02X807959Y1432823I141J142D01*
G01Y1441257D01*
G03X807900Y1441399I-200J0D01*
G01X807114Y1442185D01*
X806311Y1442988D01*
Y1444526D01*
X806432Y1444647D01*
X807967D01*
X819590D01*
G03X819732Y1444706I0J200D01*
G01X820257Y1445231D01*
G03X820316Y1445373I-141J142D01*
G01Y1448438D01*
G02X820375Y1448580I200J0D01*
G01X820385Y1448590D01*
X820458Y1448620D01*
X821497D01*
G02X821639Y1448561I0J-200D01*
G01X822194Y1448006D01*
G02X822253Y1447864I-141J-142D01*
G01Y1442722D01*
G03X822312Y1442580I200J0D01*
G01X822948Y1441944D01*
G02X823007Y1441802I-141J-142D01*
G01Y1441193D01*
G03X823066Y1441051I200J0D01*
G01X826108Y1438009D01*
G03X826250Y1437950I142J141D01*
G01X842457D01*
G02X842599Y1437891I0J-200D01*
G01X843717Y1436773D01*
G03X843859Y1436714I142J141D01*
G01X848786D01*
G03X848928Y1436773I0J200D01*
G01X849192Y1437037D01*
X849232Y1437052D01*
G03X849690Y1437349I-463J1216D01*
G01X853805Y1441464D01*
G37*
G36*
G01X822554Y1626504D02*
X927703D01*
G02X927843Y1626447I0J-200D01*
G01X932332Y1621958D01*
G02X932334Y1621956I-140J-142D01*
G02X932391Y1621816I-143J-140D01*
G01Y1585734D01*
G03X932450Y1585592I200J0D01*
G01X940497Y1577545D01*
G03X940639Y1577486I142J141D01*
G01X956366D01*
G02X956506Y1577429I0J-200D01*
G01X960090Y1573845D01*
G02X960092Y1573843I-140J-142D01*
G02X960149Y1573703I-143J-140D01*
G01Y1545224D01*
G03X960186Y1545109I200J1D01*
G01X960204Y1545083D01*
X960222Y1545025D01*
Y1543190D01*
G03X960281Y1543048I200J0D01*
G01X964685Y1538644D01*
G03X964827Y1538585I142J141D01*
G01X1020051D01*
G02X1020191Y1538528I0J-200D01*
G01X1031736Y1526983D01*
G02X1031738Y1526981I-140J-142D01*
G02X1031795Y1526841I-143J-140D01*
G01Y1492779D01*
G02X1031736Y1492637I-200J0D01*
G01X1031447Y1492348D01*
X1031419Y1492319D01*
X1031345Y1492289D01*
X1019568D01*
G02X1019368Y1492489I0J200D01*
G01Y1493297D01*
G03X1019045Y1493766I-502J0D01*
G01X1019022Y1493775D01*
X1018985Y1493800D01*
X1018959Y1493828D01*
X1018942Y1493846D01*
G03X1017867Y1494298I-1074J-1050D01*
G03X1016765Y1493817I-1J-1501D01*
G01X1016689Y1493766D01*
G03X1016366Y1493297I179J-469D01*
G01Y1492475D01*
G02X1016166Y1492289I-200J15D01*
G01X981786D01*
G02X981586Y1492489I0J200D01*
G01Y1493297D01*
G03X981263Y1493766I-502J0D01*
G01X981240Y1493775D01*
X981203Y1493800D01*
X981177Y1493828D01*
X981160Y1493846D01*
G03X980085Y1494298I-1074J-1050D01*
G03X978983Y1493817I-1J-1501D01*
G01X978907Y1493766D01*
G03X978584Y1493297I179J-469D01*
G01Y1492475D01*
G02X978384Y1492289I-200J15D01*
G01X957250D01*
X957246Y1492293D01*
X947172D01*
G02X947030Y1492352I0J200D01*
G01X944500Y1494882D01*
G03X944358Y1494941I-142J-141D01*
G01X944288D01*
G02X944088Y1495141I0J200D01*
G01Y1498282D01*
G03X943911Y1498988I-1502J-1D01*
G01X943888Y1499033D01*
Y1500482D01*
G03X943386Y1500984I-502J0D01*
G01X941786D01*
G03X941284Y1500482I0J-502D01*
G01Y1499033D01*
X941261Y1498988D01*
G03X941084Y1498282I1325J-707D01*
G01Y1495141D01*
G02X940884Y1494941I-200J0D01*
G01X933345D01*
G03X933203Y1494882I0J-200D01*
G01X917090Y1478769D01*
G03X917031Y1478627I141J-142D01*
G01Y1464953D01*
G02X916972Y1464811I-200J0D01*
G01X914131Y1461970D01*
G03X914072Y1461828I141J-142D01*
G01Y1460856D01*
G02X914013Y1460714I-200J0D01*
G01X913858Y1460559D01*
X913852D01*
X913446Y1460153D01*
G03X913387Y1460011I141J-142D01*
G01Y1452480D01*
G02X913258Y1452293I-200J0D01*
G01Y1446039D01*
X913122Y1445903D01*
X900148D01*
X900000Y1446051D01*
Y1449211D01*
G02X899998Y1449237I198J28D01*
G01Y1459953D01*
G03X899939Y1460095I-200J0D01*
G01X899336Y1460698D01*
X899307Y1460726D01*
X899277Y1460800D01*
Y1462388D01*
G03X899218Y1462530I-200J0D01*
G01X894243Y1467505D01*
X894214Y1467533D01*
X894184Y1467607D01*
Y1473419D01*
G03X894125Y1473561I-200J0D01*
G01X888556Y1479130D01*
G03X888414Y1479189I-142J-141D01*
G01X880246D01*
G03X880104Y1479130I0J-200D01*
G01X872204Y1471230D01*
G03X872145Y1471088I141J-142D01*
G01Y1460906D01*
G02X872086Y1460764I-200J0D01*
G01X871408Y1460086D01*
G03X871349Y1459944I141J-142D01*
G01Y1446235D01*
X871028Y1445914D01*
X858012D01*
X857880Y1446046D01*
Y1459845D01*
G03X857821Y1459987I-200J0D01*
G01X853265Y1464543D01*
G03X853123Y1464602I-142J-141D01*
G01X828106D01*
G03X827964Y1464543I0J-200D01*
G01X826987Y1463566D01*
G03X826928Y1463424I141J-142D01*
G01Y1461709D01*
G02X826869Y1461567I-200J0D01*
G01X826720Y1461418D01*
G02X826589Y1461359I-142J141D01*
G01X824706D01*
G03X824564Y1461300I0J-200D01*
G01X822174Y1458910D01*
G03X822115Y1458768I141J-142D01*
G01Y1458536D01*
G02X821915Y1458336I-200J0D01*
G01X819764D01*
G03X819622Y1458277I0J-200D01*
G01X819287Y1457942D01*
G03X819228Y1457800I141J-142D01*
G01Y1457744D01*
X818998Y1457514D01*
Y1446396D01*
X818572Y1445971D01*
X806156D01*
X805779Y1446348D01*
Y1460109D01*
X806335Y1460665D01*
Y1468074D01*
G02X806438Y1468249I200J0D01*
G01X806888D01*
G03X807576Y1468082I688J1334D01*
G03X809078Y1469584I0J1502D01*
G01Y1469586D01*
G03X808844Y1470390I-1502J-1D01*
G01X808837Y1470402D01*
Y1473384D01*
X806778Y1475443D01*
X806772Y1475458D01*
Y1523862D01*
G02X806829Y1524002I200J0D01*
G01X816897Y1534070D01*
G03X816956Y1534212I-141J142D01*
G01Y1620906D01*
G02X817013Y1621046I200J0D01*
G01X822412Y1626445D01*
G02X822414Y1626447I142J-140D01*
G02X822554Y1626504I140J-143D01*
G37*
G36*
G01X832183Y89438D02*
X846208D01*
G02X846350Y89379I0J-200D01*
G01X846352Y89376D01*
Y74039D01*
G03X846411Y73898I200J1D01*
G01X846458Y73851D01*
G02Y73568I-141J-141D01*
G01X846271Y73381D01*
G02X846129Y73322I-142J141D01*
G01X842314D01*
X842311Y73319D01*
X821883D01*
X821825Y73377D01*
X821824Y73378D01*
X821756Y73446D01*
X821755Y73447D01*
X821697Y73505D01*
Y86363D01*
X821755Y86421D01*
X821756Y86422D01*
X821824Y86490D01*
X821825Y86491D01*
X821883Y86549D01*
X827277D01*
G03X827419Y86608I0J200D01*
G01X828252Y87441D01*
G03X828311Y87583I-141J142D01*
G01Y88917D01*
G02X828370Y89059I200J0D01*
G01X828690Y89379D01*
G02X828832Y89438I142J-141D01*
G01X831803D01*
G02X831944Y89379I-1J-200D01*
G01X832042D01*
G02X832183Y89438I142J-141D01*
G37*
G36*
G01X819692Y176789D02*
X834119D01*
X834882Y176026D01*
Y174795D01*
X835645Y174032D01*
X838753D01*
X839340Y173445D01*
Y161423D01*
X838636Y160719D01*
X820337D01*
Y160720D01*
X818341D01*
X817580Y161481D01*
Y176203D01*
X818166Y176789D01*
X819692D01*
G37*
G36*
G01X846611Y219609D02*
X848253D01*
X848645Y219217D01*
Y210795D01*
X848437Y210587D01*
X847133D01*
X847081Y210639D01*
X846689D01*
X845926D01*
X845568Y210281D01*
Y209518D01*
Y204802D01*
X835099Y194333D01*
Y189191D01*
X838736Y185554D01*
X843501D01*
X844049Y185006D01*
Y183690D01*
X845044Y182695D01*
X846978D01*
X847365Y182308D01*
X849579D01*
X849757Y182130D01*
Y181714D01*
X849444Y181401D01*
X846234D01*
X845833Y181000D01*
X845788D01*
X844495Y179707D01*
X818936D01*
X817624Y181019D01*
Y216698D01*
X818527Y217601D01*
X844603D01*
X846611Y219609D01*
G37*
G36*
G01X844971Y234621D02*
Y221520D01*
X843170Y219719D01*
X842074Y218623D01*
X819233D01*
X817505Y220351D01*
Y252516D01*
X818816Y253827D01*
X841056D01*
X844971Y249912D01*
Y234621D01*
G37*
G36*
G01X819851Y277007D02*
X827280D01*
X839731D01*
X841588Y275150D01*
X844167D01*
X844442Y274875D01*
Y272398D01*
X843892Y271848D01*
X841348D01*
X841244Y271952D01*
X837564Y268272D01*
Y265554D01*
X834366Y262356D01*
X819782D01*
X819094Y263044D01*
Y276250D01*
X819851Y277007D01*
G37*
G36*
G01X821877Y298500D02*
X834095D01*
X837564Y295031D01*
Y278899D01*
X837323Y278658D01*
X820573D01*
X819301Y279930D01*
Y295924D01*
X821877Y298500D01*
G37*
G36*
G01X820340Y447472D02*
Y448528D01*
X820367Y448555D01*
X824207D01*
G02X824349Y448496I0J-200D01*
G01X825978Y446866D01*
G03X826120Y446807I142J141D01*
G01X829251D01*
G03X829393Y446866I0J200D01*
G01X829516Y446989D01*
G03X829575Y447131I-141J142D01*
G01Y457837D01*
G03X829516Y457979I-200J0D01*
G01X829440Y458055D01*
G03X829298Y458114I-142J-141D01*
G01X825753D01*
G03X825611Y458055I0J-200D01*
G01X825377Y457821D01*
G02X825235Y457762I-142J141D01*
G01X820882D01*
X820809Y457792D01*
X820798Y457803D01*
Y463387D01*
Y464729D01*
X820862Y464793D01*
X820978Y464909D01*
G02X821120Y464968I142J-141D01*
G01X830208D01*
X832703D01*
X834238Y463433D01*
Y458982D01*
Y447451D01*
X834232Y447427D01*
Y440893D01*
X833422Y440083D01*
X821462D01*
X821062Y440483D01*
Y446584D01*
G03X821003Y446726I-200J0D01*
G01X820399Y447330D01*
G02X820340Y447472I141J142D01*
G37*
G36*
G01X836216Y476400D02*
Y466772D01*
X835967Y466523D01*
X828687D01*
X828289Y466921D01*
Y478798D01*
X827509Y479578D01*
Y490368D01*
Y491794D01*
X827818Y492103D01*
X837855D01*
X838768Y491190D01*
Y476929D01*
X838693Y476854D01*
X838362D01*
X836670D01*
X836216Y476400D01*
G37*
G36*
G01X949468Y54588D02*
X976546D01*
Y52591D01*
X949468D01*
G03X943531Y46654I0J-5937D01*
G01Y7874D01*
G02X937657Y2000I-5874J0D01*
G01X842776D01*
G02X836902Y7874I0J5874D01*
G01Y46186D01*
X838900D01*
Y7874D01*
G03X842776Y3998I3876J0D01*
G01X937657D01*
G03X941534Y7874I0J3877D01*
G01Y46654D01*
G02X949468Y54588I7934J0D01*
G37*
G36*
G01X831795Y95055D02*
X846811D01*
X846831Y95035D01*
X850836D01*
X851549Y94322D01*
Y74773D01*
X850688Y73912D01*
X848077D01*
X847813D01*
X847354Y74371D01*
Y90663D01*
X847231Y90786D01*
X846525D01*
X843770D01*
X832032D01*
X831993Y90747D01*
X831716Y91024D01*
Y94976D01*
X831795Y95055D01*
G37*
G36*
G01X851706Y276354D02*
X869279D01*
X870105Y275528D01*
Y258570D01*
Y232732D01*
X861971Y224598D01*
Y220921D01*
X859671Y218621D01*
X857671D01*
X857381Y218331D01*
Y205660D01*
X856794Y205073D01*
X849962D01*
X849454Y205581D01*
Y220421D01*
X846171Y223704D01*
Y234821D01*
X846337Y234987D01*
Y250246D01*
X849501Y253410D01*
X849537D01*
X851757Y255630D01*
Y268925D01*
X848748Y271934D01*
X846444D01*
X845928Y272450D01*
Y274738D01*
X846151Y274961D01*
X850313D01*
X851706Y276354D01*
G37*
G36*
G01X846960Y276095D02*
X847699D01*
X847725Y276122D01*
X849926D01*
X851378Y277574D01*
X853013D01*
X853047Y277540D01*
X860218D01*
X860250Y277572D01*
X867981D01*
X869796Y279387D01*
Y287118D01*
Y296369D01*
X868970Y297195D01*
X852738D01*
X850623Y295080D01*
Y282733D01*
X848440Y280550D01*
X846650Y278760D01*
Y276405D01*
X846960Y276095D01*
G37*
G36*
G01X833010Y977981D02*
G03I-577J0D01*
G37*
G36*
G01X900478Y1107671D02*
Y1155805D01*
G03X900419Y1155947I-200J0D01*
G01X899011Y1157355D01*
G03X898869Y1157414I-142J-141D01*
G01X867160D01*
G03X867018Y1157355I0J-200D01*
G01X864496Y1154833D01*
G03X864437Y1154691I141J-142D01*
G01Y1121059D01*
G02X864378Y1120917I-200J0D01*
G01X862588Y1119127D01*
G02X862446Y1119068I-142J141D01*
G01X844491D01*
G02X844349Y1119127I0J200D01*
G01X840125Y1123352D01*
G02X840066Y1123494I141J142D01*
G01Y1171150D01*
G02X840125Y1171292I200J0D01*
G01X842638Y1173805D01*
G02X842780Y1173864I142J-141D01*
G01X976310D01*
G02X976452Y1173805I0J-200D01*
G01X977267Y1172990D01*
G02X977326Y1172848I-141J-142D01*
G01Y1166457D01*
G03X977385Y1166315I200J0D01*
G01X980675Y1163025D01*
G02X980734Y1162883I-141J-142D01*
G01Y1107742D01*
G02X980675Y1107600I-200J0D01*
G01X980355Y1107280D01*
G02X980213Y1107221I-142J141D01*
G01X964905D01*
G02X964763Y1107280I0J200D01*
G01X964514Y1107529D01*
G02X964455Y1107671I141J142D01*
G01Y1155805D01*
G03X964396Y1155947I-200J0D01*
G01X962988Y1157355D01*
G03X962846Y1157414I-142J-141D01*
G01X931137D01*
G03X930995Y1157355I0J-200D01*
G01X928473Y1154833D01*
G03X928414Y1154691I141J-142D01*
G01Y1120554D01*
G02X928355Y1120412I-200J0D01*
G01X927070Y1119127D01*
G02X926928Y1119068I-142J141D01*
G01X920749D01*
G03X920607Y1119009I0J-200D01*
G01X919754Y1118156D01*
G03X919695Y1118014I141J-142D01*
G01Y1107916D01*
G02X919636Y1107774I-200J0D01*
G01X919142Y1107280D01*
G02X919000Y1107221I-142J141D01*
G01X900928D01*
G02X900786Y1107280I0J200D01*
G01X900537Y1107529D01*
G02X900478Y1107671I141J142D01*
G37*
G36*
G01X857088Y399162D02*
X863401D01*
G03X863601Y399362I0J200D01*
G01Y405722D01*
G03X863547Y405859I-201J0D01*
G01X856942D01*
G03X856888Y405722I146J-137D01*
G01Y399362D01*
G03X857088Y399162I200J0D01*
G37*
G36*
G01X854633Y462899D02*
X914852D01*
G02X914994Y462840I0J-200D01*
G01X915002Y462832D01*
G02X915061Y462690I-141J-142D01*
G01Y448233D01*
G02X915002Y448091I-200J0D01*
G01X914687Y447776D01*
X914659Y447747D01*
X914585Y447717D01*
X885468D01*
G03X885326Y447658I0J-200D01*
G01X883222Y445554D01*
G03X883163Y445412I141J-142D01*
G01Y431574D01*
X883159Y431570D01*
Y411794D01*
G03X883218Y411652I200J0D01*
G01X885108Y409762D01*
G02X885167Y409620I-141J-142D01*
G01Y408144D01*
G02X885108Y408002I-200J0D01*
G01X884834Y407728D01*
X884806Y407699D01*
X884732Y407669D01*
X876531D01*
X876300Y407900D01*
Y409700D01*
Y410373D01*
X875873Y410800D01*
X875200D01*
X872568D01*
X871568Y411800D01*
Y419084D01*
G03X871509Y419226I-200J0D01*
G01X870220Y420515D01*
G03X870078Y420574I-142J-141D01*
G01X865703D01*
G03X865561Y420515I0J-200D01*
G01X864546Y419500D01*
X863014Y417967D01*
G03X862955Y417825I141J-142D01*
G01Y413226D01*
G02X862896Y413084I-200J0D01*
G01X862466Y412654D01*
X862438Y412625D01*
X862364Y412595D01*
X861174D01*
G03X861032Y412536I0J-200D01*
G01X860155Y411659D01*
G03X860096Y411517I141J-142D01*
G01Y409749D01*
G02X860037Y409607I-200J0D01*
G01X859768Y409338D01*
G03X859709Y409196I141J-142D01*
G01Y407148D01*
G02X859650Y407006I-200J0D01*
G01X859590Y406946D01*
X859562Y406917D01*
X859488Y406887D01*
X859198D01*
G02X859056Y406946I0J200D01*
G01X858861Y407141D01*
X858832Y407169D01*
X858802Y407243D01*
Y410327D01*
G03X858743Y410469I-200J0D01*
G01X858401Y410811D01*
Y410856D01*
X857167Y412090D01*
X857138Y412118D01*
X857108Y412192D01*
Y412232D01*
Y412233D01*
X856023Y413318D01*
X855994Y413346D01*
X855964Y413420D01*
Y419074D01*
G03X855905Y419216I-200J0D01*
G01X854680Y420441D01*
G03X854538Y420500I-142J-141D01*
G01X853726D01*
G02X853584Y420559I0J200D01*
G01X851503Y422640D01*
X851474Y422668D01*
X851444Y422742D01*
Y429879D01*
G03X851429Y429955I-200J0D01*
G01X851412Y429996D01*
G02X851397Y430072I185J76D01*
G01Y459577D01*
G02X851510Y459757I200J0D01*
G03X852415Y460739I-777J1625D01*
G01X852431Y460780D01*
X854491Y462840D01*
G02X854633Y462899I142J-141D01*
G37*
G36*
G01X891791Y465911D02*
Y476469D01*
X890575Y477685D01*
X857187D01*
X854651Y475149D01*
Y471205D01*
X853946Y470500D01*
Y465044D01*
X854628Y464362D01*
X890242D01*
X891791Y465911D01*
G37*
G36*
G01X850072Y761000D02*
G03I-572J0D01*
G37*
G36*
G01Y779000D02*
G03I-572J0D01*
G37*
G36*
G01Y797000D02*
G03I-572J0D01*
G37*
G36*
G01Y815000D02*
G03I-572J0D01*
G37*
G36*
G01X970084Y1000425D02*
X974713D01*
X974716Y1000422D01*
X976072D01*
G02X976272Y1000236I0J-201D01*
G01Y999456D01*
X980310D01*
G02X980437Y999398I-14J-199D01*
G01X980451Y999384D01*
X980481Y999311D01*
Y995925D01*
G02X980422Y995783I-200J0D01*
G01X976893Y992254D01*
G02X976751Y992195I-142J141D01*
G01X968647D01*
G02X968505Y992254I0J200D01*
G01X967091Y993668D01*
G03X966949Y993727I-142J-141D01*
G01X942602D01*
G03X942460Y993668I0J-200D01*
G01X940309Y991517D01*
G02X940167Y991458I-142J141D01*
G01X937657D01*
G03X937515Y991399I0J-200D01*
G01X926825Y980709D01*
G02X926683Y980650I-142J141D01*
G01X850018D01*
G02X849876Y980709I0J200D01*
G01X849866Y980718D01*
Y987314D01*
G02X849925Y987455I200J-1D01*
G01X849941Y987471D01*
G02X850083Y987530I142J-141D01*
G01X867272D01*
X868992D01*
Y989943D01*
X869012Y990002D01*
X869033Y990029D01*
G03X869136Y990333I-398J304D01*
G01Y994334D01*
G03X868635Y994836I-502J0D01*
G01X868049D01*
Y994879D01*
X867138Y995790D01*
G03X866996Y995849I-142J-141D01*
G01X865700D01*
G02X865558Y995908I0J200D01*
G01X864525Y996941D01*
G02X864466Y997083I141J142D01*
G01Y999758D01*
G02X864525Y999900I200J0D01*
G01X864878Y1000253D01*
G02X865020Y1000312I142J-141D01*
G01X868297D01*
G03X868439Y1000371I0J200D01*
G01X868446Y1000378D01*
X913261D01*
X913334Y1000409D01*
X913350Y1000425D01*
X945228D01*
G02X945428Y1000239I0J-201D01*
G01Y998634D01*
X951142D01*
Y1000239D01*
G02X951342Y1000425I200J-15D01*
G01X952108D01*
G02X952308Y1000239I0J-201D01*
G01Y998682D01*
X958022D01*
Y1000239D01*
G02X958222Y1000425I200J-15D01*
G01X963972D01*
G02X964170Y1000249I0J-199D01*
G01Y998732D01*
X969886D01*
Y1000249D01*
G02X970084Y1000425I198J-23D01*
G37*
G36*
G01X909662Y1070112D02*
Y1028626D01*
X906816Y1025780D01*
Y1017980D01*
X906529Y1017693D01*
X901225D01*
X899738Y1016206D01*
X892452D01*
X851613D01*
X849570Y1018249D01*
Y1067562D01*
X852797Y1070789D01*
X855877D01*
X864727D01*
G02X864869Y1070730I0J-200D01*
G01X864952Y1070647D01*
G02X865011Y1070506I-141J-142D01*
G01Y1031182D01*
G03X865069Y1031041I200J0D01*
G01X865079Y1031030D01*
G02X865138Y1030889I-141J-142D01*
G01Y1029358D01*
G03X865197Y1029216I200J0D01*
G01X866336Y1028077D01*
G03X866478Y1028018I142J141D01*
G01X891821D01*
G03X891963Y1028077I0J200D01*
G01X893920Y1030034D01*
G03X893979Y1030176I-141J142D01*
G01Y1070706D01*
Y1072745D01*
X895857Y1074623D01*
X906745D01*
X907251Y1074117D01*
X909662Y1071706D01*
Y1070112D01*
G37*
G36*
G01X850945Y1092592D02*
X879100D01*
X882168Y1089524D01*
G02X882309Y1089466I0J-200D01*
G01X882959Y1088816D01*
G02X883017Y1088675I-142J-141D01*
G01Y1086123D01*
G03X883033Y1086045I200J0D01*
G01X883065Y1085969D01*
X883067Y1085935D01*
G03X883126Y1085807I200J14D01*
G01X892445Y1076488D01*
G02X892504Y1076346I-141J-142D01*
G01Y1031106D01*
G02X892445Y1030964I-200J0D01*
G01X891842Y1030361D01*
X891814Y1030332D01*
X891740Y1030302D01*
X867307D01*
G02X867165Y1030361I0J200D01*
G01X866071Y1031455D01*
X866042Y1031483D01*
X866012Y1031557D01*
Y1071201D01*
X864223Y1072990D01*
X851252D01*
X849931Y1074311D01*
Y1089571D01*
G03X849996Y1089570I56J1502D01*
G03X851499Y1091073I0J1503D01*
G03X850735Y1092382I-1503J0D01*
G01X850945Y1092592D01*
G37*
G36*
G01X867874Y1155777D02*
X898832D01*
X898906Y1155747D01*
X898934Y1155718D01*
X899138Y1155514D01*
G02X899197Y1155372I-141J-142D01*
G01Y1106244D01*
X899167Y1106170D01*
X899138Y1106142D01*
X898300Y1105304D01*
G02X898158Y1105245I-142J141D01*
G01X883989D01*
G03X883847Y1105186I0J-200D01*
G01X882424Y1103763D01*
G03X882365Y1103621I141J-142D01*
G01Y1098106D01*
G03X882424Y1097964I200J0D01*
G01X883649Y1096739D01*
G03X883791Y1096680I142J141D01*
G01X888054D01*
G02X888196Y1096621I0J-200D01*
G01X889269Y1095548D01*
G02X889328Y1095406I-141J-142D01*
G01Y1094592D01*
G03X889387Y1094450I200J0D01*
G01X890264Y1093573D01*
G03X890406Y1093514I142J141D01*
G01X891662D01*
G02X891739Y1093499I1J-200D01*
G01X892302Y1093266D01*
G03X892536Y1093190I579J1385D01*
G01X892538D01*
X892563Y1093185D01*
X892614Y1093157D01*
X892687Y1093127D01*
X894815D01*
X894889Y1093097D01*
X894917Y1093068D01*
X894977Y1093008D01*
G02X895036Y1092866I-141J-142D01*
G01Y1092576D01*
X895006Y1092502D01*
X894977Y1092474D01*
X894782Y1092279D01*
G02X894640Y1092220I-142J141D01*
G01X892063D01*
G03X891956Y1092189I0J-200D01*
G01X891955Y1092188D01*
G02X891849Y1092158I-105J170D01*
G01X891763D01*
G03X891623Y1092100I1J-200D01*
G01X891115Y1091593D01*
X890107Y1090585D01*
X890079Y1090556D01*
X890005Y1090526D01*
X882914D01*
G02X882772Y1090585I0J200D01*
G01X879563Y1093794D01*
G03X879421Y1093853I-142J-141D01*
G01X851684D01*
G02X851512Y1093952I1J200D01*
G01X851310Y1094295D01*
X851309Y1094401D01*
X851335Y1094448D01*
G03X851525Y1095179I-1311J731D01*
G03X850023Y1096681I-1502J0D01*
G03X849713Y1096649I-2J-1502D01*
G01X849669Y1096639D01*
X849581Y1096661D01*
X849305Y1096885D01*
G02X849231Y1097040I126J155D01*
G01Y1116539D01*
G02X849290Y1116681I200J0D01*
G01X850183Y1117574D01*
G02X850325Y1117633I142J-141D01*
G01X864042D01*
G03X864184Y1117692I0J200D01*
G01X865867Y1119375D01*
G03X865926Y1119517I-141J142D01*
G01Y1153869D01*
X865956Y1153943D01*
X865985Y1153971D01*
X867732Y1155718D01*
G02X867874Y1155777I142J-141D01*
G37*
G36*
G01X916505Y463293D02*
X921495D01*
X921546Y463242D01*
Y446684D01*
X923419Y444811D01*
X932460D01*
X933131Y444140D01*
Y394933D01*
X929123Y390925D01*
X896120D01*
X890658Y396387D01*
X888075D01*
X888014Y396448D01*
X884092D01*
X884052Y396488D01*
Y398392D01*
X884032Y398412D01*
X883512Y398933D01*
X874287D01*
X873554Y399666D01*
Y406493D01*
X873921Y406860D01*
X875663D01*
G02X875805Y406801I0J-200D01*
G01X875879Y406727D01*
G03X876021Y406668I142J141D01*
G01X885107D01*
G03X885249Y406726I1J200D01*
G01X885324Y406802D01*
G02X885466Y406860I141J-142D01*
G01X885472D01*
X885513Y406843D01*
X885942D01*
X885959Y406860D01*
X885979D01*
X889203Y410084D01*
G02X889345Y410143I142J-141D01*
G01X900296D01*
G02X900438Y410084I0J-200D01*
G01X900486Y410036D01*
G03X900628Y409977I142J141D01*
G01X914789D01*
G02X914834Y409972I1J-200D01*
G01X915673D01*
X916640Y410939D01*
Y419014D01*
X915905Y419749D01*
Y419793D01*
X913088Y422610D01*
Y425236D01*
X913073Y425250D01*
Y442969D01*
X916294Y446190D01*
X916420Y446315D01*
Y463208D01*
X916505Y463293D01*
G37*
G36*
G01X870029Y978003D02*
G03I-639J0D01*
G37*
G36*
G01X897655Y1183477D02*
X878313D01*
X874731D01*
X874409Y1183799D01*
Y1198799D01*
X877626Y1202016D01*
X882164Y1206554D01*
Y1213336D01*
X882434Y1213606D01*
X882974D01*
X883354Y1213226D01*
Y1200176D01*
X884479Y1199051D01*
X884484D01*
X885819Y1197716D01*
X885919Y1197616D01*
X891843D01*
X893935D01*
X894388D01*
X894609Y1197837D01*
X894713Y1197941D01*
Y1202223D01*
X894858Y1202368D01*
X896946D01*
X898502Y1200812D01*
Y1184324D01*
X897655Y1183477D01*
G37*
G36*
G01X867891Y1271969D02*
X900948D01*
X903448Y1269469D01*
Y1228842D01*
X902995Y1228389D01*
X896612D01*
X896275Y1228726D01*
Y1264007D01*
X893946Y1266336D01*
X884670D01*
X880094Y1261760D01*
Y1209894D01*
X879944Y1209744D01*
X867664D01*
X867109Y1210299D01*
Y1219649D01*
G03X868227Y1225118I-12818J5469D01*
G03X866204Y1232349I-13935J0D01*
G01Y1256137D01*
X866184Y1256157D01*
Y1260463D01*
X866192Y1260471D01*
Y1270270D01*
X867891Y1271969D01*
G37*
G36*
G01X871843Y1208744D02*
X879854D01*
X880024Y1208574D01*
Y1207194D01*
X879414Y1206584D01*
X871817D01*
X871636Y1206765D01*
Y1208537D01*
X871843Y1208744D01*
G37*
G36*
G01X900179Y411343D02*
X887078D01*
X885277Y413144D01*
X884181Y414240D01*
Y437081D01*
Y444862D01*
X885621Y446302D01*
X910951D01*
X911836Y445417D01*
Y421505D01*
X915316Y418025D01*
Y412169D01*
X914490Y411343D01*
X914367D01*
X900179D01*
G37*
G36*
G01X915104Y463832D02*
Y465704D01*
X913612Y467196D01*
X895293D01*
X895082Y466985D01*
Y464214D01*
X895497Y463799D01*
X915071D01*
X915104Y463832D01*
G37*
G36*
G01X908407Y568531D02*
Y566081D01*
X908337Y566011D01*
X907367D01*
X907307Y566071D01*
Y568641D01*
Y568961D01*
X907047Y569221D01*
X890847D01*
X889937Y570131D01*
Y589171D01*
X890097Y589331D01*
X909757D01*
X910017Y589071D01*
Y570661D01*
X910637Y570041D01*
X913087D01*
X913227Y569901D01*
Y568971D01*
X913147Y568891D01*
X911097D01*
X910747Y569241D01*
X908627D01*
X908407Y569021D01*
Y568531D01*
G37*
G36*
G01X888667Y587754D02*
Y586554D01*
X886534D01*
X886105Y586983D01*
X881528D01*
X881329Y587182D01*
X881106D01*
X880379Y587909D01*
Y588620D01*
X880944Y589185D01*
X881903D01*
X882479Y588609D01*
Y588009D01*
X883137Y587351D01*
X886074D01*
X886477Y587754D01*
X886667D01*
X888667D01*
G37*
G36*
G01Y577911D02*
Y576711D01*
X886569D01*
X886140Y577140D01*
X883127D01*
X882606Y576619D01*
X880433D01*
X880248Y576804D01*
Y577787D01*
X880569Y578108D01*
X882627D01*
X883226Y577509D01*
X886075D01*
X886477Y577911D01*
X886667D01*
X888667D01*
G37*
G36*
G01X892693Y590580D02*
X891493D01*
Y592723D01*
X891930Y593160D01*
Y595932D01*
X890650Y597212D01*
Y600565D01*
X891156Y601071D01*
X892267D01*
X892974Y600364D01*
Y596767D01*
X892298Y596091D01*
Y593090D01*
X892693Y592695D01*
Y590580D01*
G37*
G36*
G01X896175Y1096988D02*
X902518D01*
X902685Y1096821D01*
Y1090511D01*
X902505Y1090331D01*
X896241D01*
X896074Y1090498D01*
Y1096887D01*
X896175Y1096988D01*
G37*
G36*
G01X898182Y1079081D02*
X907549D01*
G02X907691Y1079022I0J-200D01*
G01X908059Y1078654D01*
G02X908118Y1078512I-141J-142D01*
G01Y1076058D01*
G02X908059Y1075916I-200J0D01*
G01X907718Y1075575D01*
G02X907576Y1075516I-142J141D01*
G01X907351D01*
G02X907210Y1075575I1J200D01*
G01X907190Y1075594D01*
X907117Y1075624D01*
X895525D01*
G03X895384Y1075566I0J-200D01*
G01X895364Y1075546D01*
X895291Y1075516D01*
X894696D01*
G02X894554Y1075575I0J200D01*
G01X894267Y1075862D01*
G02X894208Y1076004I141J142D01*
G01Y1078079D01*
G02X894267Y1078221I200J0D01*
G01X894836Y1078790D01*
G02X894977Y1078848I141J-142D01*
G01X897784D01*
G03X897925Y1078907I-1J200D01*
G01X898041Y1079022D01*
G02X898182Y1079081I142J-141D01*
G37*
G36*
G01X892096Y1091157D02*
X894980D01*
X895051Y1091086D01*
Y1090250D01*
Y1089961D01*
X889999Y1084909D01*
X885564D01*
X884019Y1086454D01*
Y1088930D01*
X884608Y1089519D01*
X890458D01*
X892096Y1091157D01*
G37*
G36*
G01X895926Y1089286D02*
X896699D01*
X896869Y1089116D01*
Y1086817D01*
X897710Y1085976D01*
Y1084419D01*
X897734Y1084395D01*
Y1080132D01*
X897452Y1079850D01*
X893634D01*
X890440Y1083044D01*
Y1083800D01*
X895926Y1089286D01*
G37*
G36*
G01X886323Y1201046D02*
X884714D01*
X884504Y1201256D01*
Y1214556D01*
X883057Y1216003D01*
X881202Y1217858D01*
Y1253104D01*
X881981Y1253883D01*
X894236D01*
X895188Y1252931D01*
Y1236009D01*
Y1231250D01*
Y1229924D01*
X893694Y1228430D01*
X892368D01*
X891300Y1227362D01*
X885724Y1221786D01*
Y1205666D01*
X886691Y1204699D01*
Y1201414D01*
X886323Y1201046D01*
G37*
G36*
G01X887485Y1208485D02*
X887600Y1208600D01*
X890700D01*
X891026Y1208273D01*
Y1206966D01*
X893613Y1204379D01*
Y1199945D01*
X893375Y1199707D01*
X891428D01*
X891147D01*
X890671Y1200183D01*
Y1203060D01*
X887485Y1206246D01*
Y1208485D01*
G37*
G36*
G01X895393Y1227209D02*
G03I-506J0D01*
G37*
G36*
G01X892587Y1255481D02*
X885765D01*
X885092Y1256154D01*
Y1261562D01*
Y1263616D01*
X885271Y1263795D01*
X885585Y1264109D01*
X892902D01*
X893216Y1263795D01*
X893575Y1263436D01*
Y1261303D01*
Y1255738D01*
X893318Y1255481D01*
X892587D01*
G37*
G36*
G01X914402Y470245D02*
Y472463D01*
Y472910D01*
X914299Y473013D01*
X913852D01*
X905427D01*
X905223Y472809D01*
Y469939D01*
X905467Y469695D01*
X913852D01*
X914402Y470245D01*
G37*
G36*
G01X914435Y474677D02*
Y476468D01*
X914313Y476590D01*
X900148D01*
X899293Y475735D01*
Y469894D01*
X899538Y469649D01*
X902976D01*
X903221Y469894D01*
Y473476D01*
X904172Y474427D01*
X914359D01*
X914435Y474503D01*
Y474677D01*
G37*
G36*
G01X912311Y565087D02*
X916647D01*
G02X916787Y565030I0J-200D01*
G01X916788Y565029D01*
X920317Y561500D01*
G02X920376Y561358I-141J-142D01*
G01Y558488D01*
G03X920435Y558346I200J0D01*
G01X928590Y550191D01*
G02X928649Y550049I-141J-142D01*
G01Y530516D01*
X928619Y530442D01*
X928590Y530414D01*
X925748Y527572D01*
G02X925606Y527513I-142J141D01*
G01X907212D01*
X907138Y527543D01*
X907110Y527572D01*
X905937Y528745D01*
G02X905878Y528887I141J142D01*
G01Y536727D01*
G02X905937Y536869I200J0D01*
G01X907413Y538345D01*
G03X907472Y538487I-141J142D01*
G01Y542800D01*
G03X907434Y542917I-200J0D01*
G01X907415Y542943D01*
X907396Y543002D01*
Y545988D01*
G02X907455Y546130I200J0D01*
G01X908134Y546809D01*
G03X908193Y546951I-141J142D01*
G01Y547761D01*
G02X908252Y547903I200J0D01*
G01X908366Y548017D01*
G03X908736Y548909I-892J893D01*
G01Y558345D01*
G02X908790Y558482I200J0D01*
G01X908872Y558568D01*
G02X908997Y558630I146J-137D01*
G03X909025Y558633I-146J1495D01*
G01X909068Y558638D01*
X909150Y558612D01*
X909406Y558385D01*
G02X909410Y558381I-139J-143D01*
G01X909411D01*
G02X909474Y558235I-137J-146D01*
G01Y557352D01*
G03X909836Y556478I1236J0D01*
G01X912433Y553880D01*
G02X912440Y553873I-138J-145D01*
G02X912492Y553738I-148J-135D01*
G01Y551381D01*
X912476Y551325D01*
X912460Y551301D01*
X912446Y551278D01*
G03X912226Y550496I1282J-783D01*
G01Y550469D01*
G03X912879Y549256I1502J26D01*
G02X912966Y549091I-113J-165D01*
G01Y548700D01*
G02X912792Y548598I-174J98D01*
G01X912344D01*
X912260D01*
X912144Y548480D01*
Y546216D01*
X912260Y546098D01*
X912334D01*
X912792D01*
G02X912966Y545996I0J-200D01*
G01Y545067D01*
G03X913190Y544529I761J1D01*
G01X914482Y543236D01*
G02X914526Y543171I-141J-143D01*
G01X914835Y542422D01*
G02X914850Y542346I-185J-76D01*
G01Y537484D01*
G02X914792Y537343I-200J0D01*
G01X914116Y536667D01*
G02X913974Y536608I-142J141D01*
G01X908680D01*
G03X908178Y536106I0J-502D01*
G01Y531306D01*
G03X908680Y530804I502J0D01*
G01X914580D01*
G03X915082Y531306I0J502D01*
G01Y535396D01*
G02X915141Y535538I200J0D01*
G01X916150Y536548D01*
G03X916373Y537073I-538J538D01*
G02X916702Y537223I200J-3D01*
G03X916848Y537137I324J383D01*
G03X917026Y537104I179J469D01*
G01X922926D01*
G03X923428Y537606I0J502D01*
G01Y539085D01*
G02X923475Y539214I200J0D01*
G01X923501Y539246D01*
G03X923997Y539468I-42J760D01*
G01X924497Y539968D01*
G03X924720Y540506I-537J538D01*
G01Y543775D01*
G03X924497Y544313I-760J0D01*
G01X923947Y544863D01*
G03X923409Y545086I-538J-537D01*
G01X919236D01*
G02X919141Y545110I0J200D01*
G01X919088Y545139D01*
X919053Y545169D01*
X919040Y545189D01*
G03X918675Y545554I-1229J-864D01*
G01X918655Y545567D01*
X918625Y545602D01*
X918596Y545655D01*
G02X918572Y545750I176J95D01*
G01Y545994D01*
G02X918747Y546098I175J-96D01*
G01X919196D01*
X919278D01*
X919396Y546216D01*
Y546288D01*
Y548398D01*
Y548480D01*
X919278Y548598D01*
X919206D01*
X918552D01*
G02X918352Y548784I0J200D01*
G01Y548834D01*
X918186D01*
G02X918012Y548936I0J200D01*
G01Y550071D01*
X918084Y550173D01*
X918144Y550195D01*
G03X918736Y551033I-298J839D01*
G01Y551886D01*
Y551970D01*
X918618Y552086D01*
X918617D01*
X918500Y552204D01*
Y553954D01*
G02X918686Y554154I200J0D01*
G01X918736D01*
Y555207D01*
G03X917818Y556097I-891J0D01*
G01X917815Y556096D01*
X916959D01*
G02X916918Y556104I18J200D01*
G01X916518Y556504D01*
G02X916460Y556645I142J141D01*
G01Y556741D01*
G03X916236Y557279I-761J-1D01*
G01X915792Y557724D01*
X915763Y557817D01*
X915772Y557867D01*
G03X915798Y558143I-1476J278D01*
G03X914623Y559609I-1502J0D01*
G01X914596Y559615D01*
X914545Y559642D01*
X913033Y561155D01*
G02X912990Y561220I142J141D01*
G01X912062Y563460D01*
G02X912056Y563477I185J75D01*
G02X912046Y563538I190J62D01*
G01Y564037D01*
G03X911945Y564528I-1232J3D01*
G01X911925Y564575D01*
X911933Y564675D01*
X912144Y564996D01*
G02X912166Y565024I167J-109D01*
G02X912307Y565087I146J-137D01*
G01X912311D01*
G37*
G36*
G01X899367Y567980D02*
X900567D01*
Y565797D01*
X900172Y565402D01*
Y561317D01*
X900265Y561222D01*
Y559254D01*
X899977Y558966D01*
X899534D01*
X898352D01*
X898109Y559209D01*
Y560439D01*
X899804Y562134D01*
X899805Y565398D01*
X899367Y565836D01*
Y567980D01*
G37*
G36*
G01X911267Y586554D02*
Y587754D01*
X913334D01*
X913700Y587388D01*
X913707D01*
X913758Y587337D01*
X915956D01*
Y586988D01*
X913891D01*
X913884Y586981D01*
X913823Y586920D01*
X913457Y586554D01*
X913267D01*
X911267D01*
G37*
G36*
G01X911288Y578690D02*
Y579890D01*
X913398D01*
X913811Y579477D01*
X917747D01*
X918579Y580309D01*
X919679D01*
X919702Y580286D01*
X921412D01*
X922407Y579291D01*
Y578091D01*
X922107Y577791D01*
X920297D01*
X919679Y578409D01*
X918479D01*
X917779Y579109D01*
X913897D01*
X913478Y578690D01*
X913288D01*
X911288D01*
G37*
G36*
G01X910410Y590580D02*
X909210D01*
Y592664D01*
X909652Y593104D01*
X909654Y593106D01*
Y595860D01*
X910015D01*
Y593165D01*
X910410Y592770D01*
Y592580D01*
Y590580D01*
G37*
G36*
G01X898640Y590600D02*
X897440D01*
Y592783D01*
X897835Y593178D01*
Y597958D01*
X897083Y598710D01*
Y600326D01*
X897159Y600402D01*
X897568Y600811D01*
X898256D01*
X898731D01*
X899227Y600315D01*
Y598267D01*
X898758Y597798D01*
Y596868D01*
X898204Y596314D01*
Y593118D01*
X898640Y592682D01*
Y592600D01*
Y590600D01*
G37*
G36*
G01X907349Y962433D02*
G03I-639J0D01*
G37*
G36*
G01X905300Y1297398D02*
G03I-597J0D01*
G37*
G36*
G01X922556Y115094D02*
X923612D01*
X923639Y115067D01*
Y111227D01*
G02X923580Y111085I-200J0D01*
G01X921950Y109456D01*
G03X921891Y109314I141J-142D01*
G01Y106183D01*
G03X921950Y106041I200J0D01*
G01X922073Y105918D01*
G03X922215Y105859I142J141D01*
G01X932921D01*
G03X933063Y105918I0J200D01*
G01X933139Y105994D01*
G03X933198Y106136I-141J142D01*
G01Y109681D01*
G03X933139Y109823I-200J0D01*
G01X932905Y110057D01*
G02X932846Y110199I141J142D01*
G01Y114552D01*
X932876Y114625D01*
X932887Y114636D01*
X938471D01*
X939813D01*
X939877Y114572D01*
X939993Y114456D01*
G02X940052Y114314I-141J-142D01*
G01Y105226D01*
G02X939993Y105084I-200J0D01*
G01X939322Y104413D01*
X939239Y104383D01*
X939194Y104388D01*
G03X939012Y104396I-174J-1893D01*
G01X936430D01*
X935144D01*
X934398Y103650D01*
Y101528D01*
X934066Y101196D01*
X922535D01*
X922511Y101202D01*
X915331D01*
X914636Y101897D01*
Y102887D01*
Y114049D01*
G02X914695Y114191I200J0D01*
G01X914817Y114313D01*
G02X914959Y114372I142J-141D01*
G01X921668D01*
G03X921810Y114431I0J200D01*
G01X922414Y115035D01*
G02X922556Y115094I142J-141D01*
G37*
G36*
G01X925921Y119235D02*
X929367D01*
X932203Y122071D01*
X938250D01*
X938620Y121701D01*
Y116118D01*
X938139Y115637D01*
X928465D01*
X926109D01*
X925761Y115985D01*
Y119075D01*
X925921Y119235D01*
G37*
G36*
G01X914818Y120851D02*
X920235D01*
G02X920377Y120792I0J-200D01*
G01X921998Y119171D01*
G03X922140Y119112I142J141D01*
G01X923655D01*
G02X923797Y119053I0J-200D01*
G01X924270Y118580D01*
G02X924329Y118438I-141J-142D01*
G01Y116276D01*
G02X924206Y116091I-200J0D01*
G01X924149Y116068D01*
X924031Y116091D01*
X924027Y116096D01*
X922555D01*
G03X921741Y115777I1J-1202D01*
G02X921605Y115724I-136J147D01*
G01X914759D01*
G02X914617Y115783I0J200D01*
G01X914602Y115798D01*
X914572Y115871D01*
Y120605D01*
G02X914631Y120747I200J0D01*
G01X914676Y120792D01*
G02X914818Y120851I142J-141D01*
G37*
G36*
G01X925159Y195956D02*
X934599D01*
X936400Y194155D01*
X937496Y193059D01*
Y172208D01*
X936549Y171261D01*
X925777D01*
X924333Y172705D01*
Y195130D01*
X925159Y195956D01*
G37*
G36*
G01X924887Y212416D02*
X935655D01*
G02X935797Y212357I0J-200D01*
G01X937439Y210715D01*
G02X937498Y210573I-141J-142D01*
G01Y208739D01*
G03X937557Y208597I200J0D01*
G01X937729Y208425D01*
G03X937871Y208366I142J141D01*
G01X947824D01*
X947939Y208253D01*
X947941Y208171D01*
G03X949443Y206704I1502J35D01*
G03X950945Y208206I0J1502D01*
G03X950854Y208721I-1503J0D01*
G01X950834Y208776D01*
X950859Y208889D01*
X952944Y210974D01*
G02X953086Y211033I142J-141D01*
G01X961862D01*
G02X962004Y210974I0J-200D01*
G01X962228Y210750D01*
G02X962287Y210608I-141J-142D01*
G01Y198380D01*
G02X962228Y198238I-200J0D01*
G01X961634Y197644D01*
G02X961492Y197585I-142J141D01*
G01X954241D01*
G02X954099Y197644I0J200D01*
G01X951363Y200380D01*
G03X951221Y200439I-142J-141D01*
G01X946014D01*
G02X945873Y200498I1J200D01*
G01X945797Y200573D01*
G03X945656Y200632I-142J-141D01*
G01X936570D01*
G03X936429Y200573I1J-200D01*
G01X936353Y200498D01*
G02X936212Y200439I-142J141D01*
G01X935406D01*
G03X935264Y200380I0J-200D01*
G01X934936Y200052D01*
G03X934877Y199910I141J-142D01*
G01Y198512D01*
G02X934818Y198370I-200J0D01*
G01X933663Y197215D01*
G02X933521Y197156I-142J141D01*
G01X924871D01*
G02X924729Y197215I0J200D01*
G01X924187Y197757D01*
G02X924128Y197899I141J142D01*
G01Y211657D01*
G02X924187Y211799I200J0D01*
G01X924745Y212357D01*
G02X924887Y212416I142J-141D01*
G37*
G36*
G01X917590Y464338D02*
Y480579D01*
X917447Y480722D01*
X915636D01*
X915473Y480559D01*
Y469467D01*
Y468722D01*
X916450Y467745D01*
Y464358D01*
X916512Y464296D01*
X917548D01*
X917590Y464338D01*
G37*
G36*
G01X914374Y804591D02*
X919996D01*
X920486Y804101D01*
Y801508D01*
X918630Y799652D01*
X913144D01*
X912666Y800130D01*
Y801358D01*
X913782Y802474D01*
Y803999D01*
X914374Y804591D01*
G37*
G36*
G01X919287Y964717D02*
G03I-639J0D01*
G37*
G36*
G01X916068Y969885D02*
G03I-577J0D01*
G37*
G36*
G01X976705Y1071122D02*
Y1031925D01*
Y1017227D01*
X976146Y1016668D01*
X956226D01*
X955628Y1016070D01*
X914087D01*
X913547Y1016610D01*
Y1067562D01*
X916774Y1070789D01*
X919854D01*
X928704D01*
G02X928846Y1070730I0J-200D01*
G01X928929Y1070647D01*
G02X928988Y1070506I-141J-142D01*
G01Y1031182D01*
G03X929046Y1031041I200J0D01*
G01X929056Y1031030D01*
G02X929115Y1030889I-141J-142D01*
G01Y1029358D01*
G03X929174Y1029216I200J0D01*
G01X930313Y1028077D01*
G03X930455Y1028018I142J141D01*
G01X955798D01*
G03X955940Y1028077I0J200D01*
G01X957897Y1030034D01*
G03X957956Y1030176I-141J142D01*
G01Y1069412D01*
Y1073489D01*
X958428Y1073961D01*
X975305D01*
X976705Y1072561D01*
Y1071122D01*
G37*
G36*
G01X947042Y1085969D02*
X947044Y1085935D01*
G03X947103Y1085807I200J14D01*
G01X956422Y1076488D01*
G02X956481Y1076346I-141J-142D01*
G01Y1031106D01*
G02X956422Y1030964I-200J0D01*
G01X955819Y1030361D01*
X955791Y1030332D01*
X955717Y1030302D01*
X931284D01*
G02X931142Y1030361I0J200D01*
G01X930048Y1031455D01*
X930019Y1031483D01*
X929989Y1031557D01*
Y1071834D01*
X929222Y1072601D01*
X922184D01*
X920862Y1073923D01*
Y1090450D01*
X922729Y1092317D01*
X943355D01*
X943533Y1092139D01*
Y1092136D01*
X946145Y1089524D01*
G02X946286Y1089466I0J-200D01*
G01X946936Y1088816D01*
G02X946994Y1088675I-142J-141D01*
G01Y1086123D01*
G03X947010Y1086045I200J0D01*
G01X947042Y1085969D01*
G37*
G36*
G01X931851Y1155777D02*
X962769D01*
G02X962911Y1155718I0J-200D01*
G01X963115Y1155514D01*
G02X963174Y1155372I-141J-142D01*
G01Y1106284D01*
G02X963115Y1106142I-200J0D01*
G01X962277Y1105304D01*
X962249Y1105275D01*
X962175Y1105245D01*
X947966D01*
G03X947824Y1105186I0J-200D01*
G01X946401Y1103763D01*
G03X946342Y1103621I141J-142D01*
G01Y1098106D01*
G03X946401Y1097964I200J0D01*
G01X947626Y1096739D01*
G03X947768Y1096680I142J141D01*
G01X952031D01*
G02X952173Y1096621I0J-200D01*
G01X953246Y1095548D01*
G02X953305Y1095406I-141J-142D01*
G01Y1094592D01*
G03X953364Y1094450I200J0D01*
G01X954241Y1093573D01*
G03X954383Y1093514I142J141D01*
G01X955639D01*
G02X955716Y1093499I1J-200D01*
G01X956279Y1093266D01*
G03X956513Y1093190I579J1385D01*
G01X956515D01*
X956540Y1093185D01*
X956591Y1093157D01*
X956664Y1093127D01*
X958792D01*
X958866Y1093097D01*
X958894Y1093068D01*
X958954Y1093008D01*
G02X959013Y1092866I-141J-142D01*
G01Y1092576D01*
X958983Y1092502D01*
X958954Y1092474D01*
X958759Y1092279D01*
G02X958617Y1092220I-142J141D01*
G01X956040D01*
G03X955933Y1092189I0J-200D01*
G01X955932Y1092188D01*
G02X955826Y1092158I-105J170D01*
G01X955740D01*
G03X955600Y1092100I1J-200D01*
G01X955092Y1091593D01*
X954084Y1090585D01*
X954056Y1090556D01*
X953982Y1090526D01*
X948823D01*
X948822Y1090528D01*
X946640D01*
G02X946499Y1090587I1J200D01*
G01X944534Y1092551D01*
Y1092554D01*
X943828Y1093260D01*
G03X943687Y1093318I-141J-142D01*
G01X923554D01*
G02X923413Y1093377I1J200D01*
G01X920936Y1095854D01*
X920907Y1095882D01*
X920877Y1095956D01*
Y1117435D01*
G02X920936Y1117577I200J0D01*
G01X921268Y1117909D01*
G02X921410Y1117968I142J-141D01*
G01X927895D01*
G03X928037Y1118027I0J200D01*
G01X929844Y1119834D01*
G03X929903Y1119976I-141J142D01*
G01Y1153829D01*
G02X929962Y1153971I200J0D01*
G01X931709Y1155718D01*
G02X931851Y1155777I142J-141D01*
G37*
G36*
G01X931868Y1271969D02*
X964925D01*
X967425Y1269469D01*
Y1234960D01*
X967379Y1234914D01*
Y1229420D01*
X966251Y1228292D01*
X960623D01*
X960252Y1228663D01*
Y1234931D01*
Y1264007D01*
X957899Y1266360D01*
X948671D01*
X944071Y1261760D01*
Y1209971D01*
X943844Y1209744D01*
X925036D01*
X924051Y1210729D01*
Y1271551D01*
X924469Y1271969D01*
X931868D01*
G37*
G36*
G01X938518Y172169D02*
Y195588D01*
X936510Y197596D01*
Y199238D01*
X936902Y199630D01*
X945324D01*
X945532Y199422D01*
Y198118D01*
X945480Y198066D01*
Y197674D01*
Y197061D01*
X945988Y196553D01*
X946601D01*
X950827D01*
X952155Y195225D01*
Y190999D01*
Y172540D01*
X951000Y171385D01*
X939302D01*
X938518Y172169D01*
G37*
G36*
G01X935145Y371840D02*
X958882D01*
G02X959024Y371781I0J-200D01*
G01X961349Y369456D01*
G02X961408Y369314I-141J-142D01*
G01Y356500D01*
G02X961349Y356358I-200J0D01*
G01X959266Y354275D01*
G02X959124Y354216I-142J141D01*
G01X956154D01*
G03X956012Y354157I0J-200D01*
G01X937072D01*
G02X936995Y354172I-1J200D01*
G01X936882Y354219D01*
G02X936818Y354262I77J184D01*
G01X935855Y355225D01*
G02X935796Y355367I141J142D01*
G01Y357263D01*
G03X935737Y357405I-200J0D01*
G01X935685Y357457D01*
G02X935666Y357718I141J141D01*
G03X935966Y358618I-1202J901D01*
G03X935963Y358704I-1502J-9D01*
G01X935961Y358746D01*
X935988Y358822D01*
X936217Y359064D01*
G02X936362Y359126I145J-138D01*
G01X939801D01*
G03X940296Y359227I0J1262D01*
G01X940333Y359244D01*
X942734D01*
G03X942934Y359444I0J199D01*
G01Y360066D01*
X942943D01*
G03X943389Y359589I1294J763D01*
G02X943476Y359424I-113J-165D01*
G01Y358340D01*
G03X943700Y357802I761J1D01*
G01X944201Y357301D01*
G03X944739Y357078I538J537D01*
G01X947827D01*
G03X948365Y357301I0J760D01*
G01X948990Y357926D01*
G03X949159Y358180I-537J540D01*
G01X949182Y358238D01*
X949282Y358306D01*
X950452D01*
G03X950954Y358807I0J502D01*
G01Y362407D01*
G03X950452Y362908I-501J0D01*
G01X946452D01*
G03X945950Y362407I0J-502D01*
G01Y362205D01*
G02X945829Y362021I-200J0D01*
G01X945435Y361852D01*
X945319Y361873D01*
X945275Y361915D01*
G03X944238Y362330I-1037J-1088D01*
G03X943275Y361980I1J-1502D01*
G02X943138Y361934I-128J154D01*
G01X943013Y361939D01*
G02X942885Y361992I8J200D01*
G03X942274Y362230I-606J-652D01*
G01X941096D01*
G03X940653Y362115I-5J-890D01*
G01X940630Y362102D01*
X940582Y362090D01*
X940241D01*
G03X939349Y361720I1J-1262D01*
G01X939337Y361708D01*
G02X939196Y361650I-141J142D01*
G01X936180D01*
G02X936039Y361708I0J200D01*
G01X935569Y362178D01*
G03X935290Y362389I-893J-891D01*
G01X935238Y362417D01*
X935184Y362517D01*
X935208Y362935D01*
G02X935331Y363108I200J-12D01*
G01X935877Y363334D01*
X935931Y363341D01*
X935957Y363337D01*
G03X936175Y363321I219J1486D01*
G03X937016Y363578I1J1502D01*
G02X937155Y363611I113J-165D01*
G01X937278Y363594D01*
G02X937400Y363529I-27J-198D01*
G03X938068Y363234I662J595D01*
G01X939246D01*
G03X940142Y364124I6J890D01*
G01Y364978D01*
G03X939942Y365178I-200J0D01*
G01X939906D01*
Y366824D01*
G02X940106Y367024I200J0D01*
G01X940988D01*
G02X941188Y366824I0J-200D01*
G01Y366396D01*
G03X941388Y366196I200J-1D01*
G01X943486D01*
G03X943686Y366396I0J199D01*
G01Y366967D01*
X943749Y367065D01*
X943802Y367090D01*
G03X944018Y367242I-323J689D01*
G01X944242Y367465D01*
G02X944383Y367524I142J-141D01*
G01X952186D01*
G02X952327Y367465I-1J-200D01*
G01X952584Y367208D01*
G02X952642Y367067I-142J-141D01*
G01Y363925D01*
G03X953144Y363424I501J0D01*
G01X957144D01*
G03X957646Y363925I0J502D01*
G01Y367525D01*
G03X957144Y368026I-501J0D01*
G01X954002D01*
G02X953861Y368085I1J200D01*
G01X953122Y368823D01*
G03X952584Y369046I-538J-537D01*
G01X943985D01*
G03X943722Y369000I-2J-761D01*
G02X943539Y369023I-69J188D01*
G03X943026Y369182I-508J-731D01*
G01X941848D01*
G03X941033Y368664I-6J-890D01*
G01X941008Y368610D01*
X940911Y368548D01*
X940186D01*
X940087Y368611D01*
X940063Y368665D01*
G03X939246Y369188I-811J-367D01*
G01X938068D01*
G03X937172Y368298I-6J-890D01*
G01Y367444D01*
G03X937372Y367244I200J0D01*
G01X937408D01*
Y366533D01*
G02X937314Y366364I-200J1D01*
G01X936982Y366156D01*
X936879Y366151D01*
X936832Y366173D01*
G03X936175Y366325I-658J-1350D01*
G03X934970Y365720I0J-1503D01*
G01X934954Y365698D01*
X934911Y365665D01*
X933858Y365229D01*
G02X933671Y365247I-77J185D01*
G01X933629Y365275D01*
X933582Y365362D01*
Y367458D01*
G02X933782Y367658I200J0D01*
G01X934047D01*
G03X935549Y369160I0J1502D01*
G03X934581Y370564I-1502J0D01*
G01X934533Y370582D01*
X934468Y370658D01*
X934387Y371036D01*
G02X934427Y371204I196J42D01*
G01X934434Y371212D01*
X935003Y371781D01*
G02X935005Y371783I142J-140D01*
G02X935145Y371840I140J-143D01*
G37*
G36*
G01X937828Y443561D02*
Y471322D01*
X938155Y471649D01*
X942062D01*
X942632Y471079D01*
Y443504D01*
X942404Y443276D01*
X941858D01*
X938113D01*
X937828Y443561D01*
G37*
G36*
G01X953896Y592103D02*
X940689D01*
X940404Y591818D01*
Y556112D01*
Y555516D01*
X940791Y555129D01*
X941142Y554778D01*
X949249D01*
X949828Y554199D01*
X954447D01*
X955445Y555197D01*
Y590554D01*
X953896Y592103D01*
G37*
G36*
G01X945130Y614747D02*
X943339D01*
X943217Y614625D01*
Y600460D01*
X944072Y599605D01*
X949913D01*
X950158Y599850D01*
Y603288D01*
X949913Y603533D01*
X946331D01*
X945380Y604484D01*
Y614671D01*
X945304Y614747D01*
X945130D01*
G37*
G36*
G01X955398Y617902D02*
X939228D01*
X939085Y617759D01*
Y615948D01*
X939248Y615785D01*
X950340D01*
X951085D01*
X952062Y616762D01*
X955362D01*
X955500Y616900D01*
Y617800D01*
X955398Y617902D01*
G37*
G36*
G01X961661Y1183477D02*
X942290D01*
X938708D01*
X938386Y1183799D01*
Y1198799D01*
X941603Y1202016D01*
X946141Y1206554D01*
Y1213336D01*
X946411Y1213606D01*
X946951D01*
X947331Y1213226D01*
Y1200176D01*
X948456Y1199051D01*
X948461D01*
X949796Y1197716D01*
X949896Y1197616D01*
X955820D01*
X957912D01*
X958365D01*
X958586Y1197837D01*
X958690Y1197941D01*
Y1202223D01*
X958835Y1202368D01*
X960567D01*
X962640Y1200295D01*
Y1184029D01*
X962088Y1183477D01*
X961661D01*
G37*
G36*
G01X935820Y1208744D02*
X943831D01*
X944001Y1208574D01*
Y1207194D01*
X943391Y1206584D01*
X935794D01*
X935613Y1206765D01*
Y1208537D01*
X935820Y1208744D01*
G37*
G36*
G01X944288Y1482139D02*
X951824D01*
G02X951966Y1482080I0J-200D01*
G01X953644Y1480402D01*
G02X953703Y1480260I-141J-142D01*
G01Y1451575D01*
G02X953644Y1451433I-200J0D01*
G01X952809Y1450598D01*
G02X952667Y1450539I-142J141D01*
G01X930490D01*
G02X930348Y1450598I0J200D01*
G01X929394Y1451552D01*
G02X929335Y1451694I141J142D01*
G01Y1480950D01*
G02X929394Y1481092I200J0D01*
G01X930382Y1482080D01*
G02X930524Y1482139I142J-141D01*
G01X940884D01*
G02X941084Y1481939I0J-200D01*
G01Y1477022D01*
G03X941261Y1476316I1502J1D01*
G02X941284Y1476222I-177J-93D01*
G01Y1474822D01*
G03X941786Y1474320I502J0D01*
G01X943386D01*
G03X943888Y1474822I0J502D01*
G01Y1476222D01*
G02X943911Y1476316I200J1D01*
G03X944088Y1477022I-1325J707D01*
G01Y1481939D01*
G02X944288Y1482139I200J0D01*
G37*
G36*
G01X1035042Y1558912D02*
Y1549416D01*
G02X1034983Y1549274I-200J0D01*
G01X1029590Y1543881D01*
G02X1029448Y1543822I-142J141D01*
G01X1004925D01*
G02X1004783Y1543881I0J200D01*
G01X1002426Y1546238D01*
G02X1002367Y1546380I141J142D01*
G01Y1569139D01*
G03X1002308Y1569281I-200J0D01*
G01X998153Y1573437D01*
G03X998011Y1573496I-142J-141D01*
G01X972310D01*
G02X972168Y1573555I0J200D01*
G01X962292Y1583431D01*
G03X962150Y1583490I-142J-141D01*
G01X942870D01*
G02X942728Y1583549I0J200D01*
G01X938157Y1588120D01*
G02X938098Y1588262I141J142D01*
G01Y1628572D01*
G02X938157Y1628714I200J0D01*
G01X941866Y1632423D01*
G02X942008Y1632482I142J-141D01*
G01X1037599D01*
G02X1037741Y1632423I0J-200D01*
G01X1042190Y1627974D01*
G02X1042249Y1627832I-141J-142D01*
G01Y1566285D01*
G02X1042190Y1566143I-200J0D01*
G01X1035101Y1559054D01*
G03X1035042Y1558912I141J-142D01*
G37*
G36*
G01X953766Y86514D02*
X962481D01*
X962834Y86161D01*
Y73377D01*
X962388Y72931D01*
X953990D01*
X953655Y73266D01*
Y86403D01*
X953766Y86514D01*
G37*
G36*
G01X962283Y545147D02*
Y533484D01*
X965566Y530201D01*
Y529803D01*
Y518852D01*
G02X965507Y518710I-200J0D01*
G01X965459Y518662D01*
G03X965400Y518520I141J-142D01*
G01Y504632D01*
G02X965341Y504490I-200J0D01*
G01X964262Y503411D01*
G02X964120Y503352I-142J141D01*
G01X950633D01*
G02X950491Y503411I0J200D01*
G01X949825Y504077D01*
G02X949766Y504219I141J142D01*
G01Y532166D01*
X951871Y534271D01*
Y534788D01*
Y535061D01*
X951899Y535089D01*
X954240D01*
X954356Y535205D01*
Y535259D01*
Y544824D01*
Y545347D01*
X954695Y545686D01*
X955218D01*
X961744D01*
X962283Y545147D01*
G37*
G36*
G01X956965Y615406D02*
X971809D01*
X972338Y614877D01*
Y607338D01*
X971500Y606500D01*
Y594000D01*
X972338Y593162D01*
Y573133D01*
X975837Y569634D01*
X982137D01*
X982959Y570456D01*
X984968Y572466D01*
Y577231D01*
X985516Y577779D01*
X986832D01*
X987827Y578774D01*
Y580708D01*
X988214Y581095D01*
Y583479D01*
X988279Y583544D01*
X989084D01*
X989121Y583507D01*
Y579964D01*
X989522Y579563D01*
Y579518D01*
X990815Y578225D01*
Y570737D01*
X988615Y568537D01*
Y556856D01*
X988644Y556827D01*
Y551391D01*
X990409Y549626D01*
X993736D01*
X994739Y548623D01*
Y536737D01*
X993991Y535989D01*
X967134D01*
X965126Y533981D01*
X963484D01*
X963092Y534373D01*
Y542795D01*
X963300Y543003D01*
X964604D01*
X964656Y542951D01*
X965048D01*
X965908D01*
X966169Y543212D01*
Y544072D01*
Y548298D01*
X966163D01*
X965295Y549166D01*
X958170D01*
X956928Y550408D01*
Y554389D01*
X956910Y554407D01*
Y615351D01*
X956965Y615406D01*
G37*
G36*
G01X955784Y615416D02*
X954103D01*
X952611Y613924D01*
Y596550D01*
X952933Y596228D01*
Y596180D01*
X955736D01*
X955799D01*
X955908Y596289D01*
Y615292D01*
X955784Y615416D01*
G37*
G36*
G01X949562Y614714D02*
X947344D01*
X946897D01*
X946794Y614611D01*
Y614164D01*
Y605739D01*
X946998Y605535D01*
X949868D01*
X950112Y605779D01*
Y614164D01*
X949562Y614714D01*
G37*
G36*
G01X973123Y621858D02*
X956565D01*
X956514Y621807D01*
Y616817D01*
X956599Y616732D01*
X973492D01*
X977919Y612305D01*
X997169D01*
X997778Y612914D01*
Y624584D01*
X996257Y626105D01*
X977370D01*
X973123Y621858D01*
G37*
G36*
G01X976246Y638140D02*
X948485D01*
X948158Y638467D01*
Y642374D01*
X948728Y642944D01*
X976303D01*
X976531Y642716D01*
Y642170D01*
Y638425D01*
X976246Y638140D01*
G37*
G36*
G01X956481Y860376D02*
G03I-514J0D01*
G37*
G36*
G01X983174Y1083154D02*
X989147D01*
G02X989267Y1083114I0J-200D01*
G02X989288Y1083096I-119J-160D01*
G01Y1031878D01*
G02X989229Y1031737I-200J1D01*
G01X987488Y1029996D01*
G03X987118Y1029104I892J-893D01*
G01Y1025960D01*
G02X987060Y1025819I-200J0D01*
G01X983020Y1021779D01*
G03X982961Y1021637I141J-142D01*
G01Y1019673D01*
G03X983020Y1019531I200J0D01*
G01X985989Y1016562D01*
X986016Y1016511D01*
X986022Y1016481D01*
G03X986522Y1015452I2218J442D01*
G02X986570Y1015322I-152J-130D01*
G01Y995039D01*
G02X986511Y994897I-200J0D01*
G01X979498Y987884D01*
G02X979356Y987825I-142J141D01*
G01X960929D01*
G02X960729Y988025I0J200D01*
G01Y991464D01*
G02X960788Y991606I200J0D01*
G01X961588Y992406D01*
G02X961730Y992465I142J-141D01*
G01X965780D01*
G02X965922Y992406I0J-200D01*
G01X967154Y991174D01*
G03X967296Y991115I142J141D01*
G01X974909D01*
X974910Y991116D01*
X977837D01*
G03X977979Y991175I0J200D01*
G01X981531Y994727D01*
X981601Y994757D01*
X981640Y994758D01*
G03X982130Y995259I-11J501D01*
G01Y995366D01*
X982161Y995440D01*
X982168Y995447D01*
Y1011721D01*
G03X982109Y1011863I-200J0D01*
G01X978663Y1015309D01*
G02X978604Y1015451I141J142D01*
G01Y1029361D01*
G02X978663Y1029503I200J0D01*
G01X982403Y1033242D01*
G03X982462Y1033384I-141J142D01*
G01Y1075382D01*
G02X982472Y1075445I200J1D01*
G01X982501Y1075531D01*
X982518Y1075556D01*
G03X982870Y1076658I-1549J1102D01*
G01Y1076660D01*
G03X982518Y1077762I-1901J0D01*
G01X982501Y1077787D01*
X982472Y1077873D01*
G02X982462Y1077936I190J62D01*
G01Y1079881D01*
X982478Y1079919D01*
G03X982628Y1080659I-1752J740D01*
G03X982478Y1081399I-1902J0D01*
G01X982462Y1081437D01*
Y1082442D01*
G02X982521Y1082584I200J0D01*
G01X983032Y1083095D01*
G02X983174Y1083154I142J-141D01*
G37*
G36*
G01X960152Y1096988D02*
X966495D01*
X966662Y1096821D01*
Y1090511D01*
X966482Y1090331D01*
X960218D01*
X960051Y1090498D01*
Y1096887D01*
X960152Y1096988D01*
G37*
G36*
G01X959903Y1089286D02*
X960676D01*
X960846Y1089116D01*
Y1086817D01*
X961687Y1085976D01*
Y1084419D01*
X961711Y1084395D01*
Y1080132D01*
X961429Y1079850D01*
X957611D01*
X954417Y1083044D01*
Y1083800D01*
X959903Y1089286D01*
G37*
G36*
G01X956073Y1091157D02*
X958957D01*
X959028Y1091086D01*
Y1090250D01*
Y1089961D01*
X953976Y1084909D01*
X949541D01*
X947996Y1086454D01*
Y1088930D01*
X948585Y1089519D01*
X954435D01*
X956073Y1091157D01*
G37*
G36*
G01X951462Y1207215D02*
Y1208605D01*
X951621Y1208764D01*
X954791D01*
X955003Y1208551D01*
Y1207553D01*
Y1206966D01*
X957590Y1204379D01*
Y1199945D01*
X957352Y1199707D01*
X955405D01*
X955124D01*
X954648Y1200183D01*
Y1203060D01*
X951462Y1206246D01*
Y1207215D01*
G37*
G36*
G01X950300Y1201046D02*
X948691D01*
X948481Y1201256D01*
Y1214556D01*
X947034Y1216003D01*
X945179Y1217858D01*
Y1253104D01*
X945714Y1253639D01*
X958457D01*
X959165Y1252931D01*
Y1236009D01*
Y1231250D01*
Y1229924D01*
X957671Y1228430D01*
X956345D01*
X955277Y1227362D01*
X949701Y1221786D01*
Y1205666D01*
X950668Y1204699D01*
Y1201414D01*
X950300Y1201046D01*
G37*
G36*
G01X959370Y1227209D02*
G03I-506J0D01*
G37*
G36*
G01X956564Y1255481D02*
X949742D01*
X949069Y1256154D01*
Y1261562D01*
Y1263616D01*
X949248Y1263795D01*
X949562Y1264109D01*
X956879D01*
X957193Y1263795D01*
X957552Y1263436D01*
Y1261303D01*
Y1255738D01*
X957295Y1255481D01*
X956564D01*
G37*
G36*
G01X1019771Y1487179D02*
X1038865D01*
G02X1039007Y1487120I0J-200D01*
G01X1039166Y1486961D01*
G02X1039204Y1486909I-141J-143D01*
G01X1039246Y1486823D01*
X1039250Y1486790D01*
G03X1046915Y1470037I31211J4150D01*
G01Y1452158D01*
X1045718Y1450961D01*
X958816D01*
X958794Y1450939D01*
X955821D01*
G02X955679Y1450998I0J200D01*
G01X955197Y1451480D01*
X955168Y1451508D01*
X955138Y1451582D01*
Y1485156D01*
G02X955197Y1485298I200J0D01*
G01X957019Y1487120D01*
G02X957161Y1487179I142J-141D01*
G01X978383D01*
G02X978583Y1486979I0J-200D01*
G01Y1486181D01*
G03X978584Y1486154I502J5D01*
G01Y1486149D01*
Y1486059D01*
X978600Y1486043D01*
X978616Y1486003D01*
G03X978907Y1485712I469J178D01*
G01X978947Y1485696D01*
X979405Y1485239D01*
G03X979546Y1485180I142J141D01*
G01X980624D01*
G03X980765Y1485239I-1J200D01*
G01X981223Y1485696D01*
X981263Y1485712D01*
G03X981569Y1486048I-178J469D01*
G01X981574Y1486064D01*
G03X981586Y1486133I-188J68D01*
G01Y1486149D01*
Y1486154D01*
G03X981587Y1486181I-501J32D01*
G01Y1486777D01*
G02X981646Y1486919I200J0D01*
G01X981847Y1487120D01*
G02X981989Y1487179I142J-141D01*
G01X1016166D01*
G02X1016365Y1486999I0J-200D01*
G01Y1486181D01*
G03X1016366Y1486149I502J0D01*
G01Y1486059D01*
X1016385Y1486040D01*
G03X1016726Y1485699I482J141D01*
G01X1017187Y1485239D01*
G03X1017328Y1485180I142J141D01*
G01X1018406D01*
G03X1018547Y1485239I-1J200D01*
G01X1019008Y1485699D01*
G03X1019354Y1486061I-141J482D01*
G01X1019355Y1486062D01*
G03X1019368Y1486133I-187J71D01*
G01Y1486149D01*
G03X1019369Y1486181I-501J32D01*
G01Y1486796D01*
G02X1019427Y1486918I199J-20D01*
G01X1019629Y1487120D01*
G02X1019771Y1487179I142J-141D01*
G37*
G36*
G01X982183Y89438D02*
X996208D01*
G02X996350Y89379I0J-200D01*
G01X996352Y89376D01*
Y74039D01*
G03X996411Y73898I200J1D01*
G01X996458Y73851D01*
G02Y73568I-141J-141D01*
G01X996271Y73381D01*
G02X996129Y73322I-142J141D01*
G01X992314D01*
X992311Y73319D01*
X971883D01*
X971825Y73377D01*
X971824Y73378D01*
X971756Y73446D01*
X971755Y73447D01*
X971697Y73505D01*
Y86363D01*
X971755Y86421D01*
X971756Y86422D01*
X971824Y86490D01*
X971825Y86491D01*
X971883Y86549D01*
X977277D01*
G03X977419Y86608I0J200D01*
G01X978252Y87441D01*
G03X978311Y87583I-141J142D01*
G01Y88917D01*
G02X978370Y89059I200J0D01*
G01X978690Y89379D01*
G02X978832Y89438I142J-141D01*
G01X981803D01*
G02X981944Y89379I-1J-200D01*
G01X982042D01*
G02X982183Y89438I142J-141D01*
G37*
G36*
G01X969692Y176789D02*
X984119D01*
X984882Y176026D01*
Y174795D01*
X985645Y174032D01*
X988753D01*
X989340Y173445D01*
Y161423D01*
X988636Y160719D01*
X970337D01*
Y160720D01*
X968341D01*
X967580Y161481D01*
Y176203D01*
X968166Y176789D01*
X969692D01*
G37*
G36*
G01X996611Y219609D02*
X998253D01*
X998645Y219217D01*
Y210795D01*
X998437Y210587D01*
X997133D01*
X997081Y210639D01*
X996689D01*
X995989D01*
X995568Y210218D01*
Y209518D01*
Y204802D01*
X985099Y194333D01*
Y189191D01*
X988736Y185554D01*
X993501D01*
X994049Y185006D01*
Y183690D01*
X995044Y182695D01*
X996978D01*
X997365Y182308D01*
X999579D01*
X999757Y182130D01*
Y181714D01*
X999444Y181401D01*
X996234D01*
X995833Y181000D01*
X995788D01*
X994495Y179707D01*
X968936D01*
X967624Y181019D01*
Y216698D01*
X968527Y217601D01*
X994603D01*
X996611Y219609D01*
G37*
G36*
G01X994971Y234621D02*
Y221520D01*
X993170Y219719D01*
X992074Y218623D01*
X969233D01*
X967505Y220351D01*
Y252516D01*
X968816Y253827D01*
X991056D01*
X994971Y249912D01*
Y234621D01*
G37*
G36*
G01X969851Y277007D02*
X977280D01*
X989731D01*
X991588Y275150D01*
X994167D01*
X994442Y274875D01*
Y272398D01*
X993892Y271848D01*
X991348D01*
X991244Y271952D01*
X987564Y268272D01*
Y265554D01*
X984366Y262356D01*
X969782D01*
X969094Y263044D01*
Y276250D01*
X969851Y277007D01*
G37*
G36*
G01X972844Y299467D02*
X983128D01*
X987564Y295031D01*
Y278899D01*
X987323Y278658D01*
X970573D01*
X969301Y279930D01*
Y295924D01*
X972844Y299467D01*
G37*
G36*
G01X972602Y325959D02*
X985851D01*
G02X985884Y325956I-2J-200D01*
G02X985991Y325902I-32J-197D01*
G01X988305Y323588D01*
G03X988447Y323529I142J141D01*
G01X990406D01*
G02X990530Y323486I0J-200D01*
G03X991299Y323218I769J969D01*
G01X993017D01*
X993042Y323211D01*
G03X993118Y323193I329J1218D01*
G01X993119D01*
G03X993372Y323168I250J1236D01*
G01X995779D01*
G03X996032Y323193I3J1261D01*
G01X996033D01*
G03X996109Y323211I-253J1236D01*
G01X996134Y323218D01*
X1001562D01*
X1001677Y323105D01*
X1001679Y323023D01*
G03X1001793Y322483I1502J35D01*
G01Y322482D01*
X1001794Y322480D01*
G02X1001775Y322294I-186J-75D01*
G01X1001607Y322044D01*
G02X1001441Y321954I-167J110D01*
G01X1000447D01*
G03X999909Y321731I0J-760D01*
G01X997381Y319204D01*
X997172Y318995D01*
G02X997031Y318936I-142J141D01*
G01X994976D01*
G02X994880Y318961I1J200D01*
G01X994829Y318989D01*
X994796Y319019D01*
X994782Y319038D01*
G03X992322I-1230J-862D01*
G01X992308Y319019D01*
X992275Y318989D01*
X992224Y318961D01*
G02X992128Y318936I-97J175D01*
G01X991757D01*
G02X991654Y319092I97J176D01*
G01Y319643D01*
X991538Y319760D01*
X989272D01*
X989156Y319643D01*
Y319092D01*
G02X989053Y318936I-200J20D01*
G01X988124D01*
G03X987586Y318713I0J-760D01*
G01X986410Y317538D01*
X986313Y317441D01*
G02X986248Y317397I-143J141D01*
G01X985852Y317233D01*
X985451Y317068D01*
G02X985375Y317052I-78J184D01*
G01X980528D01*
G02X980400Y317111I14J200D01*
G01X979672Y317839D01*
G02X979664Y317875I191J61D01*
G01Y323223D01*
G03X979163Y323724I-501J0D01*
G01X974363D01*
G03X973862Y323223I0J-501D01*
G01Y317323D01*
G03X974363Y316822I501J0D01*
G01X978507D01*
G02X978543Y316814I-25J-199D01*
G01X978710Y316647D01*
X979605Y315753D01*
G03X979927Y315561I539J538D01*
G01X979967Y315549D01*
X980029Y315497D01*
X980180Y315202D01*
G02X980190Y315045I-179J-90D01*
G01Y315044D01*
G03X980180Y315014I471J-174D01*
G01Y315013D01*
G03X980162Y314877I483J-133D01*
G01Y308977D01*
G03X980663Y308476I501J0D01*
G01X982146D01*
G02X982302Y308373I-20J-200D01*
G01Y308186D01*
G03X982525Y307648I760J0D01*
G01X983025Y307148D01*
G03X983308Y306969I538J538D01*
G03X983563Y306924I258J716D01*
G01X986943D01*
G03X987198Y306969I-3J761D01*
G03X987481Y307148I-255J717D01*
G01X988055Y307722D01*
G03X988278Y308260I-537J538D01*
G01Y312668D01*
G02X988303Y312764I200J-1D01*
G01X988332Y312816D01*
X988361Y312850D01*
X988381Y312863D01*
G03X988756Y313243I-865J1228D01*
G01X988785Y313285D01*
X988871Y313330D01*
X989053D01*
G02X989156Y313175I-97J-176D01*
G01Y312708D01*
G03X989356Y312508I200J0D01*
G01X991454D01*
G03X991654Y312708I0J199D01*
G01Y313370D01*
G02X991853Y313550I199J-20D01*
G01X991890D01*
Y313736D01*
G02X991993Y313892I200J-20D01*
G01X993128D01*
X993231Y313819D01*
X993252Y313759D01*
G03X994090Y313168I838J299D01*
G01X994944D01*
G03X995144Y313368I0J200D01*
G01Y313404D01*
X997030D01*
G02X997210Y313205I-20J-199D01*
G01Y313168D01*
X998261D01*
G03X999154Y314062I3J890D01*
G01Y314895D01*
G02X999213Y315037I200J0D01*
G01X1000686Y316510D01*
X1000779Y316539D01*
X1000829Y316530D01*
G03X1001105Y316504I278J1476D01*
G03X1002607Y318006I0J1502D01*
G03X1002581Y318282I-1502J-2D01*
G01X1002572Y318332D01*
X1002601Y318425D01*
X1003090Y318914D01*
G02X1003155Y318958I143J-141D01*
G01X1006205Y320221D01*
G02X1006282Y320236I76J-185D01*
G01X1007381D01*
G02X1007522Y320178I0J-200D01*
G01X1008362Y319338D01*
G02X1008421Y319196I-141J-142D01*
G01Y316021D01*
X1008391Y315947D01*
X1008362Y315919D01*
X1006176Y313733D01*
G02X1006035Y313674I-142J141D01*
G01X1005374D01*
G03X1004705Y313482I0J-1262D01*
G01X1004682Y313468D01*
X1004600Y313443D01*
G02X1004543Y313435I-56J192D01*
G01X1002318D01*
G03X1002176Y313376I0J-200D01*
G01X992768Y303968D01*
G02X992626Y303909I-142J141D01*
G01X976585D01*
X976511Y303939D01*
X976483Y303968D01*
X970946Y309505D01*
G02X970887Y309647I141J142D01*
G01Y324244D01*
G02X970946Y324386I200J0D01*
G01X972460Y325900D01*
G02X972602Y325959I142J-141D01*
G37*
G36*
G01X975942Y456982D02*
X973302D01*
X972643Y457641D01*
Y460485D01*
Y461933D01*
X972638Y461937D01*
Y462774D01*
X971917Y463495D01*
X967928D01*
X967212Y462779D01*
Y462195D01*
Y460910D01*
Y458716D01*
Y454556D01*
X967747Y454021D01*
X976532D01*
X976543Y454032D01*
Y456381D01*
X975942Y456982D01*
G37*
G36*
G01X976597Y475886D02*
Y485326D01*
X978398Y487127D01*
X979494Y488223D01*
X1000345D01*
X1001292Y487276D01*
Y476504D01*
X999848Y475060D01*
X977423D01*
X976597Y475886D01*
G37*
G36*
G01X964187Y488854D02*
Y499374D01*
Y501186D01*
X964774Y501773D01*
X971606D01*
X972114Y501265D01*
Y499252D01*
Y487471D01*
Y486284D01*
X972813Y485585D01*
X974000D01*
X975397Y484188D01*
Y483142D01*
Y475515D01*
X974737Y474855D01*
X961943D01*
X961295Y475503D01*
Y487623D01*
X962041Y488369D01*
X963702D01*
X964187Y488854D01*
G37*
G36*
G01X1078379Y554616D02*
X1090819D01*
G02X1090961Y554557I0J-200D01*
G01X1092929Y552589D01*
G03X1093071Y552530I142J141D01*
G01X1093872D01*
G02X1094001Y552483I0J-200D01*
G03X1095442Y551956I1442J1710D01*
G01X1097819D01*
G02X1098019Y551756I0J-200D01*
G01Y551373D01*
G02X1097960Y551231I-200J0D01*
G01X1097875Y551146D01*
G02X1097733Y551087I-142J141D01*
G01X1092613D01*
G03X1092471Y551028I0J-200D01*
G01X1090357Y548914D01*
G02X1090215Y548855I-142J141D01*
G01X1088846D01*
G03X1088704Y548796I0J-200D01*
G01X1080995Y541087D01*
G02X1080853Y541028I-142J141D01*
G01X1070198D01*
X1070186Y541029D01*
G03X1069871Y541048I-322J-2723D01*
G03X1069556Y541029I7J-2742D01*
G01X1069544Y541028D01*
X1068098D01*
X1068086Y541029D01*
G03X1067771Y541048I-322J-2723D01*
G03X1067456Y541029I7J-2742D01*
G01X1067444Y541028D01*
X1051027D01*
G03X1050885Y540969I0J-200D01*
G01X1037321Y527405D01*
G03X1037262Y527263I141J-142D01*
G01Y474821D01*
G02X1037203Y474679I-200J0D01*
G01X1016554Y454030D01*
G02X1016412Y453971I-142J141D01*
G01X992795D01*
X992773Y453949D01*
G02X992631Y453890I-142J141D01*
G01X988970D01*
G02X988828Y453949I0J200D01*
G01X988806Y453971D01*
X986607D01*
Y453993D01*
X978289D01*
G02X978089Y454193I0J200D01*
G01Y456924D01*
X978119Y456997D01*
X978125Y457003D01*
X980870D01*
G03X981012Y457062I0J200D01*
G01X983845Y459895D01*
G03X983904Y460037I-141J142D01*
G01Y465233D01*
G02X983963Y465375I200J0D01*
G01X986607Y468019D01*
Y468025D01*
X987234Y468652D01*
G02X987376Y468711I142J-141D01*
G01X999310D01*
G03X999452Y468770I0J200D01*
G01X1002632Y471950D01*
G03X1002691Y472092I-141J142D01*
G01Y487807D01*
G03X1002632Y487949I-200J0D01*
G01X1001407Y489174D01*
G03X1001265Y489233I-142J-141D01*
G01X977036D01*
G03X976894Y489174I0J-200D01*
G01X974992Y487272D01*
G02X974850Y487213I-142J141D01*
G01X973316D01*
G02X973116Y487413I0J200D01*
G01Y495744D01*
G02X973187Y495897I200J0D01*
G01X973456Y496123D01*
X973540Y496146D01*
X973584Y496138D01*
G03X973843Y496116I256J1479D01*
G03X974336Y496199I1J1501D01*
G01X974410Y496225D01*
X974465Y496212D01*
G03X974510Y496207I44J195D01*
G01X974796D01*
X975313D01*
X976000Y496894D01*
Y497411D01*
Y500592D01*
G02X976059Y500734I200J0D01*
G01X976918Y501593D01*
G02X977060Y501652I142J-141D01*
G01X994791D01*
G03X994933Y501711I0J200D01*
G01X998520Y505298D01*
G03X998579Y505440I-141J142D01*
G01Y528321D01*
G02X998638Y528463I200J0D01*
G01X1021283Y551108D01*
G02X1021425Y551167I142J-141D01*
G01X1071826D01*
G02X1071952Y551122I0J-200D01*
G03X1074482I1265J1553D01*
G01X1074509Y551144D01*
X1074573Y551167D01*
X1074764D01*
G03X1074906Y551226I0J200D01*
G01X1078237Y554557D01*
G02X1078379Y554616I142J-141D01*
G37*
G36*
G01X966766Y518969D02*
Y532070D01*
X968567Y533871D01*
X969663Y534967D01*
X992504D01*
X995947Y531524D01*
Y520887D01*
Y504757D01*
X994789Y503599D01*
X968375D01*
X966766Y505208D01*
Y518969D01*
G37*
G36*
G01X977019Y627231D02*
X997071D01*
X998007Y628167D01*
Y641266D01*
X997457Y641816D01*
X982844D01*
X981826Y640798D01*
Y633084D01*
X981318Y632576D01*
X977227D01*
X976676Y632025D01*
Y630928D01*
Y627574D01*
X977019Y627231D01*
G37*
G36*
G01X976343Y850380D02*
X979854D01*
G02X979996Y850321I0J-200D01*
G01X980732Y849585D01*
G02X980791Y849443I-141J-142D01*
G01Y847692D01*
G02X980732Y847550I-200J0D01*
G01X979497Y846315D01*
G03X979438Y846173I141J-142D01*
G01Y840073D01*
G02X979379Y839931I-200J0D01*
G01X979018Y839570D01*
G02X978876Y839511I-142J141D01*
G01X978562D01*
G03X978420Y839452I0J-200D01*
G01X977823Y838855D01*
G03X977764Y838713I141J-142D01*
G01Y838218D01*
G02X977732Y838110I-200J1D01*
G03X977458Y837313I1471J-951D01*
G02X977400Y837189I-199J18D01*
G01X977216Y837005D01*
G02X977074Y836946I-142J141D01*
G01X972686D01*
G02X972544Y837005I0J200D01*
G01X972124Y837425D01*
G02X972065Y837567I141J142D01*
G01Y843507D01*
X972077Y843540D01*
G03Y844564I-1411J512D01*
G01X972065Y844597D01*
Y847168D01*
X972502Y847605D01*
X975240D01*
X976157Y848522D01*
Y850194D01*
X976343Y850380D01*
G37*
G36*
G01X965030Y1546535D02*
Y1565513D01*
G02X965089Y1565655I200J0D01*
G01X966159Y1566725D01*
G02X966301Y1566784I142J-141D01*
G01X993823D01*
G02X993965Y1566725I0J-200D01*
G01X995797Y1564893D01*
G02X995856Y1564751I-141J-142D01*
G01Y1547091D01*
G02X995797Y1546949I-200J0D01*
G01X993903Y1545055D01*
G02X993761Y1544996I-142J141D01*
G01X966569D01*
G02X966427Y1545055I0J200D01*
G01X965089Y1546393D01*
G02X965030Y1546535I141J142D01*
G37*
G36*
G01X1051831Y54588D02*
X1079804D01*
Y52591D01*
X1051831D01*
G03X1045894Y46654I0J-5937D01*
G01Y7874D01*
G02X1040020Y2000I-5874J0D01*
G01X992776D01*
G02X986902Y7874I0J5874D01*
G01Y46344D01*
X988900D01*
Y7874D01*
G03X992776Y3998I3876J0D01*
G01X1040020D01*
G03X1043896Y7874I0J3876D01*
G01Y46654D01*
G02X1051831Y54588I7935J-1D01*
G37*
G36*
G01X981795Y95055D02*
X996811D01*
X996831Y95035D01*
X1000836D01*
X1001549Y94322D01*
Y74773D01*
X1000688Y73912D01*
X998077D01*
X997813D01*
X997354Y74371D01*
Y90663D01*
X997231Y90786D01*
X996525D01*
X993770D01*
X982032D01*
X981993Y90747D01*
X981716Y91024D01*
Y94976D01*
X981795Y95055D01*
G37*
G36*
G01X990316Y451919D02*
X984316D01*
X983232D01*
X981670D01*
X981417Y451666D01*
Y446698D01*
X982157Y445958D01*
X983788D01*
X990232D01*
X990816Y446542D01*
Y451419D01*
X990316Y451919D01*
G37*
G36*
G01X1084891Y577871D02*
X1097197D01*
G02X1097339Y577812I0J-200D01*
G01X1097825Y577326D01*
G02X1097884Y577184I-141J-142D01*
G01Y563277D01*
G02X1097825Y563135I-200J0D01*
G01X1097692Y563002D01*
G02X1097550Y562943I-142J141D01*
G01X1083363D01*
G02X1083221Y563002I0J200D01*
G01X1080407Y565816D01*
G03X1080265Y565875I-142J-141D01*
G01X1074550D01*
G02X1074423Y565920I-1J200D01*
G03X1071887I-1268J-1548D01*
G02X1071760Y565875I-126J155D01*
G01X1055098D01*
G03X1054956Y565816I0J-200D01*
G01X1053690Y564550D01*
G03X1053631Y564408I141J-142D01*
G01Y558946D01*
G02X1053572Y558804I-200J0D01*
G01X1050937Y556169D01*
G02X1050795Y556110I-142J141D01*
G01X1016980D01*
G03X1016838Y556051I0J-200D01*
G01X1012893Y552106D01*
G02X1012751Y552047I-142J141D01*
G01X991843D01*
G02X991701Y552106I0J200D01*
G01X990842Y552965D01*
G02X990783Y553107I141J142D01*
G01Y567243D01*
G02X990842Y567385I200J0D01*
G01X992338Y568881D01*
G02X992480Y568940I142J-141D01*
G01X995643D01*
G03X995785Y568999I0J200D01*
G01X996202Y569416D01*
G03X996261Y569558I-141J142D01*
G01Y572492D01*
G02X996320Y572634I200J0D01*
G01X996893Y573207D01*
G02X997035Y573266I142J-141D01*
G01X1004317D01*
G03X1004459Y573325I0J200D01*
G01X1012293Y581159D01*
X1012337D01*
X1012508Y581330D01*
G02X1012650Y581389I142J-141D01*
G01X1013956Y582695D01*
X1080067D01*
X1084891Y577871D01*
G37*
G36*
G01X982538Y850440D02*
X996362D01*
G02X996504Y850381I0J-200D01*
G01X996990Y849895D01*
G02X997049Y849753I-141J-142D01*
G01Y841896D01*
G02X996849Y841696I-200J0D01*
G01X987493D01*
G03X987351Y841637I0J-200D01*
G01X985866Y840152D01*
G02X985724Y840093I-142J141D01*
G01X981746D01*
G02X981604Y840152I0J200D01*
G01X981577Y840179D01*
G02X981518Y840321I141J142D01*
G01Y846837D01*
G02X981577Y846978I200J-1D01*
G01X981734Y847136D01*
G03X981792Y847277I-142J141D01*
G01Y849695D01*
G02X981851Y849836I200J-1D01*
G01X982396Y850381D01*
G02X982538Y850440I142J-141D01*
G37*
G36*
G01X1330070Y1299000D02*
G03X1330068I-1J-1502D01*
G03X1329779Y1298972I0J-1502D01*
G01X1329760Y1298968D01*
X1304102D01*
G02X1304046Y1298976I0J200D01*
G01X1303967Y1298999D01*
X1303944Y1299013D01*
G03X1303591Y1299189I-1171J-1906D01*
G03X1302992Y1299333I-817J-2082D01*
G02X1302978Y1299335I21J199D01*
G03X1302595Y1299368I-385J-2228D01*
G01X1053006D01*
G03X1052688Y1299346I-3J-2261D01*
G01X1052674Y1299344D01*
X1051478D01*
G03X1050307Y1299013I0J-2237D01*
G01X1050284Y1298999D01*
X1050205Y1298976D01*
G02X1050149Y1298968I-56J192D01*
G01X1010313D01*
G02X1010222Y1298990I0J200D01*
G02X1010172Y1299026I90J178D01*
G01X1009739Y1299459D01*
G03X1009597Y1299518I-142J-141D01*
G01X987932D01*
G02X987841Y1299540I0J200D01*
G02X987791Y1299576I90J178D01*
G01X985785Y1301582D01*
G02X985727Y1301730I142J141D01*
G01X985737Y1302021D01*
G02X985757Y1302103I200J-5D01*
G01X985775Y1302139D01*
X985805Y1302166D01*
G03X986319Y1303297I-987J1131D01*
G03X985605Y1304576I-1503J0D01*
G02X985529Y1304698I120J160D01*
G02X985525Y1304736I196J40D01*
G01Y1322874D01*
G02X985529Y1322912I200J-2D01*
G02X985582Y1323014I196J-37D01*
G01X988546Y1325978D01*
G03X988605Y1326120I-141J142D01*
G01Y1326377D01*
G02X988616Y1326441I200J-1D01*
G01X988625Y1326469D01*
X988645Y1326496D01*
G03X988865Y1326863I-1770J1310D01*
G01X1002600Y1340598D01*
X1035010D01*
G02X1035066Y1340590I0J-200D01*
G01X1035583Y1340073D01*
G03X1036474Y1339704I891J892D01*
G01X1053032D01*
G02X1053174Y1339645I0J-200D01*
G01X1056287Y1336531D01*
G02X1056346Y1336389I-141J-142D01*
G01Y1316957D01*
G02X1056273Y1316881I-176J96D01*
G02X1056181Y1316854I-101J174D01*
G01X1055200D01*
G02X1055000Y1317054I0J200D01*
G01Y1317090D01*
X1053957D01*
X1053955D01*
G03X1053381Y1316888I-9J-890D01*
G02X1053359Y1316874I-118J161D01*
G01X1050744D01*
G02X1050704Y1316904I99J174D01*
G03X1049175Y1317614I-1529J-1292D01*
G01X1049173D01*
G03X1047644Y1316904I0J-2002D01*
G02X1047604Y1316874I-139J144D01*
G01X1045649D01*
G02X1045533Y1316911I0J200D01*
G01X1045523Y1316918D01*
X1045495Y1316987D01*
G02X1045493Y1316991I177J91D01*
G03X1045025Y1317314I-468J-178D01*
G01X1040825D01*
G03X1040324Y1316814I0J-501D01*
G01Y1315909D01*
G02X1040317Y1315858I-200J1D01*
G02X1040316Y1315853I-197J37D01*
G01X1039564Y1315101D01*
G03X1039194Y1314209I892J-893D01*
G01Y1312269D01*
G03X1039564Y1311377I1262J1D01*
G01X1039715Y1311226D01*
G02X1039713Y1311110I-193J-55D01*
G01X1039581Y1310978D01*
X1039576Y1310976D01*
X1039505Y1310970D01*
G03X1038686Y1310088I71J-888D01*
G03Y1310076I890J-6D01*
G01Y1309916D01*
G02X1038679Y1309864I-200J0D01*
G01X1038674Y1309859D01*
G02X1038532Y1309800I-142J141D01*
G01X1036339D01*
G02X1036209Y1309848I0J200D01*
G01X1036186Y1309868D01*
X1036169Y1309965D01*
G03X1035646Y1311004I-1973J-342D01*
G03X1035568Y1311082I-1454J-1376D01*
G01X1035543Y1311106D01*
X1035520Y1311158D01*
G02X1035502Y1311240I182J83D01*
G01Y1314602D01*
G03X1035133Y1315493I-1261J0D01*
G01X1034904Y1315722D01*
G02X1034903Y1315725I189J65D01*
G02X1034896Y1315777I193J52D01*
G01Y1316795D01*
X1034897Y1316811D01*
G03X1034751Y1317166I-502J1D01*
G03X1034731Y1317185I-355J-354D01*
G01X1034710Y1317204D01*
X1034699Y1317213D01*
X1034682Y1317251D01*
G02X1034665Y1317332I183J81D01*
G01Y1317631D01*
G02X1034682Y1317712I200J0D01*
G01X1034699Y1317750D01*
X1034731Y1317779D01*
G03X1034897Y1318152I-336J373D01*
G01Y1321656D01*
G02X1034998Y1321830I200J0D01*
G01X1035312D01*
G03X1036204Y1322200I-1J1262D01*
G01X1037698Y1323694D01*
G03X1038068Y1324586I-892J893D01*
G01Y1335566D01*
G03X1037698Y1336458I-1262J-1D01*
G01X1035436Y1338720D01*
G03X1034905Y1339037I-892J-892D01*
G02X1034889Y1339057I148J135D01*
G02X1034861Y1339117I165J113D01*
G03X1034372Y1339506I-489J-113D01*
G01X1030150D01*
G03X1029670Y1339006I22J-501D01*
G01Y1336605D01*
G03X1030170Y1336104I501J0D01*
G01X1034372D01*
G03X1034416Y1336105I11J501D01*
G01X1034417D01*
X1034466Y1336107D01*
X1034489Y1336099D01*
X1034767Y1335821D01*
G02Y1335711I-192J-55D01*
G01X1034627Y1335571D01*
X1034613Y1335565D01*
X1034579D01*
X1034569Y1335566D01*
X1034513D01*
G03X1032612Y1333665I0J-1901D01*
G01Y1332576D01*
G02X1032610Y1332547I-200J-1D01*
G02X1032572Y1332456I-198J29D01*
G02X1032553Y1332434I-160J119D01*
G01X1032404Y1332285D01*
G02X1032382Y1332266I-141J141D01*
G02X1032291Y1332228I-120J160D01*
G02X1032262Y1332226I-28J198D01*
G01X1030219D01*
G02X1030190Y1332228I-1J200D01*
G02X1030100Y1332265I29J198D01*
G02X1030077Y1332285I119J161D01*
G01X1027054Y1335309D01*
G03X1025709Y1335866I-1345J-1345D01*
G01X1024115D01*
G03X1022214Y1333964I0J-1901D01*
G03X1022803Y1332587I1901J-1D01*
G01X1022804Y1332586D01*
G02X1022851Y1332520I-136J-147D01*
G01X1022866Y1332484D01*
Y1332198D01*
Y1332197D01*
G02X1022761Y1332022I-200J1D01*
G01X1021403D01*
G02X1021298Y1332197I95J176D01*
G01Y1332229D01*
X1021181Y1332346D01*
X1019000D01*
G03X1018800Y1332146I0J-200D01*
G01Y1331502D01*
Y1331492D01*
G02X1018600Y1331302I-200J11D01*
G01X1018564D01*
Y1330249D01*
G03X1018767Y1329683I890J0D01*
G02X1018788Y1329652I-154J-127D01*
G01Y1324886D01*
G03X1019157Y1323995I1261J0D01*
G01X1019403Y1323749D01*
X1019412Y1323725D01*
X1019409Y1323662D01*
Y1323658D01*
G03X1019404Y1323531I1997J-142D01*
G01Y1323529D01*
G03X1021406Y1321528I2002J1D01*
G03X1023328Y1322969I0J2002D01*
G01X1023335Y1322994D01*
G02X1023408Y1323099I192J-56D01*
G01X1023425Y1323112D01*
X1026999D01*
G02X1027141Y1323053I0J-200D01*
G01X1028070Y1322125D01*
G03X1028961Y1321756I891J892D01*
G01X1029588D01*
G02X1029693Y1321580I-95J-176D01*
G01Y1321454D01*
G02X1029493Y1321254I-200J0D01*
G01X1027558D01*
G02X1027417Y1321312I0J200D01*
G01X1026779Y1321951D01*
G03X1024089I-1345J-1345D01*
G01X1024054Y1321916D01*
G03X1023614Y1321228I1345J-1345D01*
G03X1023498Y1320571I1786J-654D01*
G01Y1318698D01*
Y1318688D01*
G02X1023308Y1318498I-201J11D01*
G01X1021259D01*
G03X1019358Y1316597I0J-1901D01*
G01Y1316595D01*
G03X1019947Y1315220I1901J1D01*
G01X1019948Y1315219D01*
G02X1019995Y1315153I-136J-147D01*
G01X1020010Y1315117D01*
Y1314874D01*
Y1314873D01*
G02X1019905Y1314698I-200J1D01*
G01X1018683D01*
G02X1018578Y1314873I95J176D01*
G01Y1315846D01*
Y1315856D01*
G02X1018778Y1316046I200J-11D01*
G01X1018814D01*
Y1317099D01*
G03X1017918Y1317989I-890J0D01*
G01Y1317988D01*
X1017759D01*
G02X1017707Y1317995I0J200D01*
G02X1017704Y1317996I62J190D01*
G01X1014052Y1321648D01*
G03X1013160Y1322018I-893J-892D01*
G01X991374D01*
G02X991272Y1322046I0J200D01*
G03X990502Y1322258I-769J-1290D01*
G01X990475D01*
G03Y1319254I26J-1502D01*
G01X990502D01*
G03X991272Y1319466I1J1502D01*
G02X991374Y1319494I102J-172D01*
G01X1012554D01*
G02X1012696Y1319435I0J-200D01*
G01X1015836Y1316296D01*
G02X1015837Y1316293I-189J-65D01*
G02X1015844Y1316241I-193J-52D01*
G01Y1316163D01*
X1015961Y1316046D01*
X1015962D01*
X1016021Y1315987D01*
G02X1016080Y1315845I-141J-142D01*
G01Y1314178D01*
Y1314168D01*
G02X1015880Y1313978I-200J11D01*
G01X1015844D01*
Y1312925D01*
G03X1016740Y1312035I890J0D01*
G01Y1312036D01*
X1017905D01*
X1017907Y1312035D01*
G03X1018120Y1312057I16J890D01*
G03X1018376Y1312159I-198J868D01*
G01X1018407Y1312176D01*
X1020197D01*
X1020221Y1312163D01*
G03X1020561Y1312051I443J772D01*
G03X1020682Y1312045I104J884D01*
G01X1020684Y1312046D01*
X1021835D01*
X1021837Y1312045D01*
G03X1022050Y1312067I16J890D01*
G03X1022306Y1312169I-198J868D01*
G01X1022337Y1312186D01*
X1023987D01*
X1024052Y1312162D01*
X1024062Y1312154D01*
G03X1024398Y1312024I337J372D01*
G01X1026399D01*
G03X1026901Y1312526I0J502D01*
G01Y1313096D01*
G02X1026909Y1313152I200J0D01*
G01X1028049Y1314291D01*
G02X1028191Y1314350I142J-141D01*
G01X1029571D01*
G02X1029687Y1314313I0J-200D01*
G01X1029697Y1314306D01*
X1029725Y1314237D01*
G02X1029727Y1314233I-177J-91D01*
G03X1030195Y1313910I468J178D01*
G01X1032805D01*
G02X1032980Y1313805I-1J-199D01*
G01Y1311324D01*
G02X1032960Y1311237I-200J0D01*
G01X1032931Y1311177D01*
X1032910Y1311159D01*
G03X1032194Y1309624I1287J-1535D01*
G03X1032196Y1309533I2002J-2D01*
G03X1033525Y1307737I2001J91D01*
G03X1033681Y1307689I666J1888D01*
G03X1033777Y1307666I514J1935D01*
G02X1033789Y1307663I-42J-195D01*
G03X1034697Y1307276I909J874D01*
G01X1039101D01*
G03X1039138Y1307275I53J1262D01*
G01X1039140D01*
G03X1040032Y1307645I-1J1263D01*
G01X1040382Y1307995D01*
G02X1040434Y1308002I52J-193D01*
G01X1040514D01*
X1040629Y1308117D01*
G02X1040631Y1308119I142J-140D01*
G01X1040694Y1308181D01*
G02X1040834Y1308238I140J-143D01*
G01X1042496D01*
G02X1042696Y1308038I0J-200D01*
G01Y1308002D01*
X1043750D01*
G03X1044109Y1308078I-1J890D01*
G03X1044640Y1308897I-359J814D01*
G01Y1310075D01*
Y1310077D01*
G03X1043750Y1310972I-890J5D01*
G01X1043584D01*
G02X1043532Y1310979I0J200D01*
G02X1043529Y1310980I62J190D01*
G01X1041777Y1312733D01*
G02X1041718Y1312875I141J142D01*
G01Y1313603D01*
G02X1041776Y1313745I200J1D01*
G01X1041933Y1313902D01*
G02X1041988Y1313910I56J-192D01*
G01X1045025D01*
G03X1045493Y1314233I0J501D01*
G02X1045495Y1314237I179J-87D01*
G01X1045501Y1314252D01*
G02X1045570Y1314340I186J-75D01*
G01X1045585Y1314350D01*
X1047604D01*
G02X1047644Y1314320I-99J-174D01*
G03X1049173Y1313610I1529J1292D01*
G01X1049175D01*
G03X1050704Y1314320I0J2002D01*
G02X1050744Y1314350I139J-144D01*
G01X1053344D01*
G02X1053358Y1314341I-101J-173D01*
G03X1053944Y1314120I587J669D01*
G01X1054800D01*
G03X1055000Y1314320I0J200D01*
G01Y1314356D01*
X1056126D01*
X1056135D01*
G02X1056227Y1314329I-9J-201D01*
G02X1056300Y1314253I-103J-172D01*
G01Y1312788D01*
G02X1056126Y1312686I-174J98D01*
G01X1056095D01*
X1055978Y1312569D01*
Y1310386D01*
G03X1056178Y1310186I200J0D01*
G01X1056821D01*
G02X1057020Y1309986I0J-200D01*
G01Y1309950D01*
X1058074D01*
G03X1058964Y1310846I0J890D01*
G01Y1312024D01*
Y1312026D01*
G03X1058846Y1312473I-890J4D01*
G02X1058844Y1312477I178J91D01*
G01X1058824Y1312514D01*
Y1314400D01*
G02X1058858Y1314511I200J0D01*
G01Y1314512D01*
G03X1059010Y1315008I-738J498D01*
G01Y1316193D01*
Y1316195D01*
G03X1058892Y1316642I-890J4D01*
G02X1058890Y1316646I178J91D01*
G01X1058870Y1316683D01*
Y1336995D01*
G03X1058500Y1337887I-1262J-1D01*
G01X1056045Y1340342D01*
G02X1056040Y1340361I190J60D01*
G01X1056101Y1340508D01*
G02X1056175Y1340598I185J-76D01*
G01X1434246D01*
G02X1434369Y1340555I-1J-200D01*
G01X1434397Y1340534D01*
X1434432Y1340478D01*
X1434436Y1340463D01*
G03X1437364Y1340462I1464J338D01*
G01Y1340464D01*
X1437376Y1340512D01*
X1437431Y1340555D01*
G02X1437554Y1340598I124J-157D01*
G01X1440028D01*
G02X1440213Y1340473I0J-200D01*
G01X1440277Y1340289D01*
X1440340Y1340105D01*
G02X1440343Y1339984I-189J-65D01*
G01X1440325Y1339923D01*
X1440312Y1339912D01*
X1440274Y1339883D01*
G03X1439698Y1338700I927J-1183D01*
G03X1439711Y1338500I1502J-3D01*
G03X1440275Y1337516I1489J200D01*
G02X1440331Y1337447I-123J-157D01*
G01X1440350Y1337410D01*
X1440355Y1337221D01*
X1440360Y1337057D01*
G02X1440343Y1336971I-200J-5D01*
G01X1440326Y1336932D01*
X1440292Y1336902D01*
G03X1439784Y1335776I994J-1126D01*
G03X1442788I1502J0D01*
G01X1442789D01*
G03X1442211Y1336960I-1502J0D01*
G02X1442155Y1337029I123J157D01*
G01X1442136Y1337066D01*
X1442131Y1337255D01*
X1442126Y1337419D01*
G02X1442143Y1337505I200J5D01*
G01X1442160Y1337544D01*
X1442194Y1337574D01*
G03X1442702Y1338700I-994J1126D01*
G03X1442126Y1339883I-1503J0D01*
G01X1442088Y1339912D01*
X1442075Y1339923D01*
X1442057Y1339984D01*
G02X1442060Y1340105I192J56D01*
G01X1442123Y1340289D01*
X1442187Y1340473D01*
G02X1442372Y1340598I185J-75D01*
G01X1820163D01*
G03X1820238Y1340613I-1J200D01*
G01X1820276Y1340628D01*
G02X1820351Y1340643I76J-185D01*
G01X1820373D01*
G02X1820515Y1340584I0J-200D01*
G01X1823225Y1337874D01*
G02X1823278Y1337772I-143J-139D01*
G02X1823282Y1337734I-196J-40D01*
G01Y1324516D01*
G03X1823297Y1324442I200J2D01*
G01Y1324440D01*
X1823327Y1324366D01*
G02X1823339Y1324298I-188J-68D01*
G01Y1317888D01*
G03X1823354Y1317812I200J0D01*
G01X1823366Y1317783D01*
G02X1823381Y1317713I-185J-76D01*
G01Y1289018D01*
G02X1823181Y1288818I-200J0D01*
G01X1746024D01*
G02X1745933Y1288840I0J200D01*
G02X1745883Y1288876I90J178D01*
G01X1735850Y1298909D01*
G03X1735708Y1298968I-142J-141D01*
G01X1469199D01*
G02X1469108Y1298990I0J200D01*
G02X1469058Y1299026I90J178D01*
G01X1449347Y1318737D01*
G03X1449205Y1318796I-142J-141D01*
G01X1422600D01*
G03X1422458Y1318737I0J-200D01*
G01X1410674Y1306953D01*
G02X1410624Y1306917I-140J142D01*
G01X1410599Y1306904D01*
X1410567Y1306898D01*
G03X1409336Y1305667I250J-1481D01*
G01X1409330Y1305635D01*
X1409317Y1305610D01*
G02X1409281Y1305560I-178J90D01*
G01X1402747Y1299026D01*
G02X1402697Y1298990I-140J142D01*
G02X1402606Y1298968I-91J178D01*
G01X1357380D01*
X1357361Y1298972D01*
G03X1357072Y1299000I-289J-1474D01*
G03X1357070I-1J-1502D01*
G03X1357068I-1J-1502D01*
G03X1356779Y1298972I0J-1502D01*
G01X1356760Y1298968D01*
X1351980D01*
X1351961Y1298972D01*
G03X1351672Y1299000I-289J-1474D01*
G03X1351670I-1J-1502D01*
G03X1351668I-1J-1502D01*
G03X1351379Y1298972I0J-1502D01*
G01X1351360Y1298968D01*
X1346580D01*
X1346561Y1298972D01*
G03X1346272Y1299000I-289J-1474D01*
G03X1346270I-1J-1502D01*
G03X1346268I-1J-1502D01*
G03X1345979Y1298972I0J-1502D01*
G01X1345960Y1298968D01*
X1341180D01*
X1341161Y1298972D01*
G03X1340872Y1299000I-289J-1474D01*
G03X1340870I-1J-1502D01*
G03X1340868I-1J-1502D01*
G03X1340579Y1298972I0J-1502D01*
G01X1340560Y1298968D01*
X1335780D01*
X1335761Y1298972D01*
G03X1335472Y1299000I-289J-1474D01*
G03X1335470I-1J-1502D01*
G03X1335468I-1J-1502D01*
G03X1335179Y1298972I0J-1502D01*
G01X1335160Y1298968D01*
X1330380D01*
X1330361Y1298972D01*
G03X1330072Y1299000I-289J-1474D01*
G03X1330070I-1J-1502D01*
G37*
G36*
G01X1001706Y276354D02*
X1019279D01*
X1020105Y275528D01*
Y258570D01*
X1018846Y257312D01*
Y232116D01*
X1011971Y225241D01*
Y223943D01*
Y220921D01*
X1009671Y218621D01*
X1007671D01*
X1007381Y218331D01*
Y205660D01*
X1006794Y205073D01*
X999962D01*
X999454Y205581D01*
Y220421D01*
X996171Y223704D01*
Y234821D01*
X996337Y234987D01*
Y250246D01*
X999501Y253410D01*
X999537D01*
X1001757Y255630D01*
Y268925D01*
X998748Y271934D01*
X996444D01*
X995928Y272450D01*
Y274738D01*
X996151Y274961D01*
X1000313D01*
X1001706Y276354D01*
G37*
G36*
G01X996960Y276095D02*
X997699D01*
X997725Y276122D01*
X999926D01*
X1001378Y277574D01*
X1003013D01*
X1003047Y277540D01*
X1010218D01*
X1010250Y277572D01*
X1017981D01*
X1019796Y279387D01*
Y287118D01*
Y296369D01*
X1018970Y297195D01*
X1002738D01*
X1000623Y295080D01*
Y282733D01*
X998440Y280550D01*
X996650Y278760D01*
Y276405D01*
X996960Y276095D01*
G37*
G36*
G01X1011588Y323496D02*
X1009138D01*
X1009068Y323566D01*
Y324536D01*
X1009128Y324596D01*
X1011698D01*
X1012018D01*
X1012278Y324856D01*
Y341056D01*
X1013188Y341966D01*
X1032228D01*
X1032388Y341806D01*
Y322146D01*
X1032128Y321886D01*
X1013718D01*
X1013098Y321266D01*
Y318816D01*
X1012958Y318676D01*
X1012028D01*
X1011948Y318756D01*
Y320806D01*
X1012298Y321156D01*
Y323276D01*
X1012078Y323496D01*
X1011588D01*
G37*
G36*
G01X1011037Y332536D02*
Y331336D01*
X1008854D01*
X1008459Y331731D01*
X1004374D01*
X1004279Y331638D01*
X1003805D01*
X1002311D01*
X1002023Y331926D01*
Y332369D01*
Y333551D01*
X1002266Y333794D01*
X1003189D01*
X1004884Y332099D01*
X1008456D01*
X1008893Y332536D01*
X1011037D01*
G37*
G36*
G01X1040551Y388583D02*
G03I-19685J0D01*
G37*
G36*
G01X998050Y847392D02*
X998070Y847411D01*
G02X998212Y847470I142J-141D01*
G01X1004296D01*
G02X1004438Y847411I0J-200D01*
G01X1004531Y847318D01*
G02X1004590Y847177I-141J-142D01*
G01Y839356D01*
X1004612Y839334D01*
Y836900D01*
Y834187D01*
X1003671Y833246D01*
X999007D01*
X997943Y834310D01*
Y836900D01*
Y840587D01*
X997992Y840636D01*
G03X998050Y840777I-142J141D01*
G01Y847392D01*
G37*
G36*
G01X1010968Y845922D02*
X1016305D01*
G02X1016447Y845863I0J-200D01*
G01X1016644Y845666D01*
G02X1016702Y845525I-142J-141D01*
G01Y841193D01*
G03X1016703Y841163I1201J25D01*
G01Y840742D01*
G02X1016644Y840600I-200J0D01*
G01X1015893Y839849D01*
X1015790Y839822D01*
X1015737Y839837D01*
G03X1015128Y839920I-607J-2178D01*
G01X1012703D01*
G03X1012385Y839898I-3J-2261D01*
G01X1012371Y839896D01*
X1012140D01*
G03X1011998Y839837I0J-200D01*
G01X1011954Y839793D01*
X1011914Y839778D01*
G03X1011890Y839769I782J-2122D01*
G01X1011855Y839756D01*
X1006194D01*
G02X1006052Y839815I0J200D01*
G01X1005699Y840168D01*
G02X1005640Y840310I141J142D01*
G01Y844438D01*
G02X1005699Y844580I200J0D01*
G01X1005782Y844663D01*
G02X1005924Y844722I142J-141D01*
G01X1006817D01*
X1006853Y844708D01*
G03X1007440Y844596I588J1490D01*
G01X1008896D01*
G03X1009483Y844708I-1J1602D01*
G01X1009519Y844722D01*
X1009556D01*
G03X1009698Y844781I0J200D01*
G01X1009765Y844848D01*
G02X1009794Y844872I141J-141D01*
G03X1010028Y845066I-900J1324D01*
G01X1010826Y845863D01*
G02X1010968Y845922I142J-141D01*
G37*
G36*
G01X1007737Y876914D02*
X1014651D01*
X1016137Y878400D01*
X1017914D01*
X1018948Y877366D01*
Y873263D01*
X1018722Y873037D01*
X1007802D01*
X1007414Y873425D01*
Y876591D01*
X1007737Y876914D01*
G37*
G36*
G01X1024519Y950322D02*
Y931422D01*
X1023819Y930722D01*
X1004119D01*
X1003619Y931222D01*
Y939622D01*
X1003819Y939822D01*
X1010819D01*
X1011419Y939222D01*
Y933922D01*
X1012019Y933322D01*
X1017319D01*
X1017919Y933922D01*
Y950422D01*
Y950822D01*
X1016919Y951822D01*
Y955422D01*
X1017219Y955722D01*
X1024219D01*
X1024519Y955422D01*
Y953322D01*
Y950322D01*
G37*
G36*
G01X1004219Y950622D02*
X1010819D01*
X1011819Y949622D01*
Y948122D01*
X1012819Y947122D01*
X1016519D01*
X1016819Y946822D01*
Y942622D01*
X1016619Y942422D01*
X1004019D01*
X1003719Y942722D01*
Y950122D01*
X1004219Y950622D01*
G37*
G36*
G01X1008973Y1036752D02*
X1017454D01*
X1017772Y1036434D01*
Y1034639D01*
X1017707Y1034575D01*
X1015702D01*
X1015222Y1034095D01*
X1014229D01*
X1013857Y1034467D01*
X1010883D01*
X1010522Y1034106D01*
Y1033887D01*
Y1029718D01*
X1010826Y1029414D01*
X1011028Y1029212D01*
X1013358D01*
X1013604Y1028966D01*
Y1026187D01*
X1013416Y1025999D01*
X1008322D01*
X1008076Y1026245D01*
Y1035855D01*
X1008973Y1036752D01*
G37*
G36*
G01X1031581Y1385222D02*
X1030949Y1384590D01*
G02X1030807Y1384531I-142J141D01*
G01X1001471D01*
G02X1001329Y1384590I0J200D01*
G01X1000718Y1385201D01*
G02X1000659Y1385343I141J142D01*
G01Y1398966D01*
G02X1000859Y1399166I200J0D01*
G01X1031010D01*
G02X1031152Y1399107I0J-200D01*
G01X1031581Y1398678D01*
G02X1031640Y1398536I-141J-142D01*
G01Y1385364D01*
G02X1031581Y1385222I-200J0D01*
G37*
G36*
G01X1014240Y-44304D02*
G03I-557J0D01*
G37*
G36*
G01Y-39348D02*
G03I-557J0D01*
G37*
G36*
G01Y-29348D02*
G03I-557J0D01*
G37*
G36*
G01Y-34304D02*
G03I-557J0D01*
G37*
G36*
G01X1024918Y115094D02*
X1025974D01*
X1026001Y115067D01*
Y111227D01*
G02X1025942Y111085I-200J0D01*
G01X1024312Y109456D01*
G03X1024253Y109314I141J-142D01*
G01Y106183D01*
G03X1024312Y106041I200J0D01*
G01X1024435Y105918D01*
G03X1024577Y105859I142J141D01*
G01X1035283D01*
G03X1035425Y105918I0J200D01*
G01X1035501Y105994D01*
G03X1035560Y106136I-141J142D01*
G01Y109681D01*
G03X1035501Y109823I-200J0D01*
G01X1035267Y110057D01*
G02X1035208Y110199I141J142D01*
G01Y114552D01*
X1035238Y114625D01*
X1035249Y114636D01*
X1040833D01*
X1042175D01*
X1042239Y114572D01*
X1042355Y114456D01*
G02X1042414Y114314I-141J-142D01*
G01Y105226D01*
G02X1042355Y105084I-200J0D01*
G01X1041684Y104413D01*
X1041601Y104383D01*
X1041556Y104388D01*
G03X1041374Y104396I-174J-1893D01*
G01X1038792D01*
X1037506D01*
X1036760Y103650D01*
Y101528D01*
X1036428Y101196D01*
X1024897D01*
X1024873Y101202D01*
X1017693D01*
X1016998Y101897D01*
Y102887D01*
Y114049D01*
G02X1017057Y114191I200J0D01*
G01X1017179Y114313D01*
G02X1017321Y114372I142J-141D01*
G01X1024030D01*
G03X1024172Y114431I0J200D01*
G01X1024776Y115035D01*
G02X1024918Y115094I142J-141D01*
G37*
G36*
G01X1017180Y120851D02*
X1022597D01*
G02X1022739Y120792I0J-200D01*
G01X1024360Y119171D01*
G03X1024502Y119112I142J141D01*
G01X1026017D01*
G02X1026159Y119053I0J-200D01*
G01X1026632Y118580D01*
G02X1026691Y118438I-141J-142D01*
G01Y116276D01*
G02X1026568Y116091I-200J0D01*
G01X1026511Y116068D01*
X1026393Y116091D01*
X1026389Y116096D01*
X1024917D01*
G03X1024103Y115777I1J-1202D01*
G02X1023967Y115724I-136J147D01*
G01X1017121D01*
G02X1016979Y115783I0J200D01*
G01X1016964Y115798D01*
X1016934Y115871D01*
Y120605D01*
G02X1016993Y120747I200J0D01*
G01X1017038Y120792D01*
G02X1017180Y120851I142J-141D01*
G37*
G36*
G01X1026855Y210785D02*
X1036295D01*
X1038096Y208984D01*
X1039192Y207888D01*
Y187037D01*
X1038245Y186090D01*
X1027473D01*
X1026029Y187534D01*
Y209959D01*
X1026855Y210785D01*
G37*
G36*
G01X1039484Y223195D02*
X1049509D01*
X1049539Y223225D01*
X1052062D01*
X1054699Y225862D01*
X1063641D01*
X1063983Y225520D01*
Y213126D01*
X1063271Y212414D01*
X1055854D01*
X1053000Y215268D01*
X1049560D01*
X1038583D01*
X1037019D01*
X1036573Y214822D01*
Y213258D01*
X1035300Y211985D01*
X1034888D01*
X1034111D01*
X1026484D01*
X1025824Y212645D01*
Y226569D01*
X1026500Y227245D01*
X1037434D01*
X1039194Y225485D01*
Y223485D01*
X1039484Y223195D01*
G37*
G36*
G01X1021747Y320615D02*
X1022947D01*
Y318505D01*
X1022534Y318092D01*
Y314156D01*
X1023366Y313324D01*
Y312224D01*
X1023343Y312201D01*
Y310491D01*
X1022348Y309496D01*
X1021148D01*
X1020848Y309796D01*
Y311606D01*
X1021466Y312224D01*
Y313424D01*
X1022166Y314124D01*
Y318006D01*
X1021747Y318425D01*
Y318615D01*
Y320615D01*
G37*
G36*
G01X1020968Y343236D02*
X1019768D01*
Y345334D01*
X1020197Y345763D01*
Y348776D01*
X1019676Y349297D01*
Y351470D01*
X1019861Y351655D01*
X1020844D01*
X1021165Y351334D01*
Y349276D01*
X1020564Y348675D01*
Y345830D01*
X1020968Y345426D01*
Y345236D01*
Y343236D01*
G37*
G36*
G01X1042171Y828553D02*
X1054127D01*
G02X1054269Y828494I0J-200D01*
G01X1055201Y827562D01*
G02X1055260Y827420I-141J-142D01*
G01Y816113D01*
G02X1055201Y815971I-200J0D01*
G01X1054872Y815642D01*
G02X1054730Y815583I-142J141D01*
G01X1038205D01*
G02X1038063Y815642I0J200D01*
G01X1034956Y818749D01*
G03X1034814Y818808I-142J-141D01*
G01X1025497D01*
G02X1025355Y818867I0J200D01*
G01X1020111Y824111D01*
G03X1019969Y824170I-142J-141D01*
G01X1018473D01*
G02X1018273Y824370I0J200D01*
G01Y827978D01*
G02X1018332Y828120I200J0D01*
G01X1019869Y829657D01*
G02X1020011Y829716I142J-141D01*
G01X1023041D01*
G03X1023183Y829775I0J200D01*
G01X1025555Y832147D01*
G02X1025697Y832206I142J-141D01*
G01X1038352D01*
G02X1038494Y832147I0J-200D01*
G01X1042029Y828612D01*
G03X1042171Y828553I142J141D01*
G37*
G36*
G01X1017983Y850431D02*
X1023804D01*
X1024738Y849497D01*
Y848511D01*
X1026848Y846401D01*
Y841347D01*
X1026554Y841053D01*
X1017763D01*
G02X1017704Y841194I141J142D01*
G01Y850153D01*
G02X1017763Y850294I200J-1D01*
G01X1017841Y850372D01*
G02X1017983Y850431I142J-141D01*
G37*
G36*
G01X1013419Y941122D02*
X1016019D01*
X1016419Y940722D01*
Y935122D01*
X1015919Y934622D01*
X1013719D01*
X1013319Y935022D01*
Y941022D01*
X1013419Y941122D01*
G37*
G36*
G01X1025919Y945222D02*
X1030819D01*
X1031569Y944472D01*
Y940872D01*
X1031919Y940522D01*
X1032419Y940022D01*
X1034919D01*
X1035019Y939922D01*
Y931422D01*
X1034319Y930722D01*
X1026219D01*
X1025619Y931322D01*
Y944922D01*
X1025919Y945222D01*
G37*
G36*
G01X1034719Y947122D02*
Y941722D01*
X1034419Y941422D01*
X1032919D01*
X1032719Y941622D01*
Y945222D01*
X1031719Y946222D01*
X1025819D01*
X1025619Y946422D01*
Y946922D01*
X1025719Y947022D01*
X1029319D01*
X1030019Y947722D01*
X1034519D01*
X1034719Y947522D01*
Y947122D01*
G37*
G36*
G01X1010719Y960822D02*
X1015219D01*
X1015819Y960222D01*
Y951522D01*
X1015917Y951424D01*
Y951407D01*
X1016917Y950407D01*
Y948220D01*
X1016821Y948124D01*
X1013417D01*
X1013219Y948322D01*
Y950522D01*
X1009919Y953822D01*
Y960022D01*
X1010719Y960822D01*
G37*
G36*
G01X1027819Y948222D02*
X1026019D01*
X1025819Y948422D01*
Y954522D01*
Y954922D01*
Y959675D01*
X1025978Y959834D01*
X1028363D01*
X1028584Y959613D01*
Y955287D01*
X1028219Y954922D01*
Y948422D01*
X1028019Y948222D01*
X1027819D01*
G37*
G36*
G01X1021990Y1017168D02*
X1026549D01*
G02X1026691Y1017109I0J-200D01*
G01X1026717Y1017083D01*
X1026747Y1017010D01*
Y1001850D01*
G02X1026688Y1001708I-200J0D01*
G01X1026485Y1001505D01*
G02X1026343Y1001446I-142J141D01*
G01X1022667D01*
Y1001447D01*
X1022268D01*
G02X1022126Y1001506I0J200D01*
G01X1021813Y1001819D01*
G02X1021755Y1001960I142J141D01*
G01Y1016933D01*
G02X1021813Y1017074I200J0D01*
G01X1021848Y1017109D01*
G02X1021990Y1017168I142J-141D01*
G37*
G36*
G01X1015276Y1017056D02*
X1020405D01*
G02X1020547Y1016997I0J-200D01*
G01X1020694Y1016850D01*
G02X1020753Y1016708I-141J-142D01*
G01Y1002279D01*
G02X1020694Y1002137I-200J0D01*
G01X1020110Y1001553D01*
G02X1019968Y1001494I-142J141D01*
G01X1016397D01*
X1014722D01*
X1014077Y1002139D01*
Y1016642D01*
X1014491Y1017056D01*
X1015276D01*
G37*
G36*
G01X1023209Y1028195D02*
X1022836Y1027822D01*
G03X1022777Y1027680I141J-142D01*
G01Y1026159D01*
G02X1022718Y1026017I-200J0D01*
G01X1021214Y1024513D01*
G03X1021155Y1024371I141J-142D01*
G01Y1023313D01*
G02X1021096Y1023171I-200J0D01*
G01X1021095Y1023170D01*
Y1019903D01*
G02X1021036Y1019761I-200J0D01*
G01X1020685Y1019410D01*
G02X1020543Y1019351I-142J141D01*
G01X1015464D01*
G02X1015322Y1019410I0J200D01*
G01X1015008Y1019724D01*
G02X1014950Y1019866I142J141D01*
G01Y1029993D01*
X1014169Y1030774D01*
X1011782D01*
X1011560Y1030996D01*
Y1033274D01*
X1011723Y1033437D01*
X1012419D01*
X1012428Y1033428D01*
X1013343D01*
X1013679Y1033092D01*
X1016039D01*
X1016433Y1033486D01*
X1017174D01*
G03X1017700Y1033575I0J1602D01*
G01X1018339D01*
X1018408Y1033506D01*
Y1032354D01*
X1019268Y1031494D01*
X1022961D01*
X1023209Y1031246D01*
Y1028195D01*
G37*
G36*
G01X1024747Y1028234D02*
X1025848D01*
G02X1025990Y1028175I0J-200D01*
G01X1026252Y1027912D01*
G02X1026311Y1027771I-141J-142D01*
G01Y1019455D01*
G02X1026252Y1019313I-200J0D01*
G01X1025705Y1018766D01*
G02X1025563Y1018707I-142J141D01*
G01X1023070D01*
G02X1022928Y1018766I0J200D01*
G01X1022725Y1018969D01*
G02X1022666Y1019111I141J142D01*
G01Y1024435D01*
G02X1022725Y1024577I200J0D01*
G01X1024005Y1025857D01*
G03X1024064Y1025999I-141J142D01*
G01Y1027551D01*
G02X1024123Y1027692I200J-1D01*
G01X1024605Y1028175D01*
G02X1024747Y1028234I142J-141D01*
G37*
G36*
G01X1035525Y1032344D02*
X1043328D01*
G02X1043470Y1032285I0J-200D01*
G01X1043487Y1032268D01*
G02X1043546Y1032126I-141J-142D01*
G01Y1026997D01*
G02X1043487Y1026855I-200J0D01*
G01X1043340Y1026708D01*
G02X1043198Y1026649I-142J141D01*
G01X1028769D01*
G02X1028627Y1026708I0J200D01*
G01X1028043Y1027292D01*
G02X1027984Y1027434I141J142D01*
G01Y1028742D01*
X1027418Y1029308D01*
X1024845D01*
X1024234Y1029919D01*
Y1031653D01*
X1023381Y1032506D01*
X1019681D01*
X1019426Y1032761D01*
Y1033526D01*
X1019514Y1033614D01*
X1028003D01*
X1029273Y1032344D01*
X1035525D01*
G37*
G36*
G01X1048605Y1066535D02*
G02I-17700J0D01*
G37*
G36*
G01X1016804Y1105784D02*
X1031777D01*
G02X1031918Y1105726I0J-200D01*
G01X1031953Y1105691D01*
G02X1032012Y1105549I-141J-142D01*
G01Y1100990D01*
G02X1031953Y1100848I-200J0D01*
G01X1031927Y1100822D01*
X1031854Y1100792D01*
X1016694D01*
G02X1016552Y1100851I0J200D01*
G01X1016349Y1101054D01*
G02X1016290Y1101196I141J142D01*
G01Y1104872D01*
X1016291D01*
Y1105271D01*
G02X1016350Y1105413I200J0D01*
G01X1016663Y1105726D01*
G02X1016804Y1105784I141J-142D01*
G37*
G36*
G01X1023879Y1112481D02*
X1031682D01*
G02X1031824Y1112422I0J-200D01*
G01X1031841Y1112405D01*
G02X1031900Y1112263I-141J-142D01*
G01Y1107134D01*
G02X1031841Y1106992I-200J0D01*
G01X1031694Y1106845D01*
G02X1031552Y1106786I-142J141D01*
G01X1017123D01*
G02X1016981Y1106845I0J200D01*
G01X1016397Y1107429D01*
G02X1016338Y1107571I141J142D01*
G01Y1111142D01*
G02X1016397Y1111284I200J0D01*
G01X1017510Y1112397D01*
G02X1017652Y1112456I142J-141D01*
G01X1023855D01*
X1023879Y1112481D01*
G37*
G36*
G01X1016804Y1118384D02*
X1031777D01*
G02X1031919Y1118325I0J-200D01*
G01X1031953Y1118291D01*
G02X1031955Y1118289I-140J-142D01*
G02X1032012Y1118149I-143J-140D01*
G01Y1113590D01*
G02X1031981Y1113482I-200J-1D01*
G01X1023452D01*
X1023428Y1113458D01*
X1017237D01*
G03X1017096Y1113399I1J-200D01*
G01X1017089Y1113392D01*
X1016694D01*
G02X1016552Y1113451I0J200D01*
G01X1016349Y1113654D01*
X1016320Y1113682D01*
X1016290Y1113756D01*
Y1117472D01*
X1016291D01*
Y1117871D01*
G02X1016348Y1118011I200J0D01*
G01X1016349Y1118012D01*
X1016662Y1118325D01*
G02X1016804Y1118384I142J-141D01*
G37*
G36*
G01X1023879Y1125081D02*
X1031682D01*
G02X1031824Y1125022I0J-200D01*
G01X1031841Y1125005D01*
G02X1031900Y1124863I-141J-142D01*
G01Y1119734D01*
G02X1031841Y1119592I-200J0D01*
G01X1031694Y1119445D01*
G02X1031552Y1119386I-142J141D01*
G01X1017123D01*
G02X1016981Y1119445I0J200D01*
G01X1016397Y1120029D01*
G02X1016338Y1120171I141J142D01*
G01Y1123742D01*
G02X1016397Y1123884I200J0D01*
G01X1017510Y1124997D01*
G02X1017652Y1125056I142J-141D01*
G01X1023855D01*
X1023879Y1125081D01*
G37*
G36*
G01X1016804Y1130984D02*
X1031777D01*
G02X1031918Y1130926I0J-200D01*
G01X1031953Y1130891D01*
G02X1032012Y1130749I-141J-142D01*
G01Y1126107D01*
X1031987Y1126082D01*
X1023452D01*
X1023428Y1126058D01*
X1017237D01*
G03X1017096Y1125999I1J-200D01*
G01X1017089Y1125992D01*
X1016694D01*
G02X1016552Y1126051I0J200D01*
G01X1016349Y1126254D01*
G02X1016290Y1126396I141J142D01*
G01Y1130072D01*
X1016291D01*
Y1130471D01*
G02X1016350Y1130613I200J0D01*
G01X1016663Y1130926D01*
G02X1016804Y1130984I141J-142D01*
G37*
G36*
G01Y1143584D02*
X1031777D01*
G02X1031918Y1143526I0J-200D01*
G01X1031953Y1143491D01*
G02X1032012Y1143349I-141J-142D01*
G01Y1138707D01*
X1031987Y1138682D01*
X1023452D01*
X1023428Y1138658D01*
X1017237D01*
G03X1017096Y1138599I1J-200D01*
G01X1017089Y1138592D01*
X1016694D01*
G02X1016552Y1138651I0J200D01*
G01X1016349Y1138854D01*
G02X1016290Y1138996I141J142D01*
G01Y1142672D01*
X1016291D01*
Y1143071D01*
G02X1016350Y1143213I200J0D01*
G01X1016663Y1143526D01*
G02X1016804Y1143584I141J-142D01*
G37*
G36*
G01X1023879Y1137681D02*
X1031682D01*
G02X1031824Y1137622I0J-200D01*
G01X1031841Y1137605D01*
G02X1031900Y1137463I-141J-142D01*
G01Y1132334D01*
G02X1031841Y1132192I-200J0D01*
G01X1031694Y1132045D01*
G02X1031552Y1131986I-142J141D01*
G01X1017123D01*
G02X1016981Y1132045I0J200D01*
G01X1016397Y1132629D01*
G02X1016338Y1132771I141J142D01*
G01Y1136342D01*
G02X1016397Y1136484I200J0D01*
G01X1017510Y1137597D01*
G02X1017652Y1137656I142J-141D01*
G01X1023855D01*
X1023879Y1137681D01*
G37*
G36*
G01X1016804Y1156184D02*
X1031777D01*
G02X1031918Y1156126I0J-200D01*
G01X1031953Y1156091D01*
G02X1032012Y1155949I-141J-142D01*
G01Y1151307D01*
X1031987Y1151282D01*
X1023452D01*
X1023428Y1151258D01*
X1017237D01*
G03X1017096Y1151199I1J-200D01*
G01X1017089Y1151192D01*
X1016694D01*
G02X1016552Y1151251I0J200D01*
G01X1016349Y1151454D01*
G02X1016290Y1151596I141J142D01*
G01Y1155272D01*
X1016291D01*
Y1155671D01*
G02X1016350Y1155813I200J0D01*
G01X1016663Y1156126D01*
G02X1016804Y1156184I141J-142D01*
G37*
G36*
G01X1023879Y1150281D02*
X1031682D01*
G02X1031824Y1150222I0J-200D01*
G01X1031841Y1150205D01*
G02X1031900Y1150063I-141J-142D01*
G01Y1144934D01*
G02X1031841Y1144792I-200J0D01*
G01X1031694Y1144645D01*
G02X1031552Y1144586I-142J141D01*
G01X1017123D01*
G02X1016981Y1144645I0J200D01*
G01X1016397Y1145229D01*
G02X1016338Y1145371I141J142D01*
G01Y1148942D01*
G02X1016397Y1149084I200J0D01*
G01X1017510Y1150197D01*
G02X1017652Y1150256I142J-141D01*
G01X1023855D01*
X1023879Y1150281D01*
G37*
G36*
G01X1016804Y1168784D02*
X1031777D01*
G02X1031918Y1168726I0J-200D01*
G01X1031953Y1168691D01*
G02X1032012Y1168549I-141J-142D01*
G01Y1163907D01*
X1031987Y1163882D01*
X1023452D01*
X1023428Y1163858D01*
X1017237D01*
G03X1017096Y1163799I1J-200D01*
G01X1017089Y1163792D01*
X1016694D01*
G02X1016552Y1163851I0J200D01*
G01X1016349Y1164054D01*
G02X1016290Y1164196I141J142D01*
G01Y1167872D01*
X1016291D01*
Y1168271D01*
G02X1016350Y1168413I200J0D01*
G01X1016663Y1168726D01*
G02X1016804Y1168784I141J-142D01*
G37*
G36*
G01X1023879Y1175481D02*
X1031682D01*
G02X1031824Y1175422I0J-200D01*
G01X1031841Y1175405D01*
G02X1031900Y1175263I-141J-142D01*
G01Y1170134D01*
G02X1031841Y1169992I-200J0D01*
G01X1031694Y1169845D01*
G02X1031552Y1169786I-142J141D01*
G01X1017123D01*
G02X1016981Y1169845I0J200D01*
G01X1016397Y1170429D01*
G02X1016338Y1170571I141J142D01*
G01Y1174142D01*
G02X1016397Y1174284I200J0D01*
G01X1017510Y1175397D01*
G02X1017652Y1175456I142J-141D01*
G01X1023855D01*
X1023879Y1175481D01*
G37*
G36*
G01Y1162881D02*
X1031682D01*
G02X1031824Y1162822I0J-200D01*
G01X1031841Y1162805D01*
G02X1031900Y1162663I-141J-142D01*
G01Y1157534D01*
G02X1031841Y1157392I-200J0D01*
G01X1031694Y1157245D01*
G02X1031552Y1157186I-142J141D01*
G01X1017123D01*
G02X1016981Y1157245I0J200D01*
G01X1016397Y1157829D01*
G02X1016338Y1157971I141J142D01*
G01Y1161542D01*
G02X1016397Y1161684I200J0D01*
G01X1017510Y1162797D01*
G02X1017652Y1162856I142J-141D01*
G01X1023855D01*
X1023879Y1162881D01*
G37*
G36*
G01X1016804Y1181384D02*
X1031777D01*
G02X1031918Y1181326I0J-200D01*
G01X1031953Y1181291D01*
G02X1032012Y1181149I-141J-142D01*
G01Y1176507D01*
X1031987Y1176482D01*
X1023452D01*
X1023428Y1176458D01*
X1017237D01*
G03X1017096Y1176399I1J-200D01*
G01X1017089Y1176392D01*
X1016694D01*
G02X1016552Y1176451I0J200D01*
G01X1016349Y1176654D01*
G02X1016290Y1176796I141J142D01*
G01Y1180472D01*
X1016291D01*
Y1180871D01*
G02X1016350Y1181013I200J0D01*
G01X1016663Y1181326D01*
G02X1016804Y1181384I141J-142D01*
G37*
G36*
G01X1023879Y1188081D02*
X1031682D01*
G02X1031824Y1188022I0J-200D01*
G01X1031841Y1188005D01*
G02X1031900Y1187863I-141J-142D01*
G01Y1182734D01*
G02X1031841Y1182592I-200J0D01*
G01X1031694Y1182445D01*
G02X1031552Y1182386I-142J141D01*
G01X1017123D01*
G02X1016981Y1182445I0J200D01*
G01X1016397Y1183029D01*
G02X1016338Y1183171I141J142D01*
G01Y1186742D01*
G02X1016397Y1186884I200J0D01*
G01X1017510Y1187997D01*
G02X1017652Y1188056I142J-141D01*
G01X1023855D01*
X1023879Y1188081D01*
G37*
G36*
G01X1048605Y1263386D02*
G02I-17700J0D01*
G37*
G36*
G01X1028283Y119235D02*
X1031729D01*
X1034565Y122071D01*
X1040612D01*
X1040982Y121701D01*
Y116118D01*
X1040501Y115637D01*
X1030827D01*
X1028471D01*
X1028123Y115985D01*
Y119075D01*
X1028283Y119235D01*
G37*
G36*
G01X1040214Y186998D02*
Y210417D01*
X1038206Y212425D01*
Y214067D01*
X1038598Y214459D01*
X1047020D01*
X1047228Y214251D01*
Y212947D01*
X1047176Y212895D01*
Y212503D01*
Y211823D01*
X1047617Y211382D01*
X1048297D01*
X1052523D01*
X1053851Y210054D01*
Y205828D01*
Y187369D01*
X1052696Y186214D01*
X1040998D01*
X1040214Y186998D01*
G37*
G36*
G01X1033637Y321493D02*
Y322693D01*
X1035721D01*
X1036161Y322251D01*
X1036163Y322249D01*
X1038917D01*
Y321888D01*
X1036222D01*
X1035827Y321493D01*
X1035637D01*
X1033637D01*
G37*
G36*
G01X1029611Y320636D02*
X1030811D01*
Y318569D01*
X1030445Y318203D01*
Y318196D01*
X1030394Y318145D01*
Y315947D01*
X1030045D01*
Y318012D01*
X1030038Y318019D01*
X1029977Y318080D01*
X1029611Y318446D01*
Y318636D01*
Y320636D01*
G37*
G36*
G01X1033637Y339210D02*
Y340410D01*
X1035780D01*
X1036217Y339973D01*
X1038973D01*
X1039000Y340000D01*
X1040253Y341253D01*
X1040269D01*
X1043622D01*
X1044128Y340747D01*
Y339636D01*
X1043421Y338929D01*
X1039824D01*
X1039148Y339605D01*
X1036147D01*
X1035752Y339210D01*
X1033637D01*
G37*
G36*
G01X1033657Y333263D02*
Y334463D01*
X1035840D01*
X1036235Y334068D01*
X1041015D01*
X1041767Y334820D01*
X1043383D01*
X1043459Y334744D01*
X1043868Y334335D01*
Y333647D01*
Y333172D01*
X1043372Y332676D01*
X1041324D01*
X1040855Y333145D01*
X1039925D01*
X1039371Y333699D01*
X1036175D01*
X1035739Y333263D01*
X1035657D01*
X1033657D01*
G37*
G36*
G01X1030811Y343236D02*
X1029611D01*
Y345369D01*
X1030040Y345798D01*
Y350375D01*
X1030239Y350574D01*
Y350797D01*
X1030966Y351524D01*
X1031677D01*
X1032242Y350959D01*
Y350000D01*
X1031666Y349424D01*
X1031066D01*
X1030408Y348766D01*
Y345829D01*
X1030811Y345426D01*
Y345236D01*
Y343236D01*
G37*
G36*
G01X1034419Y948922D02*
X1030519D01*
X1030219Y949222D01*
Y950622D01*
X1030619Y951022D01*
X1034519D01*
X1034619Y950922D01*
X1034719Y950822D01*
Y949122D01*
X1034519Y948922D01*
X1034419D01*
G37*
G36*
G01X1029819Y955222D02*
X1033719D01*
X1033969Y954972D01*
Y952922D01*
X1033769Y952722D01*
X1029919D01*
X1029719Y952922D01*
Y955122D01*
X1029819Y955222D01*
G37*
G36*
G01X1028450Y1013048D02*
X1043423D01*
G02X1043564Y1012989I-1J-200D01*
G01X1043599Y1012954D01*
G02X1043658Y1012812I-141J-142D01*
G01Y1008253D01*
G02X1043599Y1008111I-200J0D01*
G01X1043573Y1008085D01*
X1043500Y1008055D01*
X1028340D01*
G02X1028198Y1008114I0J200D01*
G01X1027995Y1008317D01*
G02X1027936Y1008459I141J142D01*
G01Y1012135D01*
X1027937D01*
Y1012534D01*
G02X1027996Y1012676I200J0D01*
G01X1028309Y1012989D01*
G02X1028450Y1013048I142J-141D01*
G37*
G36*
G01Y1025648D02*
X1043423D01*
G02X1043564Y1025589I-1J-200D01*
G01X1043599Y1025554D01*
G02X1043658Y1025412I-141J-142D01*
G01Y1020770D01*
X1043633Y1020746D01*
X1035098D01*
X1035074Y1020720D01*
X1028883D01*
G03X1028742Y1020662I0J-200D01*
G01X1028735Y1020655D01*
X1028340D01*
G02X1028198Y1020714I0J200D01*
G01X1027995Y1020917D01*
G02X1027936Y1021059I141J142D01*
G01Y1024735D01*
X1027937D01*
Y1025134D01*
G02X1027996Y1025276I200J0D01*
G01X1028309Y1025589D01*
G02X1028450Y1025648I142J-141D01*
G37*
G36*
G01X1035525Y1019744D02*
X1043328D01*
G02X1043470Y1019685I0J-200D01*
G01X1043487Y1019668D01*
G02X1043546Y1019526I-141J-142D01*
G01Y1014397D01*
G02X1043487Y1014255I-200J0D01*
G01X1043340Y1014108D01*
G02X1043198Y1014049I-142J141D01*
G01X1028769D01*
G02X1028627Y1014108I0J200D01*
G01X1028043Y1014692D01*
G02X1027984Y1014834I141J142D01*
G01Y1018405D01*
G02X1028043Y1018547I200J0D01*
G01X1029156Y1019660D01*
G02X1029298Y1019719I142J-141D01*
G01X1035501D01*
X1035525Y1019744D01*
G37*
G36*
G01X1034710Y1112589D02*
X1044826D01*
G02X1044968Y1112530I0J-200D01*
G01X1045456Y1112042D01*
G02X1045515Y1111900I-141J-142D01*
G01Y1104909D01*
G02X1045456Y1104767I-200J0D01*
G01X1044920Y1104231D01*
G02X1044778Y1104172I-142J141D01*
G01X1038652D01*
G02X1038510Y1104231I0J200D01*
G01X1038291Y1104450D01*
G02X1038232Y1104592I141J142D01*
G01Y1106143D01*
G03X1038173Y1106285I-200J0D01*
G01X1038073Y1106385D01*
G03X1037931Y1106444I-142J-141D01*
G01X1034747D01*
G02X1034605Y1106503I0J200D01*
G01X1034254Y1106854D01*
G02X1034195Y1106996I141J142D01*
G01Y1112075D01*
G02X1034254Y1112217I200J0D01*
G01X1034568Y1112531D01*
G02X1034710Y1112589I141J-142D01*
G37*
G36*
G01X1033955Y1104873D02*
X1036746D01*
G02X1036888Y1104815I1J-200D01*
G01X1037140Y1104563D01*
G02X1037199Y1104421I-141J-142D01*
G01Y1103859D01*
G03X1037258Y1103717I200J0D01*
G01X1037441Y1103534D01*
G03X1037583Y1103475I142J141D01*
G01X1037767D01*
G02X1037908Y1103416I-1J-200D01*
G01X1038096Y1103229D01*
G03X1038237Y1103170I142J141D01*
G01X1042886D01*
G02X1043086Y1102970I0J-200D01*
G01Y1101540D01*
G02X1043027Y1101398I-200J0D01*
G01X1042916Y1101287D01*
G02X1042774Y1101228I-142J141D01*
G01X1034299D01*
G02X1034157Y1101287I0J200D01*
G01X1033610Y1101834D01*
G02X1033551Y1101976I141J142D01*
G01Y1104469D01*
G02X1033610Y1104611I200J0D01*
G01X1033813Y1104814D01*
G02X1033955Y1104873I142J-141D01*
G37*
G36*
G01X1034710Y1125189D02*
X1044826D01*
G02X1044968Y1125130I0J-200D01*
G01X1045420Y1124678D01*
G02X1045479Y1124537I-141J-142D01*
G01Y1117472D01*
G02X1045420Y1117331I-200J1D01*
G01X1044920Y1116831D01*
G02X1044778Y1116772I-142J141D01*
G01X1043850D01*
G02X1043708Y1116831I0J200D01*
G01X1043285Y1117254D01*
G03X1043143Y1117313I-142J-141D01*
G01X1040228D01*
G03X1040086Y1117254I0J-200D01*
G01X1039967Y1117135D01*
G02X1039826Y1117076I-142J141D01*
G01X1038307D01*
X1038234Y1117107D01*
X1038232Y1117109D01*
Y1118743D01*
G03X1038173Y1118885I-200J0D01*
G01X1038073Y1118985D01*
G03X1037931Y1119044I-142J-141D01*
G01X1034747D01*
G02X1034605Y1119103I0J200D01*
G01X1034254Y1119454D01*
G02X1034195Y1119596I141J142D01*
G01Y1124675D01*
G02X1034254Y1124817I200J0D01*
G01X1034568Y1125131D01*
G02X1034710Y1125189I141J-142D01*
G37*
G36*
G01X1033955Y1117473D02*
X1036746D01*
G02X1036888Y1117415I1J-200D01*
G01X1037140Y1117163D01*
G02X1037199Y1117021I-141J-142D01*
G01Y1116459D01*
G03X1037258Y1116317I200J0D01*
G01X1037441Y1116134D01*
G03X1037583Y1116075I142J141D01*
G01X1042789D01*
G02X1042931Y1116016I0J-200D01*
G01X1043027Y1115920D01*
G02X1043086Y1115778I-141J-142D01*
G01Y1114140D01*
G02X1043027Y1113998I-200J0D01*
G01X1042916Y1113887D01*
G02X1042774Y1113828I-142J141D01*
G01X1034299D01*
G02X1034157Y1113887I0J200D01*
G01X1033610Y1114434D01*
G02X1033551Y1114576I141J142D01*
G01Y1117069D01*
G02X1033610Y1117211I200J0D01*
G01X1033813Y1117414D01*
G02X1033955Y1117473I142J-141D01*
G37*
G36*
G01X1034710Y1137789D02*
X1044826D01*
G02X1044968Y1137730I0J-200D01*
G01X1045420Y1137278D01*
G02X1045479Y1137137I-141J-142D01*
G01Y1130072D01*
G02X1045420Y1129931I-200J1D01*
G01X1044920Y1129431D01*
G02X1044778Y1129372I-142J141D01*
G01X1043850D01*
G02X1043708Y1129431I0J200D01*
G01X1043285Y1129854D01*
G03X1043143Y1129913I-142J-141D01*
G01X1040228D01*
G03X1040086Y1129854I0J-200D01*
G01X1039967Y1129735D01*
G02X1039826Y1129676I-142J141D01*
G01X1038307D01*
X1038234Y1129707D01*
X1038232Y1129709D01*
Y1131343D01*
G03X1038173Y1131485I-200J0D01*
G01X1038073Y1131585D01*
G03X1037931Y1131644I-142J-141D01*
G01X1034747D01*
G02X1034605Y1131703I0J200D01*
G01X1034254Y1132054D01*
G02X1034195Y1132196I141J142D01*
G01Y1137275D01*
G02X1034254Y1137417I200J0D01*
G01X1034568Y1137731D01*
G02X1034710Y1137789I141J-142D01*
G37*
G36*
G01X1033955Y1142673D02*
X1036746D01*
G02X1036888Y1142615I1J-200D01*
G01X1037140Y1142363D01*
G02X1037199Y1142221I-141J-142D01*
G01Y1141659D01*
G03X1037258Y1141517I200J0D01*
G01X1037441Y1141334D01*
G03X1037583Y1141275I142J141D01*
G01X1042789D01*
G02X1042931Y1141216I0J-200D01*
G01X1043027Y1141120D01*
G02X1043086Y1140978I-141J-142D01*
G01Y1139340D01*
G02X1043027Y1139198I-200J0D01*
G01X1042916Y1139087D01*
G02X1042774Y1139028I-142J141D01*
G01X1034299D01*
G02X1034157Y1139087I0J200D01*
G01X1033610Y1139634D01*
G02X1033551Y1139776I141J142D01*
G01Y1142269D01*
G02X1033610Y1142411I200J0D01*
G01X1033813Y1142614D01*
G02X1033955Y1142673I142J-141D01*
G37*
G36*
G01Y1130073D02*
X1036746D01*
G02X1036888Y1130015I1J-200D01*
G01X1037140Y1129763D01*
G02X1037199Y1129621I-141J-142D01*
G01Y1129059D01*
G03X1037258Y1128917I200J0D01*
G01X1037441Y1128734D01*
G03X1037583Y1128675I142J141D01*
G01X1042789D01*
G02X1042931Y1128616I0J-200D01*
G01X1043027Y1128520D01*
G02X1043086Y1128378I-141J-142D01*
G01Y1126740D01*
G02X1043027Y1126598I-200J0D01*
G01X1042916Y1126487D01*
G02X1042774Y1126428I-142J141D01*
G01X1034299D01*
G02X1034157Y1126487I0J200D01*
G01X1033610Y1127034D01*
G02X1033551Y1127176I141J142D01*
G01Y1129669D01*
G02X1033610Y1129811I200J0D01*
G01X1033813Y1130014D01*
G02X1033955Y1130073I142J-141D01*
G37*
G36*
G01X1034710Y1150389D02*
X1044826D01*
G02X1044968Y1150330I0J-200D01*
G01X1045420Y1149878D01*
G02X1045479Y1149737I-141J-142D01*
G01Y1142672D01*
G02X1045420Y1142531I-200J1D01*
G01X1044920Y1142031D01*
G02X1044778Y1141972I-142J141D01*
G01X1043850D01*
G02X1043708Y1142031I0J200D01*
G01X1043285Y1142454D01*
G03X1043143Y1142513I-142J-141D01*
G01X1040228D01*
G03X1040086Y1142454I0J-200D01*
G01X1039967Y1142335D01*
G02X1039826Y1142276I-142J141D01*
G01X1038307D01*
X1038234Y1142307D01*
X1038232Y1142309D01*
Y1143943D01*
G03X1038173Y1144085I-200J0D01*
G01X1038073Y1144185D01*
G03X1037931Y1144244I-142J-141D01*
G01X1034747D01*
G02X1034605Y1144303I0J200D01*
G01X1034254Y1144654D01*
G02X1034195Y1144796I141J142D01*
G01Y1149875D01*
G02X1034254Y1150017I200J0D01*
G01X1034568Y1150331D01*
G02X1034710Y1150389I141J-142D01*
G37*
G36*
G01Y1162989D02*
X1044826D01*
G02X1044968Y1162930I0J-200D01*
G01X1045420Y1162478D01*
G02X1045479Y1162337I-141J-142D01*
G01Y1155272D01*
G02X1045420Y1155131I-200J1D01*
G01X1044920Y1154631D01*
G02X1044778Y1154572I-142J141D01*
G01X1043850D01*
G02X1043708Y1154631I0J200D01*
G01X1043285Y1155054D01*
G03X1043143Y1155113I-142J-141D01*
G01X1040228D01*
G03X1040086Y1155054I0J-200D01*
G01X1039967Y1154935D01*
G02X1039826Y1154876I-142J141D01*
G01X1038307D01*
X1038234Y1154907D01*
X1038232Y1154909D01*
Y1156543D01*
G03X1038173Y1156685I-200J0D01*
G01X1038073Y1156785D01*
G03X1037931Y1156844I-142J-141D01*
G01X1034747D01*
G02X1034605Y1156903I0J200D01*
G01X1034254Y1157254D01*
G02X1034195Y1157396I141J142D01*
G01Y1162475D01*
G02X1034254Y1162617I200J0D01*
G01X1034568Y1162931D01*
G02X1034710Y1162989I141J-142D01*
G37*
G36*
G01X1033955Y1155273D02*
X1036746D01*
G02X1036888Y1155215I1J-200D01*
G01X1037140Y1154963D01*
G02X1037199Y1154821I-141J-142D01*
G01Y1154259D01*
G03X1037258Y1154117I200J0D01*
G01X1037441Y1153934D01*
G03X1037583Y1153875I142J141D01*
G01X1042789D01*
G02X1042931Y1153816I0J-200D01*
G01X1043027Y1153720D01*
G02X1043086Y1153578I-141J-142D01*
G01Y1151940D01*
G02X1043027Y1151798I-200J0D01*
G01X1042916Y1151687D01*
G02X1042774Y1151628I-142J141D01*
G01X1034299D01*
G02X1034157Y1151687I0J200D01*
G01X1033610Y1152234D01*
G02X1033551Y1152376I141J142D01*
G01Y1154869D01*
G02X1033610Y1155011I200J0D01*
G01X1033813Y1155214D01*
G02X1033955Y1155273I142J-141D01*
G37*
G36*
G01X1034710Y1175589D02*
X1044826D01*
G02X1044968Y1175530I0J-200D01*
G01X1045456Y1175042D01*
G02X1045515Y1174900I-141J-142D01*
G01Y1167909D01*
G02X1045456Y1167767I-200J0D01*
G01X1044920Y1167231D01*
G02X1044778Y1167172I-142J141D01*
G01X1043850D01*
G02X1043708Y1167231I0J200D01*
G01X1043285Y1167654D01*
G03X1043143Y1167713I-142J-141D01*
G01X1040228D01*
G03X1040086Y1167654I0J-200D01*
G01X1039663Y1167231D01*
G02X1039521Y1167172I-142J141D01*
G01X1038652D01*
G02X1038510Y1167231I0J200D01*
G01X1038291Y1167450D01*
G02X1038232Y1167592I141J142D01*
G01Y1169143D01*
G03X1038173Y1169285I-200J0D01*
G01X1038073Y1169385D01*
G03X1037931Y1169444I-142J-141D01*
G01X1034747D01*
G02X1034605Y1169503I0J200D01*
G01X1034254Y1169854D01*
G02X1034195Y1169996I141J142D01*
G01Y1175075D01*
G02X1034254Y1175217I200J0D01*
G01X1034568Y1175531D01*
G02X1034710Y1175589I141J-142D01*
G37*
G36*
G01X1033955Y1167873D02*
X1036746D01*
G02X1036888Y1167815I1J-200D01*
G01X1037140Y1167563D01*
G02X1037199Y1167421I-141J-142D01*
G01Y1166859D01*
G03X1037258Y1166717I200J0D01*
G01X1037441Y1166534D01*
G03X1037583Y1166475I142J141D01*
G01X1037767D01*
G02X1037908Y1166416I-1J-200D01*
G01X1038096Y1166229D01*
G03X1038237Y1166170I142J141D01*
G01X1039936D01*
G03X1040077Y1166229I-1J200D01*
G01X1040265Y1166416D01*
G02X1040406Y1166475I142J-141D01*
G01X1042789D01*
G02X1042931Y1166416I0J-200D01*
G01X1043027Y1166320D01*
G02X1043086Y1166178I-141J-142D01*
G01Y1164540D01*
G02X1043027Y1164398I-200J0D01*
G01X1042916Y1164287D01*
G02X1042774Y1164228I-142J141D01*
G01X1034299D01*
G02X1034157Y1164287I0J200D01*
G01X1033610Y1164834D01*
G02X1033551Y1164976I141J142D01*
G01Y1167469D01*
G02X1033610Y1167611I200J0D01*
G01X1033813Y1167814D01*
G02X1033955Y1167873I142J-141D01*
G37*
G36*
G01X1034710Y1188189D02*
X1044826D01*
G02X1044968Y1188130I0J-200D01*
G01X1045420Y1187678D01*
G02X1045479Y1187537I-141J-142D01*
G01Y1180472D01*
G02X1045420Y1180331I-200J1D01*
G01X1044920Y1179831D01*
G02X1044778Y1179772I-142J141D01*
G01X1043850D01*
G02X1043708Y1179831I0J200D01*
G01X1043285Y1180254D01*
G03X1043143Y1180313I-142J-141D01*
G01X1040228D01*
G03X1040086Y1180254I0J-200D01*
G01X1039967Y1180135D01*
G02X1039826Y1180076I-142J141D01*
G01X1038307D01*
X1038234Y1180107D01*
X1038232Y1180109D01*
Y1181743D01*
G03X1038173Y1181885I-200J0D01*
G01X1038073Y1181985D01*
G03X1037931Y1182044I-142J-141D01*
G01X1034747D01*
G02X1034605Y1182103I0J200D01*
G01X1034254Y1182454D01*
G02X1034195Y1182596I141J142D01*
G01Y1187675D01*
G02X1034254Y1187817I200J0D01*
G01X1034568Y1188131D01*
G02X1034710Y1188189I141J-142D01*
G37*
G36*
G01X1033955Y1180473D02*
X1036746D01*
G02X1036888Y1180415I1J-200D01*
G01X1037140Y1180163D01*
G02X1037199Y1180021I-141J-142D01*
G01Y1179459D01*
G03X1037258Y1179317I200J0D01*
G01X1037441Y1179134D01*
G03X1037583Y1179075I142J141D01*
G01X1042789D01*
G02X1042931Y1179016I0J-200D01*
G01X1043027Y1178920D01*
G02X1043086Y1178778I-141J-142D01*
G01Y1177140D01*
G02X1043027Y1176998I-200J0D01*
G01X1042916Y1176887D01*
G02X1042774Y1176828I-142J141D01*
G01X1034299D01*
G02X1034157Y1176887I0J200D01*
G01X1033610Y1177434D01*
G02X1033551Y1177576I141J142D01*
G01Y1180069D01*
G02X1033610Y1180211I200J0D01*
G01X1033813Y1180414D01*
G02X1033955Y1180473I142J-141D01*
G37*
G36*
G01X1056128Y86514D02*
X1064843D01*
X1065196Y86161D01*
Y73377D01*
X1064750Y72931D01*
X1056352D01*
X1056017Y73266D01*
Y86403D01*
X1056128Y86514D01*
G37*
G36*
G01X1055694Y600514D02*
X1065097D01*
X1065525Y600086D01*
Y589755D01*
X1066629Y588651D01*
X1069426D01*
X1070012Y588065D01*
Y584209D01*
X1069651Y583848D01*
X1055827D01*
X1055173Y584502D01*
Y599993D01*
X1055694Y600514D01*
G37*
G36*
G01X1045601Y1012136D02*
X1048392D01*
G02X1048534Y1012078I1J-200D01*
G01X1048786Y1011826D01*
G02X1048845Y1011684I-141J-142D01*
G01Y1011122D01*
G03X1048904Y1010980I200J0D01*
G01X1049087Y1010797D01*
G03X1049229Y1010738I142J141D01*
G01X1049413D01*
G02X1049554Y1010679I-1J-200D01*
G01X1049742Y1010492D01*
G03X1049883Y1010434I141J142D01*
G01X1054532D01*
G02X1054732Y1010234I0J-200D01*
G01Y1008803D01*
G02X1054673Y1008661I-200J0D01*
G01X1054562Y1008550D01*
G02X1054420Y1008491I-142J141D01*
G01X1045945D01*
G02X1045803Y1008550I0J200D01*
G01X1045256Y1009097D01*
G02X1045197Y1009239I141J142D01*
G01Y1011732D01*
G02X1045256Y1011874I200J0D01*
G01X1045459Y1012077D01*
G02X1045601Y1012136I142J-141D01*
G37*
G36*
G01X1058530Y1019908D02*
X1062306D01*
G02X1062448Y1019849I0J-200D01*
G01X1062650Y1019647D01*
G02X1062709Y1019505I-141J-142D01*
G01Y1012310D01*
G02X1062650Y1012168I-200J0D01*
G01X1062150Y1011668D01*
G02X1062008Y1011609I-142J141D01*
G01X1058783D01*
G02X1058641Y1011668I0J200D01*
G01X1058221Y1012088D01*
G02X1058163Y1012229I142J141D01*
G01Y1019541D01*
G02X1058221Y1019682I200J0D01*
G01X1058388Y1019849D01*
G02X1058530Y1019908I142J-141D01*
G37*
G36*
G01Y1032508D02*
X1062306D01*
G02X1062448Y1032449I0J-200D01*
G01X1062650Y1032247D01*
G02X1062709Y1032105I-141J-142D01*
G01Y1024910D01*
G02X1062650Y1024768I-200J0D01*
G01X1062150Y1024268D01*
G02X1062008Y1024209I-142J141D01*
G01X1058783D01*
G02X1058641Y1024268I0J200D01*
G01X1058221Y1024688D01*
G02X1058163Y1024829I142J141D01*
G01Y1032141D01*
G02X1058221Y1032282I200J0D01*
G01X1058388Y1032449D01*
G02X1058530Y1032508I142J-141D01*
G37*
G36*
G01X1046356Y1032452D02*
X1056472D01*
G02X1056614Y1032393I0J-200D01*
G01X1057102Y1031905D01*
G02X1057161Y1031763I-141J-142D01*
G01Y1024772D01*
G02X1057102Y1024630I-200J0D01*
G01X1056566Y1024094D01*
G02X1056424Y1024035I-142J141D01*
G01X1050298D01*
G02X1050156Y1024094I0J200D01*
G01X1049937Y1024313D01*
G02X1049878Y1024455I141J142D01*
G01Y1026006D01*
G03X1049819Y1026148I-200J0D01*
G01X1049719Y1026248D01*
G03X1049577Y1026307I-142J-141D01*
G01X1046393D01*
G02X1046251Y1026366I0J200D01*
G01X1045900Y1026717D01*
G02X1045841Y1026859I141J142D01*
G01Y1031938D01*
G02X1045900Y1032080I200J0D01*
G01X1046214Y1032394D01*
G02X1046356Y1032452I141J-142D01*
G37*
G36*
G01Y1019852D02*
X1056472D01*
G02X1056614Y1019793I0J-200D01*
G01X1057102Y1019305D01*
G02X1057161Y1019163I-141J-142D01*
G01Y1012172D01*
G02X1057102Y1012030I-200J0D01*
G01X1056566Y1011494D01*
G02X1056424Y1011435I-142J141D01*
G01X1050298D01*
G02X1050156Y1011494I0J200D01*
G01X1049937Y1011713D01*
G02X1049878Y1011855I141J142D01*
G01Y1013406D01*
G03X1049819Y1013548I-200J0D01*
G01X1049719Y1013648D01*
G03X1049577Y1013707I-142J-141D01*
G01X1046393D01*
G02X1046251Y1013766I0J200D01*
G01X1045900Y1014117D01*
G02X1045841Y1014259I141J142D01*
G01Y1019338D01*
G02X1045900Y1019480I200J0D01*
G01X1046214Y1019794D01*
G02X1046356Y1019852I141J-142D01*
G37*
G36*
G01X1045601Y1024736D02*
X1048392D01*
G02X1048534Y1024678I1J-200D01*
G01X1048786Y1024426D01*
G02X1048845Y1024284I-141J-142D01*
G01Y1023722D01*
G03X1048904Y1023580I200J0D01*
G01X1049087Y1023397D01*
G03X1049229Y1023338I142J141D01*
G01X1049413D01*
G02X1049554Y1023279I-1J-200D01*
G01X1049742Y1023092D01*
G03X1049883Y1023034I141J142D01*
G01X1054532D01*
G02X1054732Y1022834I0J-200D01*
G01Y1021403D01*
G02X1054673Y1021261I-200J0D01*
G01X1054562Y1021150D01*
G02X1054420Y1021091I-142J141D01*
G01X1045945D01*
G02X1045803Y1021150I0J200D01*
G01X1045256Y1021697D01*
G02X1045197Y1021839I141J142D01*
G01Y1024332D01*
G02X1045256Y1024474I200J0D01*
G01X1045459Y1024677D01*
G02X1045601Y1024736I142J-141D01*
G37*
G36*
G01X1046884Y1188245D02*
X1049172D01*
X1049711Y1187706D01*
Y1166474D01*
X1050062Y1166123D01*
X1050888Y1165297D01*
Y1104789D01*
X1050504Y1104405D01*
G02X1050482Y1104386I-141J141D01*
G02X1050362Y1104346I-120J160D01*
G01X1047137D01*
G02X1047017Y1104386I0J200D01*
G02X1046995Y1104405I119J160D01*
G01X1046575Y1104825D01*
G02X1046517Y1104966I142J141D01*
G01Y1112278D01*
G02X1046548Y1112385I200J0D01*
G01Y1117452D01*
X1046539Y1117461D01*
G02X1046520Y1117483I141J141D01*
G02X1046480Y1117603I160J120D01*
G01Y1124841D01*
G02X1046520Y1124961I200J0D01*
G02X1046539Y1124983I160J-119D01*
G01X1046548Y1124992D01*
Y1130052D01*
X1046539Y1130061D01*
G02X1046520Y1130083I141J141D01*
G02X1046480Y1130203I160J120D01*
G01Y1137441D01*
G02X1046520Y1137561I200J0D01*
G02X1046539Y1137583I160J-119D01*
G01X1046548Y1137592D01*
Y1142652D01*
X1046539Y1142661D01*
G02X1046520Y1142683I141J141D01*
G02X1046480Y1142803I160J120D01*
G01Y1150041D01*
G02X1046520Y1150161I200J0D01*
G02X1046539Y1150183I160J-119D01*
G01X1046548Y1150192D01*
Y1155252D01*
X1046539Y1155261D01*
G02X1046520Y1155283I141J141D01*
G02X1046480Y1155403I160J120D01*
G01Y1162641D01*
G02X1046520Y1162761I200J0D01*
G02X1046539Y1162783I160J-119D01*
G01X1046548Y1162792D01*
Y1167859D01*
G02X1046517Y1167966I169J107D01*
G01Y1175278D01*
G02X1046548Y1175385I200J0D01*
G01Y1178989D01*
X1046838Y1179279D01*
Y1180161D01*
X1046815Y1180184D01*
Y1183102D01*
X1046480Y1183437D01*
Y1187841D01*
G02X1046520Y1187961I200J0D01*
G02X1046539Y1187983I160J-119D01*
G01X1046742Y1188186D01*
G02X1046764Y1188205I141J-141D01*
G02X1046884Y1188245I120J-160D01*
G37*
G36*
G01X1055281Y1170570D02*
G03I-400J0D01*
G37*
G36*
G01Y1178050D02*
G03I-400J0D01*
G37*
G36*
G01X1055910Y1198622D02*
G03I-400J0D01*
G37*
G36*
G01Y1191142D02*
G03I-400J0D01*
G37*
G36*
G01Y1221063D02*
G03I-400J0D01*
G37*
G36*
G01Y1213583D02*
G03I-400J0D01*
G37*
G36*
G01Y1206103D02*
G03I-400J0D01*
G37*
G36*
G01Y1228542D02*
G03I-400J0D01*
G37*
G36*
G01X1055909Y1239762D02*
G03I-400J0D01*
G37*
G36*
G01Y1247242D02*
G03I-400J0D01*
G37*
G36*
G01X1090157Y1490945D02*
G03I-19685J0D01*
G37*
G36*
G01X1084505Y89438D02*
X1098570D01*
G02X1098712Y89379I0J-200D01*
G01X1098714Y89376D01*
Y74039D01*
G03X1098773Y73898I200J1D01*
G01X1098820Y73851D01*
G02Y73568I-141J-141D01*
G01X1098633Y73381D01*
G02X1098491Y73322I-142J141D01*
G01X1094676D01*
X1094673Y73319D01*
X1074245D01*
X1074187Y73377D01*
X1074186Y73378D01*
X1074118Y73446D01*
X1074117Y73447D01*
X1074059Y73505D01*
Y86363D01*
X1074117Y86421D01*
X1074118Y86422D01*
X1074186Y86490D01*
X1074187Y86491D01*
X1074245Y86549D01*
X1079639D01*
G03X1079781Y86608I0J200D01*
G01X1080614Y87441D01*
G03X1080673Y87583I-141J142D01*
G01Y88917D01*
G02X1080732Y89059I200J0D01*
G01X1081052Y89379D01*
G02X1081194Y89438I142J-141D01*
G01X1084165D01*
G02X1084306Y89379I-1J-200D01*
G01X1084404D01*
X1084432Y89408D01*
X1084505Y89438D01*
G37*
G36*
G01X1072054Y176789D02*
X1086481D01*
X1087244Y176026D01*
Y174795D01*
X1088007Y174032D01*
X1091115D01*
X1091702Y173445D01*
Y161423D01*
X1090998Y160719D01*
X1072699D01*
Y160720D01*
X1070703D01*
X1069942Y161481D01*
Y176203D01*
X1070528Y176789D01*
X1072054D01*
G37*
G36*
G01X1098973Y219609D02*
X1100615D01*
X1101007Y219217D01*
Y210795D01*
X1100799Y210587D01*
X1099495D01*
X1099443Y210639D01*
X1099051D01*
X1099036Y210624D01*
X1098355D01*
X1097930Y210199D01*
Y209518D01*
Y204802D01*
X1087461Y194333D01*
Y189191D01*
X1091098Y185554D01*
X1095863D01*
X1096411Y185006D01*
Y183690D01*
X1097406Y182695D01*
X1099340D01*
X1099727Y182308D01*
X1101941D01*
X1102119Y182130D01*
Y181714D01*
X1101806Y181401D01*
X1098596D01*
X1098195Y181000D01*
X1098150D01*
X1096857Y179707D01*
X1071298D01*
X1069986Y181019D01*
Y216698D01*
X1070889Y217601D01*
X1096965D01*
X1098973Y219609D01*
G37*
G36*
G01X1097333Y234621D02*
Y221520D01*
X1095532Y219719D01*
X1094436Y218623D01*
X1071595D01*
X1069867Y220351D01*
Y252516D01*
X1071178Y253827D01*
X1093418D01*
X1097333Y249912D01*
Y234621D01*
G37*
G36*
G01X1072213Y277007D02*
X1079642D01*
X1092093D01*
X1093950Y275150D01*
X1096529D01*
X1096804Y274875D01*
Y272398D01*
X1096254Y271848D01*
X1093710D01*
X1093606Y271952D01*
X1089926Y268272D01*
Y265554D01*
X1086728Y262356D01*
X1072144D01*
X1071456Y263044D01*
Y276250D01*
X1072213Y277007D01*
G37*
G36*
G01X1076467Y299467D02*
X1085490D01*
X1089926Y295031D01*
Y278899D01*
X1089685Y278658D01*
X1072935D01*
X1071663Y279930D01*
Y294663D01*
X1076467Y299467D01*
G37*
G36*
G01X1067132Y1258465D02*
G03I-400J0D01*
G37*
G36*
G01X1074612D02*
G03I-400J0D01*
G37*
G36*
G01X1084240Y-78528D02*
G03I-557J0D01*
G37*
G36*
G01Y-83484D02*
G03I-557J0D01*
G37*
G36*
G01Y-73484D02*
G03I-557J0D01*
G37*
G36*
G01Y-68528D02*
G03I-557J0D01*
G37*
G36*
G01X1154193Y54588D02*
X1181332D01*
Y52591D01*
X1154193D01*
G03X1148256Y46654I0J-5937D01*
G01Y7874D01*
G02X1142382Y2000I-5874J0D01*
G01X1095138D01*
G02X1089264Y7874I0J5874D01*
G01Y46305D01*
X1091262D01*
Y7874D01*
G03X1095138Y3998I3876J0D01*
G01X1142382D01*
G03X1146258Y7874I0J3876D01*
G01Y46654D01*
G02X1154193Y54588I7935J-1D01*
G37*
G36*
G01X1084157Y95055D02*
X1099173D01*
X1099193Y95035D01*
X1103198D01*
X1103911Y94322D01*
Y74773D01*
X1103050Y73912D01*
X1100439D01*
X1100175D01*
X1099716Y74371D01*
Y90663D01*
X1099593Y90786D01*
X1098887D01*
X1096132D01*
X1084394D01*
X1084355Y90747D01*
X1084078Y91024D01*
Y94976D01*
X1084157Y95055D01*
G37*
G36*
G01X1089571Y1071455D02*
G03I-400J0D01*
G37*
G36*
G01D02*
G03I-400J0D01*
G37*
G36*
G01X1082092Y1258465D02*
G03I-400J0D01*
G37*
G36*
G01X1089573D02*
G03I-400J0D01*
G37*
G36*
G01X1104068Y276354D02*
X1121641D01*
X1122467Y275528D01*
Y258570D01*
X1120396Y256499D01*
Y231032D01*
X1114333Y224969D01*
Y224264D01*
Y220921D01*
X1112033Y218621D01*
X1110033D01*
X1109743Y218331D01*
Y205660D01*
X1109156Y205073D01*
X1102324D01*
X1101816Y205581D01*
Y220421D01*
X1098533Y223704D01*
Y234821D01*
X1098699Y234987D01*
Y250246D01*
X1101863Y253410D01*
X1101899D01*
X1104119Y255630D01*
Y268925D01*
X1101110Y271934D01*
X1098806D01*
X1098290Y272450D01*
Y274738D01*
X1098513Y274961D01*
X1102675D01*
X1104068Y276354D01*
G37*
G36*
G01X1099322Y276095D02*
X1100061D01*
X1100087Y276122D01*
X1102288D01*
X1103740Y277574D01*
X1105375D01*
X1105409Y277540D01*
X1112580D01*
X1112612Y277572D01*
X1120343D01*
X1122158Y279387D01*
Y287118D01*
Y296369D01*
X1121332Y297195D01*
X1105100D01*
X1102985Y295080D01*
Y282733D01*
X1100802Y280550D01*
X1099012Y278760D01*
Y276405D01*
X1099322Y276095D01*
G37*
G36*
G01X1097052Y1071455D02*
G03I-400J0D01*
G37*
G36*
G01D02*
G03I-400J0D01*
G37*
G36*
G01X1104532D02*
G03I-400J0D01*
G37*
G36*
G01D02*
G03I-400J0D01*
G37*
G36*
G01X1097053Y1258465D02*
G03I-400J0D01*
G37*
G36*
G01X1104533D02*
G03I-400J0D01*
G37*
G36*
G01X1127280Y115094D02*
X1128336D01*
X1128363Y115067D01*
Y111227D01*
G02X1128304Y111085I-200J0D01*
G01X1126674Y109456D01*
G03X1126615Y109314I141J-142D01*
G01Y106183D01*
G03X1126674Y106041I200J0D01*
G01X1126797Y105918D01*
G03X1126939Y105859I142J141D01*
G01X1137645D01*
G03X1137787Y105918I0J200D01*
G01X1137863Y105994D01*
G03X1137922Y106136I-141J142D01*
G01Y109681D01*
G03X1137863Y109823I-200J0D01*
G01X1137629Y110057D01*
G02X1137570Y110199I141J142D01*
G01Y114552D01*
X1137600Y114625D01*
X1137611Y114636D01*
X1143195D01*
X1144537D01*
X1144601Y114572D01*
X1144717Y114456D01*
G02X1144776Y114314I-141J-142D01*
G01Y105226D01*
G02X1144717Y105084I-200J0D01*
G01X1144046Y104413D01*
X1143963Y104383D01*
X1143918Y104388D01*
G03X1143736Y104396I-174J-1893D01*
G01X1141154D01*
X1139868D01*
X1139122Y103650D01*
Y101528D01*
X1138790Y101196D01*
X1127259D01*
X1127235Y101202D01*
X1120055D01*
X1119360Y101897D01*
Y102887D01*
Y114049D01*
G02X1119419Y114191I200J0D01*
G01X1119541Y114313D01*
G02X1119683Y114372I142J-141D01*
G01X1126392D01*
G03X1126534Y114431I0J200D01*
G01X1127138Y115035D01*
G02X1127280Y115094I142J-141D01*
G37*
G36*
G01X1119542Y120851D02*
X1124959D01*
G02X1125101Y120792I0J-200D01*
G01X1126722Y119171D01*
G03X1126864Y119112I142J141D01*
G01X1128379D01*
G02X1128521Y119053I0J-200D01*
G01X1128994Y118580D01*
G02X1129053Y118438I-141J-142D01*
G01Y116276D01*
G02X1128930Y116091I-200J0D01*
G01X1128873Y116068D01*
X1128755Y116091D01*
X1128751Y116096D01*
X1127279D01*
G03X1126465Y115777I1J-1202D01*
G02X1126329Y115724I-136J147D01*
G01X1119483D01*
G02X1119341Y115783I0J200D01*
G01X1119326Y115798D01*
X1119296Y115871D01*
Y120605D01*
G02X1119355Y120747I200J0D01*
G01X1119400Y120792D01*
G02X1119542Y120851I142J-141D01*
G37*
G36*
G01X1110718Y576428D02*
X1118566D01*
X1118972Y576022D01*
Y564567D01*
X1118452Y564048D01*
X1117027D01*
X1116500Y563521D01*
X1110479D01*
X1110402Y563598D01*
Y576112D01*
X1110718Y576428D01*
G37*
G36*
G01X1119493Y1071455D02*
G03I-400J0D01*
G37*
G36*
G01D02*
G03I-400J0D01*
G37*
G36*
G01X1112012D02*
G03I-400J0D01*
G37*
G36*
G01D02*
G03I-400J0D01*
G37*
G36*
G01X1119494Y1258465D02*
G03I-400J0D01*
G37*
G36*
G01X1112014D02*
G03I-400J0D01*
G37*
G36*
G01X1130645Y119235D02*
X1134091D01*
X1136927Y122071D01*
X1142974D01*
X1143344Y121701D01*
Y116118D01*
X1142863Y115637D01*
X1133189D01*
X1130833D01*
X1130485Y115985D01*
Y119075D01*
X1130645Y119235D01*
G37*
G36*
G01X1129217Y210785D02*
X1138657D01*
X1140458Y208984D01*
X1141554Y207888D01*
Y187037D01*
X1140607Y186090D01*
X1129835D01*
X1128391Y187534D01*
Y209959D01*
X1129217Y210785D01*
G37*
G36*
G01X1141846Y223195D02*
X1151871D01*
X1151901Y223225D01*
X1154424D01*
X1157061Y225862D01*
X1166003D01*
X1166345Y225520D01*
Y213126D01*
X1165633Y212414D01*
X1158216D01*
X1155362Y215268D01*
X1151922D01*
X1140945D01*
X1139381D01*
X1138935Y214822D01*
Y213258D01*
X1137662Y211985D01*
X1137250D01*
X1136473D01*
X1128846D01*
X1128186Y212645D01*
Y226569D01*
X1128862Y227245D01*
X1139796D01*
X1141556Y225485D01*
Y223485D01*
X1141846Y223195D01*
G37*
G36*
G01X1134453Y1071455D02*
G03I-400J0D01*
G37*
G36*
G01D02*
G03I-400J0D01*
G37*
G36*
G01X1126973D02*
G03I-400J0D01*
G37*
G36*
G01D02*
G03I-400J0D01*
G37*
G36*
G01X1134455Y1258465D02*
G03I-400J0D01*
G37*
G36*
G01X1126974D02*
G03I-400J0D01*
G37*
G36*
G01X1142576Y186998D02*
Y210417D01*
X1140568Y212425D01*
Y214067D01*
X1140960Y214459D01*
X1149382D01*
X1149590Y214251D01*
Y212947D01*
X1149538Y212895D01*
Y212503D01*
Y211586D01*
X1149742Y211382D01*
X1150659D01*
X1154885D01*
X1156213Y210054D01*
Y205828D01*
Y187369D01*
X1155058Y186214D01*
X1143360D01*
X1142576Y186998D01*
G37*
G36*
G01X1156894Y1071455D02*
G03I-400J0D01*
G37*
G36*
G01X1149414Y1071454D02*
G03I-400J0D01*
G37*
G36*
G01D02*
G03I-400J0D01*
G37*
G36*
G01X1156894Y1071455D02*
G03I-400J0D01*
G37*
G36*
G01X1141934D02*
G03I-400J0D01*
G37*
G36*
G01D02*
G03I-400J0D01*
G37*
G36*
G01X1149415Y1258465D02*
G03I-400J0D01*
G37*
G36*
G01X1156895D02*
G03I-400J0D01*
G37*
G36*
G01X1141936D02*
G03I-400J0D01*
G37*
G36*
G01X1158490Y86514D02*
X1167205D01*
X1167558Y86161D01*
Y73377D01*
X1167112Y72931D01*
X1158714D01*
X1158379Y73266D01*
Y86403D01*
X1158490Y86514D01*
G37*
G36*
G01X1174416Y176789D02*
X1188843D01*
X1189606Y176026D01*
Y174795D01*
X1190369Y174032D01*
X1193477D01*
X1194064Y173445D01*
Y161423D01*
X1193360Y160719D01*
X1175061D01*
Y160720D01*
X1173065D01*
X1172304Y161481D01*
Y176203D01*
X1172890Y176789D01*
X1174416D01*
G37*
G36*
G01X1199695Y234621D02*
Y221520D01*
X1197894Y219719D01*
X1196798Y218623D01*
X1173957D01*
X1172229Y220351D01*
Y252516D01*
X1173540Y253827D01*
X1195780D01*
X1199695Y249912D01*
Y234621D01*
G37*
G36*
G01X1171855Y1071455D02*
G03I-400J0D01*
G37*
G36*
G01D02*
G03I-400J0D01*
G37*
G36*
G01X1164375D02*
G03I-400J0D01*
G37*
G36*
G01D02*
G03I-400J0D01*
G37*
G36*
G01X1164376Y1258465D02*
G03I-400J0D01*
G37*
G36*
G01X1171856D02*
G03I-400J0D01*
G37*
G36*
G01X1186668Y89379D02*
X1186766D01*
G02X1186907Y89438I142J-141D01*
G01X1200932D01*
G02X1201074Y89379I0J-200D01*
G01X1201076Y89376D01*
Y74039D01*
G03X1201135Y73898I200J1D01*
G01X1201182Y73851D01*
G02Y73568I-141J-141D01*
G01X1200995Y73381D01*
G02X1200853Y73322I-142J141D01*
G01X1197038D01*
X1197035Y73319D01*
X1176690D01*
G02X1176548Y73378I0J200D01*
G01X1176480Y73446D01*
G02X1176421Y73588I141J142D01*
G01Y86280D01*
G02X1176480Y86422I200J0D01*
G01X1176548Y86490D01*
G02X1176690Y86549I142J-141D01*
G01X1182001D01*
G03X1182143Y86608I0J200D01*
G01X1182976Y87441D01*
G03X1183035Y87583I-141J142D01*
G01Y88917D01*
G02X1183094Y89059I200J0D01*
G01X1183414Y89379D01*
G02X1183556Y89438I142J-141D01*
G01X1186527D01*
G02X1186668Y89379I-1J-200D01*
G37*
G36*
G01X1186519Y95055D02*
X1201535D01*
X1201555Y95035D01*
X1205560D01*
X1206273Y94322D01*
Y74773D01*
X1205412Y73912D01*
X1202801D01*
X1202537D01*
X1202078Y74371D01*
Y90663D01*
X1201955Y90786D01*
X1201249D01*
X1198494D01*
X1186756D01*
X1186717Y90747D01*
X1186440Y91024D01*
Y94976D01*
X1186519Y95055D01*
G37*
G36*
G01X1201335Y219609D02*
X1202977D01*
X1203369Y219217D01*
Y210795D01*
X1203161Y210587D01*
X1201857D01*
X1201805Y210639D01*
X1201413D01*
X1201398Y210624D01*
X1200528D01*
X1200292Y210388D01*
Y209518D01*
Y204802D01*
X1189823Y194333D01*
Y189191D01*
X1193460Y185554D01*
X1198225D01*
X1198773Y185006D01*
Y183690D01*
X1199768Y182695D01*
X1201702D01*
X1202089Y182308D01*
X1204303D01*
X1204481Y182130D01*
Y181714D01*
X1204168Y181401D01*
X1200958D01*
X1200557Y181000D01*
X1200512D01*
X1199219Y179707D01*
X1173660D01*
X1172348Y181019D01*
Y216698D01*
X1173251Y217601D01*
X1199327D01*
X1201335Y219609D01*
G37*
G36*
G01X1174575Y277007D02*
X1182004D01*
X1194455D01*
X1196312Y275150D01*
X1198891D01*
X1199166Y274875D01*
Y272398D01*
X1198616Y271848D01*
X1196072D01*
X1195968Y271952D01*
X1192288Y268272D01*
Y265554D01*
X1189090Y262356D01*
X1174506D01*
X1173818Y263044D01*
Y276250D01*
X1174575Y277007D01*
G37*
G36*
G01X1177568Y299467D02*
X1187852D01*
X1192288Y295031D01*
Y278899D01*
X1192047Y278658D01*
X1175297D01*
X1174025Y279930D01*
Y295924D01*
X1177568Y299467D01*
G37*
G36*
G01X1187313Y429084D02*
X1179465D01*
X1179059Y429490D01*
Y440559D01*
X1180491Y441991D01*
X1187009D01*
X1187629Y441371D01*
Y429400D01*
X1187313Y429084D01*
G37*
G36*
G01X1284384Y551149D02*
X1305763Y529770D01*
G03X1305905Y529711I142J141D01*
G01X1325678D01*
G02X1325820Y529652I0J-200D01*
G01X1328344Y527128D01*
G02X1328403Y526986I-141J-142D01*
G01Y520666D01*
G02X1328344Y520524I-200J0D01*
G01X1324859Y517039D01*
G02X1324717Y516980I-142J141D01*
G01X1299781D01*
G02X1299639Y517039I0J200D01*
G01X1269491Y547187D01*
G02X1269432Y547329I141J142D01*
G01Y604453D01*
G03X1269373Y604595I-200J0D01*
G01X1247531Y626437D01*
G03X1247389Y626496I-142J-141D01*
G01X1238266D01*
G02X1238124Y626555I0J200D01*
G01X1233459Y631220D01*
G02X1233400Y631362I141J142D01*
G01Y848744D01*
G03X1233341Y848886I-200J0D01*
G01X1189982Y892245D01*
G03X1189840Y892304I-142J-141D01*
G01X1186883D01*
G02X1186741Y892363I0J200D01*
G01X1185418Y893686D01*
G02X1185359Y893828I141J142D01*
G01Y903511D01*
G02X1185418Y903653I200J0D01*
G01X1187463Y905698D01*
G02X1187605Y905757I142J-141D01*
G01X1201130D01*
G02X1201272Y905698I0J-200D01*
G01X1250157Y856813D01*
G02X1250216Y856671I-141J-142D01*
G01Y652659D01*
G03X1250275Y652517I200J0D01*
G01X1284266Y618526D01*
G02X1284325Y618384I-141J-142D01*
G01Y551291D01*
G03X1284384Y551149I200J0D01*
G37*
G36*
G01X1186816Y1071455D02*
G03I-400J0D01*
G37*
G36*
G01X1179335D02*
G03I-400J0D01*
G37*
G36*
G01D02*
G03I-400J0D01*
G37*
G36*
G01X1186816D02*
G03I-400J0D01*
G37*
G36*
G01X1179336Y1258465D02*
G03I-400J0D01*
G37*
G36*
G01X1186817D02*
G03I-400J0D01*
G37*
G36*
G01X1256555Y54588D02*
X1285191D01*
X1285226D01*
X1285275Y54539D01*
Y52675D01*
X1285191Y52591D01*
X1256555D01*
G03X1250618Y46654I0J-5937D01*
G01Y7874D01*
G02X1244744Y2000I-5874J0D01*
G01X1197500D01*
G02X1191626Y7874I0J5874D01*
G01Y46654D01*
G03X1190170Y50549I-5938J0D01*
G01Y50728D01*
X1190174Y50732D01*
X1192419D01*
X1192602Y50549D01*
G02X1193624Y46654I-6911J-3895D01*
G01Y7874D01*
G03X1197500Y3998I3876J0D01*
G01X1244744D01*
G03X1248620Y7874I0J3876D01*
G01Y46654D01*
G02X1256555Y54588I7935J-1D01*
G37*
G36*
G01X1206430Y276354D02*
X1224003D01*
X1224829Y275528D01*
Y258570D01*
X1223194Y256935D01*
Y231772D01*
X1216695Y225273D01*
Y224599D01*
Y220921D01*
X1214395Y218621D01*
X1212395D01*
X1212105Y218331D01*
Y205660D01*
X1211518Y205073D01*
X1204686D01*
X1204178Y205581D01*
Y220421D01*
X1200895Y223704D01*
Y234821D01*
X1201061Y234987D01*
Y250246D01*
X1204225Y253410D01*
X1204261D01*
X1206481Y255630D01*
Y268925D01*
X1203472Y271934D01*
X1201168D01*
X1200652Y272450D01*
Y274738D01*
X1200875Y274961D01*
X1205037D01*
X1206430Y276354D01*
G37*
G36*
G01X1201684Y276095D02*
X1202423D01*
X1202449Y276122D01*
X1204650D01*
X1206102Y277574D01*
X1207737D01*
X1207771Y277540D01*
X1214942D01*
X1214974Y277572D01*
X1222705D01*
X1224520Y279387D01*
Y287118D01*
Y296369D01*
X1223694Y297195D01*
X1207462D01*
X1205347Y295080D01*
Y282733D01*
X1203164Y280550D01*
X1201374Y278760D01*
Y276405D01*
X1201684Y276095D01*
G37*
G36*
G01X1200264Y442631D02*
X1211500D01*
X1211529Y442602D01*
X1247222D01*
X1253245Y436579D01*
X1267914D01*
X1269524Y434969D01*
Y432764D01*
Y428021D01*
Y411754D01*
G02X1269466Y411613I-200J0D01*
G01X1268816Y410963D01*
G02X1268675Y410905I-141J142D01*
G01X1266123D01*
X1259193D01*
X1249526D01*
X1237326Y423104D01*
X1218689D01*
X1212489Y429304D01*
X1200235D01*
X1200101Y429438D01*
Y442468D01*
X1200264Y442631D01*
G37*
G36*
G01X1260289Y482893D02*
X1284464D01*
Y473993D01*
X1284374Y473903D01*
X1278578D01*
X1276884Y472209D01*
Y457025D01*
X1276536Y456677D01*
X1273446D01*
X1273286Y456837D01*
Y458826D01*
X1273205D01*
X1270172Y461859D01*
X1259209D01*
X1248046Y450696D01*
X1207109D01*
X1204834Y452971D01*
X1200281D01*
X1200175Y453077D01*
Y454290D01*
X1200270Y454385D01*
X1205880D01*
X1207759Y456264D01*
X1209855D01*
X1216878Y463287D01*
X1240683D01*
X1260289Y482893D01*
G37*
G36*
G01X1199525Y998504D02*
G03I-680J0D01*
G37*
G36*
G01X1202845Y1013551D02*
G03I-577J0D01*
G37*
G36*
G01X1201776Y1071455D02*
G03I-400J0D01*
G37*
G36*
G01X1194296D02*
G03I-400J0D01*
G37*
G36*
G01D02*
G03I-400J0D01*
G37*
G36*
G01X1201776D02*
G03I-400J0D01*
G37*
G36*
G01X1194297Y1258465D02*
G03I-400J0D01*
G37*
G36*
G01X1201777D02*
G03I-400J0D01*
G37*
G36*
G01X1237003Y419512D02*
Y410583D01*
X1235369Y408949D01*
X1223245D01*
X1218394Y413800D01*
Y419785D01*
X1218400Y419790D01*
Y420905D01*
X1219444Y421949D01*
X1235900D01*
X1237003Y420846D01*
Y419512D01*
G37*
G36*
G01X1278571Y469053D02*
X1283531D01*
X1283547Y469037D01*
X1283992D01*
X1286275Y466754D01*
X1294972D01*
X1295987Y465739D01*
Y458596D01*
X1310638D01*
Y449570D01*
X1309089Y448021D01*
X1299119D01*
X1297060Y445962D01*
Y445880D01*
X1295929Y444749D01*
X1281867D01*
X1280202Y443084D01*
Y438941D01*
X1279763Y438502D01*
X1254479D01*
X1248626Y444355D01*
X1210728D01*
X1210350Y444733D01*
Y448862D01*
X1210833Y449345D01*
X1253161D01*
X1259071Y443435D01*
X1271594D01*
X1271595Y443434D01*
X1277388D01*
X1278149Y444195D01*
Y452584D01*
G03X1278090Y452726I-200J0D01*
G01X1277486Y453330D01*
G02X1277427Y453472I141J142D01*
G01Y454528D01*
X1277454Y454555D01*
X1281294D01*
G02X1281436Y454496I0J-200D01*
G01X1283065Y452866D01*
G03X1283207Y452807I142J141D01*
G01X1286338D01*
G03X1286480Y452866I0J200D01*
G01X1286603Y452989D01*
G03X1286662Y453131I-141J142D01*
G01Y463837D01*
G03X1286603Y463979I-200J0D01*
G01X1286527Y464055D01*
G03X1286385Y464114I-142J-141D01*
G01X1282840D01*
G03X1282698Y464055I0J-200D01*
G01X1282464Y463821D01*
G02X1282322Y463762I-142J141D01*
G01X1277969D01*
X1277896Y463792D01*
X1277885Y463803D01*
Y468367D01*
X1278571Y469053D01*
G37*
G36*
G01X1216738Y1071455D02*
G03I-400J0D01*
G37*
G36*
G01D02*
G03I-400J0D01*
G37*
G36*
G01X1209257D02*
G03I-400J0D01*
G37*
G36*
G01D02*
G03I-400J0D01*
G37*
G36*
G01X1216738Y1258465D02*
G03I-400J0D01*
G37*
G36*
G01X1209258D02*
G03I-400J0D01*
G37*
G36*
G01X1223466Y-83456D02*
G03I-557J0D01*
G37*
G36*
G01Y-78500D02*
G03I-557J0D01*
G37*
G36*
G01Y-68500D02*
G03I-557J0D01*
G37*
G36*
G01Y-73456D02*
G03I-557J0D01*
G37*
G36*
G01X1228822Y-44406D02*
G03I-557J0D01*
G37*
G36*
G01Y-39450D02*
G03I-557J0D01*
G37*
G36*
G01Y-29450D02*
G03I-557J0D01*
G37*
G36*
G01Y-34406D02*
G03I-557J0D01*
G37*
G36*
G01X1229642Y115094D02*
X1230698D01*
X1230725Y115067D01*
Y111227D01*
G02X1230666Y111085I-200J0D01*
G01X1229036Y109456D01*
G03X1228977Y109314I141J-142D01*
G01Y106183D01*
G03X1229036Y106041I200J0D01*
G01X1229159Y105918D01*
G03X1229301Y105859I142J141D01*
G01X1240007D01*
G03X1240149Y105918I0J200D01*
G01X1240225Y105994D01*
G03X1240284Y106136I-141J142D01*
G01Y109681D01*
G03X1240225Y109823I-200J0D01*
G01X1239991Y110057D01*
G02X1239932Y110199I141J142D01*
G01Y114552D01*
X1239962Y114625D01*
X1239973Y114636D01*
X1245557D01*
X1246899D01*
X1246963Y114572D01*
X1247079Y114456D01*
G02X1247138Y114314I-141J-142D01*
G01Y105226D01*
G02X1247079Y105084I-200J0D01*
G01X1246408Y104413D01*
X1246325Y104383D01*
X1246280Y104388D01*
G03X1246098Y104396I-174J-1893D01*
G01X1243516D01*
X1242230D01*
X1241484Y103650D01*
Y101528D01*
X1241152Y101196D01*
X1229621D01*
X1229597Y101202D01*
X1222417D01*
X1221722Y101897D01*
Y102887D01*
Y114049D01*
G02X1221781Y114191I200J0D01*
G01X1221903Y114313D01*
G02X1222045Y114372I142J-141D01*
G01X1228754D01*
G03X1228896Y114431I0J200D01*
G01X1229500Y115035D01*
G02X1229642Y115094I142J-141D01*
G37*
G36*
G01X1233007Y119235D02*
X1236453D01*
X1239289Y122071D01*
X1245336D01*
X1245706Y121701D01*
Y116118D01*
X1245225Y115637D01*
X1235551D01*
X1233195D01*
X1232847Y115985D01*
Y119075D01*
X1233007Y119235D01*
G37*
G36*
G01X1221904Y120851D02*
X1227321D01*
G02X1227463Y120792I0J-200D01*
G01X1229084Y119171D01*
G03X1229226Y119112I142J141D01*
G01X1230741D01*
G02X1230883Y119053I0J-200D01*
G01X1231356Y118580D01*
G02X1231415Y118438I-141J-142D01*
G01Y116276D01*
G02X1231292Y116091I-200J0D01*
G01X1231235Y116068D01*
X1231117Y116091D01*
X1231113Y116096D01*
X1229641D01*
G03X1228827Y115777I1J-1202D01*
G02X1228691Y115724I-136J147D01*
G01X1221845D01*
G02X1221703Y115783I0J200D01*
G01X1221688Y115798D01*
X1221658Y115871D01*
Y120605D01*
G02X1221717Y120747I200J0D01*
G01X1221762Y120792D01*
G02X1221904Y120851I142J-141D01*
G37*
G36*
G01X1231579Y210785D02*
X1241019D01*
X1242820Y208984D01*
X1243916Y207888D01*
Y187037D01*
X1242969Y186090D01*
X1232197D01*
X1230753Y187534D01*
Y209959D01*
X1231579Y210785D01*
G37*
G36*
G01X1244208Y223195D02*
X1254233D01*
X1254263Y223225D01*
X1256786D01*
X1259423Y225862D01*
X1268365D01*
X1268707Y225520D01*
Y213126D01*
X1267995Y212414D01*
X1260578D01*
X1257724Y215268D01*
X1254284D01*
X1243307D01*
X1241743D01*
X1241297Y214822D01*
Y213258D01*
X1240024Y211985D01*
X1239612D01*
X1238835D01*
X1231208D01*
X1230548Y212645D01*
Y226569D01*
X1231224Y227245D01*
X1242158D01*
X1243918Y225485D01*
Y223485D01*
X1244208Y223195D01*
G37*
G36*
G01X1231698Y1071455D02*
G03I-400J0D01*
G37*
G36*
G01D02*
G03I-400J0D01*
G37*
G36*
G01X1224218D02*
G03I-400J0D01*
G37*
G36*
G01D02*
G03I-400J0D01*
G37*
G36*
G01X1231698Y1258465D02*
G03I-400J0D01*
G37*
G36*
G01X1224218D02*
G03I-400J0D01*
G37*
G36*
G01X1244938Y186998D02*
Y210417D01*
X1242930Y212425D01*
Y214067D01*
X1243322Y214459D01*
X1251744D01*
X1251952Y214251D01*
Y212947D01*
X1251900Y212895D01*
Y212503D01*
X1251902Y212502D01*
Y211820D01*
X1252340Y211382D01*
X1253021D01*
X1257247D01*
X1258575Y210054D01*
Y205828D01*
Y187369D01*
X1257420Y186214D01*
X1245722D01*
X1244938Y186998D01*
G37*
G36*
G01X1247377Y1001600D02*
G03I-577J0D01*
G37*
G36*
G01X1249777Y1014000D02*
G03I-577J0D01*
G37*
G36*
G01X1284825Y1066535D02*
G02I-17700J0D01*
G37*
G36*
G01X1242920Y1090158D02*
G03I-400J0D01*
G37*
G36*
G01Y1082677D02*
G03I-400J0D01*
G37*
G36*
G01Y1101378D02*
G03I-400J0D01*
G37*
G36*
G01Y1123819D02*
G03I-400J0D01*
G37*
G36*
G01Y1116339D02*
G03I-400J0D01*
G37*
G36*
G01Y1108859D02*
G03I-400J0D01*
G37*
G36*
G01X1243549Y1136909D02*
G03I-400J0D01*
G37*
G36*
G01X1242920Y1131300D02*
G03I-400J0D01*
G37*
G36*
G01Y1198621D02*
G03I-400J0D01*
G37*
G36*
G01Y1221062D02*
G03I-400J0D01*
G37*
G36*
G01Y1213582D02*
G03I-400J0D01*
G37*
G36*
G01Y1206102D02*
G03I-400J0D01*
G37*
G36*
G01Y1228543D02*
G03I-400J0D01*
G37*
G36*
G01X1284825Y1263386D02*
G02I-17700J0D01*
G37*
G36*
G01X1242920Y1239762D02*
G03I-400J0D01*
G37*
G36*
G01Y1247243D02*
G03I-400J0D01*
G37*
G36*
G01X1260852Y86514D02*
X1269567D01*
X1269920Y86161D01*
Y73377D01*
X1269474Y72931D01*
X1261076D01*
X1260741Y73266D01*
Y86403D01*
X1260852Y86514D01*
G37*
G36*
G01X1271157Y401826D02*
Y398942D01*
X1271086Y398871D01*
X1270250D01*
X1269961D01*
X1264909Y403923D01*
Y408358D01*
X1266454Y409903D01*
X1268930D01*
X1269519Y409314D01*
Y403464D01*
X1271157Y401826D01*
G37*
G36*
G01X1269331Y397951D02*
Y397268D01*
X1269116Y397053D01*
X1266817D01*
X1265976Y396212D01*
X1264419D01*
X1264395Y396188D01*
X1260132D01*
X1259850Y396470D01*
Y400288D01*
X1263044Y403482D01*
X1263800D01*
X1269331Y397951D01*
G37*
G36*
G01X1271670Y450537D02*
Y451151D01*
G02X1271729Y451293I200J0D01*
G01X1273350Y452914D01*
G03X1273409Y453056I-141J142D01*
G01Y454571D01*
G02X1273468Y454713I200J0D01*
G01X1273941Y455186D01*
G02X1274083Y455245I142J-141D01*
G01X1276245D01*
G02X1276430Y455122I0J-200D01*
G01X1276453Y455065D01*
X1276430Y454947D01*
X1276425Y454943D01*
Y453471D01*
G03X1276744Y452657I1202J1D01*
G02X1276797Y452521I-147J-136D01*
G01Y445675D01*
G02X1276738Y445533I-200J0D01*
G01X1276723Y445518D01*
X1276650Y445488D01*
X1272380D01*
X1272366Y445502D01*
X1270172D01*
X1269795D01*
X1269388Y445909D01*
Y448255D01*
X1269716Y448583D01*
X1271670Y450537D01*
G37*
G36*
G01X1283452Y496318D02*
Y486878D01*
X1281651Y485077D01*
X1280555Y483981D01*
X1259704D01*
X1258757Y484928D01*
Y495700D01*
X1260201Y497144D01*
X1282626D01*
X1283452Y496318D01*
G37*
G36*
G01X1271627Y1218396D02*
Y1218470D01*
X1273074Y1219917D01*
X1273519D01*
X1275782Y1217654D01*
X1277784D01*
X1279972Y1215466D01*
Y1214018D01*
X1274929Y1208975D01*
X1269587D01*
X1266267Y1212295D01*
Y1213036D01*
X1271627Y1218396D01*
G37*
G36*
G01X1289030Y89379D02*
X1289128D01*
G02X1289269Y89438I142J-141D01*
G01X1303294D01*
G02X1303436Y89379I0J-200D01*
G01X1303438Y89376D01*
Y74039D01*
G03X1303497Y73898I200J1D01*
G01X1303544Y73851D01*
G02Y73568I-141J-141D01*
G01X1303357Y73381D01*
G02X1303215Y73322I-142J141D01*
G01X1299400D01*
X1299397Y73319D01*
X1279052D01*
G02X1278910Y73378I0J200D01*
G01X1278842Y73446D01*
G02X1278783Y73588I141J142D01*
G01Y86280D01*
G02X1278842Y86422I200J0D01*
G01X1278910Y86490D01*
G02X1279052Y86549I142J-141D01*
G01X1284363D01*
G03X1284505Y86608I0J200D01*
G01X1285338Y87441D01*
G03X1285397Y87583I-141J142D01*
G01Y88917D01*
G02X1285456Y89059I200J0D01*
G01X1285776Y89379D01*
G02X1285918Y89438I142J-141D01*
G01X1288889D01*
G02X1289030Y89379I-1J-200D01*
G37*
G36*
G01X1276778Y176789D02*
X1291205D01*
X1291968Y176026D01*
Y174795D01*
X1292731Y174032D01*
X1295839D01*
X1296426Y173445D01*
Y161423D01*
X1295722Y160719D01*
X1277423D01*
Y160720D01*
X1275427D01*
X1274666Y161481D01*
Y176203D01*
X1275252Y176789D01*
X1276778D01*
G37*
G36*
G01X1303697Y219609D02*
X1305339D01*
X1305731Y219217D01*
Y210795D01*
X1305523Y210587D01*
X1304219D01*
X1304167Y210639D01*
X1303775D01*
X1303769Y210633D01*
X1303183D01*
X1302654Y210104D01*
Y209518D01*
Y204802D01*
X1292185Y194333D01*
Y189191D01*
X1295822Y185554D01*
X1300587D01*
X1301135Y185006D01*
Y183690D01*
X1302130Y182695D01*
X1304064D01*
X1304451Y182308D01*
X1306665D01*
X1306843Y182130D01*
Y181714D01*
X1306530Y181401D01*
X1303320D01*
X1302919Y181000D01*
X1302874D01*
X1301581Y179707D01*
X1276022D01*
X1274710Y181019D01*
Y216698D01*
X1275613Y217601D01*
X1301689D01*
X1303697Y219609D01*
G37*
G36*
G01X1302057Y234621D02*
Y221520D01*
X1300256Y219719D01*
X1299160Y218623D01*
X1276319D01*
X1274591Y220351D01*
Y252516D01*
X1275902Y253827D01*
X1298142D01*
X1302057Y249912D01*
Y234621D01*
G37*
G36*
G01X1276937Y277007D02*
X1284366D01*
X1296817D01*
X1298674Y275150D01*
X1301253D01*
X1301528Y274875D01*
Y272398D01*
X1300978Y271848D01*
X1298434D01*
X1298330Y271952D01*
X1294650Y268272D01*
Y265554D01*
X1291452Y262356D01*
X1276868D01*
X1276180Y263044D01*
Y276250D01*
X1276937Y277007D01*
G37*
G36*
G01X1279930Y299467D02*
X1290214D01*
X1294650Y295031D01*
Y278899D01*
X1294409Y278658D01*
X1277659D01*
X1276387Y279930D01*
Y295924D01*
X1279930Y299467D01*
G37*
G36*
G01X1276988Y397747D02*
Y391404D01*
X1276821Y391237D01*
X1270511D01*
X1270331Y391417D01*
Y397681D01*
X1270498Y397848D01*
X1276887D01*
X1276988Y397747D01*
G37*
G36*
G01X1272161Y402001D02*
X1272158Y402003D01*
Y402159D01*
G03X1272100Y402299I-200J-1D01*
G01X1270585Y403815D01*
G02X1270526Y403956I141J142D01*
G01Y436739D01*
X1271170Y437383D01*
X1280599D01*
X1281223Y438007D01*
Y442600D01*
X1282085Y443462D01*
X1296174D01*
X1299270Y446558D01*
X1313830D01*
X1313930Y446458D01*
X1333882D01*
X1333908Y446432D01*
Y431809D01*
X1333475Y431376D01*
X1321805D01*
X1321020Y430591D01*
Y426913D01*
X1320477Y426370D01*
X1302610D01*
X1302010Y425770D01*
Y415233D01*
X1302006Y415229D01*
Y400678D01*
X1304131Y398553D01*
Y394595D01*
X1303941Y394405D01*
X1295080D01*
X1295056Y394429D01*
Y397123D01*
X1294482Y397697D01*
X1286176D01*
X1286015Y397858D01*
Y410288D01*
X1284256Y412047D01*
X1278513D01*
X1276680Y410214D01*
Y405785D01*
X1275489Y404594D01*
X1274592D01*
G03X1274450Y404535I0J-200D01*
G01X1273573Y403658D01*
G03X1273514Y403516I141J-142D01*
G01Y402260D01*
G02X1273499Y402183I-200J-1D01*
G01X1273266Y401620D01*
G03X1273190Y401384I1386J-577D01*
G01X1273184Y401356D01*
X1273157Y401308D01*
X1273127Y401278D01*
Y399147D01*
G02X1273068Y399005I-200J0D01*
G01X1273008Y398945D01*
G02X1272866Y398886I-142J141D01*
G01X1272616D01*
G02X1272474Y398945I0J200D01*
G01X1272279Y399140D01*
G02X1272220Y399282I141J142D01*
G01Y401859D01*
G03X1272161Y402001I-200J0D01*
G37*
G36*
G01X1285376Y471921D02*
Y483798D01*
X1284596Y484578D01*
Y495368D01*
Y496794D01*
X1284905Y497103D01*
X1294942D01*
X1295855Y496190D01*
Y481973D01*
X1295811Y481929D01*
X1293307D01*
X1293087Y481709D01*
Y481488D01*
Y471761D01*
Y468882D01*
Y468185D01*
X1292846Y467944D01*
X1286565D01*
X1285376Y469133D01*
Y470108D01*
Y470402D01*
Y471921D01*
G37*
G36*
G01X1305495Y848020D02*
X1307028D01*
G02X1307061Y848017I-2J-200D01*
G02X1307168Y847963I-32J-197D01*
G01X1307683Y847448D01*
G02X1307742Y847306I-141J-142D01*
G01Y846248D01*
G02X1307683Y846106I-200J0D01*
G01X1307156Y845579D01*
X1306696Y845119D01*
X1303533Y841955D01*
G03X1303315Y841678I1031J-1036D01*
G03X1303197Y841434I1251J-755D01*
G01X1303186Y841403D01*
G03X1303104Y840922I1380J-483D01*
G01Y827500D01*
G02X1303045Y827358I-200J0D01*
G01X1301736Y826049D01*
G02X1301719Y826034I-141J142D01*
G01X1301693Y826013D01*
X1301685Y826008D01*
G03X1301234Y825554I816J-1261D01*
G01X1301222Y825535D01*
X1300797Y825110D01*
X1297876Y822188D01*
G03X1297448Y821155I1033J-1033D01*
G01Y819385D01*
X1297443Y819365D01*
G03X1297439Y819343I874J-170D01*
G01Y819342D01*
G03X1297424Y819179I875J-163D01*
G01Y818242D01*
X1297540Y818126D01*
X1297546D01*
X1297601Y818015D01*
G03X1297634Y817953I1306J655D01*
G02X1297660Y817855I-174J-99D01*
G01Y816329D01*
G02X1297634Y816231I-200J1D01*
G03X1297614Y816194I1275J-713D01*
G01X1297613Y816193D01*
G03X1297601Y816170I1290J-688D01*
G01X1297589Y816146D01*
X1297542Y816093D01*
X1297465Y816058D01*
X1297424D01*
Y815005D01*
G03X1298320Y814115I890J0D01*
G01Y814116D01*
X1298492D01*
X1298518Y814108D01*
G03X1298558Y814098I375J1413D01*
G01X1298559D01*
X1298586Y814091D01*
X1298608Y814079D01*
G02X1298653Y814045I-97J-175D01*
G01X1300620Y812078D01*
G02X1300678Y811937I-142J-141D01*
G01Y810972D01*
G03X1300688Y810801I1462J0D01*
G01X1300694Y810757D01*
X1300668Y810676D01*
X1300462Y810448D01*
G02X1300314Y810382I-148J134D01*
G01X1297714D01*
X1296320D01*
G03X1295824Y809953I0J-501D01*
G01X1295813Y809879D01*
X1295701Y809782D01*
X1295470D01*
X1295126D01*
G03X1293938Y809365I0J-1901D01*
G01X1293912Y809344D01*
X1293818Y809310D01*
G02X1293750Y809298I-68J188D01*
G01X1290281D01*
G03X1288936Y808741I0J-1902D01*
G01X1288385Y808190D01*
G03X1287833Y806708I1345J-1345D01*
G01X1287837Y806668D01*
G03X1289730Y804943I1893J176D01*
G01X1289764D01*
X1289807Y804945D01*
G03X1290987Y805418I-77J1900D01*
G01X1291014Y805442D01*
X1291149Y805494D01*
X1294642D01*
G03X1294803Y805501I-2J1901D01*
G01X1294804D01*
G03X1295450Y805675I-164J1895D01*
G01X1295480Y805689D01*
X1295546Y805696D01*
X1295818Y805634D01*
G02X1295929Y805565I-44J-195D01*
G01X1295930Y805564D01*
G03X1295955Y805536I386J320D01*
G02X1295957Y805534I-140J-142D01*
G03X1295964Y805527I358J351D01*
G01X1295965Y805526D01*
G03X1295989Y805503I359J350D01*
G01X1296018Y805477D01*
X1296051Y805412D01*
G02X1296057Y805398I-181J-86D01*
G01X1296058D01*
G02X1296062Y805255I-185J-77D01*
G01X1296057Y805242D01*
X1296019Y805165D01*
X1295989Y805139D01*
G03X1295818Y804762I330J-377D01*
G01Y801121D01*
G02X1295761Y800981I-200J0D01*
G01X1295539Y800753D01*
X1295466Y800722D01*
X1295427D01*
G03X1293589Y798821I64J-1901D01*
G01Y797600D01*
X1293590Y797599D01*
Y796321D01*
G03X1295491Y794420I1901J0D01*
G03X1296413Y794658I1J1901D01*
G03X1296744Y794890I-920J1664D01*
G01X1296771Y794913D01*
X1296870Y794951D01*
G02X1296943Y794965I73J-186D01*
G01X1298077D01*
G02X1298100Y794896I-176J-97D01*
G01X1298160Y794836D01*
X1299153D01*
G03X1299573Y794941I1J890D01*
G01X1299595Y794953D01*
X1299642Y794965D01*
X1299832D01*
G03X1299974Y795024I0J200D01*
G01X1300713Y795763D01*
G03X1300772Y795905I-141J142D01*
G01Y798886D01*
G02X1300831Y799028I200J0D01*
G01X1302924Y801121D01*
G03X1302983Y801263I-141J142D01*
G01Y805173D01*
G02X1303042Y805315I200J0D01*
G01X1303046Y805319D01*
G02X1303188Y805378I142J-141D01*
G01X1307812D01*
G03X1308314Y805880I0J502D01*
G01Y809880D01*
G03X1307812Y810382I-502J0D01*
G01X1304844D01*
G02X1304789Y810390I1J200D01*
G01X1303660Y811519D01*
G02X1303602Y811660I142J141D01*
G01Y812280D01*
X1303607Y812301D01*
G03X1303642Y812625I-1467J322D01*
G03X1302947Y813892I-1502J0D01*
G01X1302928Y813904D01*
X1302592Y814240D01*
X1300281Y816550D01*
G03X1300229Y816600I-1038J-1028D01*
G01X1300228Y816601D01*
G03X1300224Y816605I-1034J-1030D01*
G02X1300158Y816753I134J149D01*
G01Y817855D01*
G02X1300184Y817953I200J-1D01*
G03X1300204Y817990I-1275J713D01*
G01X1300205Y817991D01*
G03X1300217Y818014I-1290J688D01*
G01X1300229Y818038D01*
X1300276Y818091D01*
X1300353Y818126D01*
X1300394D01*
Y819179D01*
G03X1300379Y819342I-890J0D01*
G01Y819343D01*
G03X1300375Y819365I-878J-148D01*
G01X1300370Y819385D01*
Y820467D01*
G02X1300429Y820608I200J-1D01*
G01X1303274Y823453D01*
G02X1303308Y823480I141J-142D01*
G03X1303768Y823940I-807J1267D01*
G02X1303795Y823974I169J-107D01*
G01X1304011Y824190D01*
X1304212Y824392D01*
X1304213D01*
X1305599Y825779D01*
G03X1305817Y826056I-1031J1036D01*
G03X1305935Y826300I-1251J755D01*
G01X1305946Y826331D01*
G03X1306028Y826812I-1380J483D01*
G01Y840234D01*
G02X1306085Y840374I200J0D01*
G01X1306086Y840375D01*
X1307588Y841877D01*
G02X1307590Y841879I142J-140D01*
G02X1307730Y841936I140J-143D01*
G01X1309489D01*
X1309590Y841866D01*
X1309612Y841807D01*
G03X1309900Y841339I1358J513D01*
G02X1309952Y841204I-148J-135D01*
G01Y838746D01*
X1309923Y838717D01*
Y834048D01*
G02X1309840Y833885I-200J-1D01*
G03X1309235Y832706I846J-1179D01*
G03X1309673Y831667I1451J0D01*
G01X1309702Y831638D01*
X1309733Y831565D01*
Y831347D01*
X1309702Y831274D01*
X1309673Y831245D01*
G03Y829167I1013J-1039D01*
G01X1309702Y829138D01*
X1309733Y829065D01*
Y828847D01*
X1309702Y828774D01*
X1309673Y828745D01*
G03X1309235Y827706I1013J-1039D01*
G03X1309840Y826527I1451J0D01*
G02X1309923Y826364I-117J-162D01*
G01Y824398D01*
X1309912Y824353D01*
X1309901Y824331D01*
X1309852Y824235D01*
X1309824Y824201D01*
X1309806Y824187D01*
X1309805Y824186D01*
X1309795Y824178D01*
G03X1309213Y822991I919J-1187D01*
G03X1309583Y822004I1501J0D01*
G01X1309607Y821976D01*
X1309632Y821910D01*
Y821572D01*
X1309607Y821506D01*
X1309583Y821478D01*
G03Y819504I1131J-987D01*
G01X1309607Y819476D01*
X1309632Y819410D01*
Y819072D01*
X1309607Y819006D01*
X1309583Y818978D01*
G03X1309213Y817991I1131J-987D01*
G01Y817960D01*
G03X1309805Y816795I1502J30D01*
G01X1309824Y816781D01*
X1309852Y816747D01*
X1309901Y816650D01*
G02X1309923Y816560I-178J-91D01*
G01Y794081D01*
X1309893Y794007D01*
X1309864Y793979D01*
X1308692Y792807D01*
G02X1308550Y792748I-142J141D01*
G01X1285795D01*
X1285721Y792778D01*
X1285693Y792807D01*
X1284988Y793512D01*
G02X1284929Y793654I141J142D01*
G01Y814848D01*
G02X1284988Y814990I200J0D01*
G01X1286874Y816876D01*
G02X1287016Y816935I142J-141D01*
G01X1291542D01*
G03X1291684Y816994I0J200D01*
G01X1293145Y818455D01*
G03X1293204Y818597I-141J142D01*
G01Y822150D01*
X1293288Y822258D01*
X1293356Y822275D01*
G03X1293947Y822608I-301J1225D01*
G01X1294995Y823656D01*
X1296558Y825219D01*
G03X1296831Y825628I-893J891D01*
G01X1297305Y826770D01*
G02X1297424Y826883I185J-76D01*
G03X1298741Y828424I-654J1892D01*
G01X1298742Y828430D01*
X1298744Y828438D01*
G02X1298797Y828532I194J-48D01*
G01X1298837Y828572D01*
G03X1298896Y828714I-141J142D01*
G01Y831225D01*
G02X1298928Y831334I200J0D01*
G03Y832966I-1261J816D01*
G02X1298896Y833075I168J109D01*
G01Y841421D01*
G02X1298955Y841563I200J0D01*
G01X1305353Y847961D01*
G02X1305495Y848020I142J-141D01*
G37*
G36*
G01X1300740Y-44434D02*
G03I-557J0D01*
G37*
G36*
G01Y-29478D02*
G03I-557J0D01*
G37*
G36*
G01Y-34434D02*
G03I-557J0D01*
G37*
G36*
G01Y-39478D02*
G03I-557J0D01*
G37*
G36*
G01X1406555Y54588D02*
X1433452D01*
Y52591D01*
X1406555D01*
G03X1400618Y46654I0J-5937D01*
G01Y7874D01*
G02X1394744Y2000I-5874J0D01*
G01X1299862D01*
G02X1293988Y7874I0J5874D01*
G01Y46654D01*
G03X1292425Y50669I-5938J0D01*
G01Y50696D01*
X1292470Y50741D01*
X1294823D01*
X1294895Y50669D01*
G02X1295986Y46654I-6842J-4015D01*
G01Y7874D01*
G03X1299862Y3998I3876J0D01*
G01X1394744D01*
G03X1398620Y7874I0J3876D01*
G01Y46654D01*
G02X1406555Y54588I7935J-1D01*
G37*
G36*
G01X1288881Y95055D02*
X1303897D01*
X1303917Y95035D01*
X1307922D01*
X1308635Y94322D01*
Y74773D01*
X1307774Y73912D01*
X1305163D01*
X1304899D01*
X1304440Y74371D01*
Y90663D01*
X1304317Y90786D01*
X1303611D01*
X1300856D01*
X1289118D01*
X1289079Y90747D01*
X1288802Y91024D01*
Y94976D01*
X1288881Y95055D01*
G37*
G36*
G01X1335352Y446952D02*
X1340342D01*
X1340393Y446901D01*
Y430343D01*
X1342266Y428470D01*
X1351307D01*
X1351978Y427799D01*
Y378592D01*
X1349770Y376384D01*
X1335610D01*
X1335505Y376279D01*
X1317606D01*
X1313839Y380046D01*
X1310643D01*
X1307628Y383061D01*
X1303069D01*
X1302888Y383242D01*
Y385317D01*
X1302345Y385860D01*
X1292603D01*
X1292401Y386062D01*
Y393183D01*
X1292693Y393475D01*
X1307782D01*
X1308050Y393743D01*
G02X1308192Y393802I142J-141D01*
G01X1319125D01*
X1319127Y393800D01*
X1334689D01*
X1335487Y394598D01*
Y406210D01*
X1331920Y409777D01*
Y426628D01*
X1335141Y429849D01*
X1335267Y429974D01*
Y446867D01*
X1335352Y446952D01*
G37*
G36*
G01X1306183Y1254968D02*
X1359077D01*
G02X1359219Y1254909I0J-200D01*
G01X1360227Y1253901D01*
G02X1360286Y1253759I-141J-142D01*
G01Y1215829D01*
G02X1360227Y1215687I-200J0D01*
G01X1359773Y1215233D01*
G02X1359631Y1215174I-142J141D01*
G01X1312177D01*
G03X1312035Y1215115I0J-200D01*
G01X1310344Y1213424D01*
G03X1310285Y1213282I141J-142D01*
G01Y1195532D01*
G03X1310344Y1195390I200J0D01*
G01X1311181Y1194553D01*
G03X1311323Y1194494I142J141D01*
G01X1370119D01*
G02X1370261Y1194435I0J-200D01*
G01X1378660Y1186036D01*
G02X1378719Y1185894I-141J-142D01*
G01Y1157818D01*
G02X1378660Y1157676I-200J0D01*
G01X1378299Y1157315D01*
G02X1378157Y1157256I-142J141D01*
G01X1292870D01*
G02X1292728Y1157315I0J200D01*
G01X1292024Y1158019D01*
G02X1291965Y1158161I141J142D01*
G01Y1233682D01*
G02X1292024Y1233824I200J0D01*
G01X1305541Y1247341D01*
G03X1305600Y1247483I-141J142D01*
G01Y1254385D01*
G02X1305659Y1254527I200J0D01*
G01X1306041Y1254909D01*
G02X1306183Y1254968I142J-141D01*
G37*
G36*
G01X1308792Y276354D02*
X1326365D01*
X1327191Y275528D01*
Y258570D01*
Y233228D01*
X1319057Y225094D01*
Y224599D01*
Y220921D01*
X1316757Y218621D01*
X1314757D01*
X1314467Y218331D01*
Y205660D01*
X1313880Y205073D01*
X1307048D01*
X1306540Y205581D01*
Y220421D01*
X1303257Y223704D01*
Y234821D01*
X1303423Y234987D01*
Y250246D01*
X1306587Y253410D01*
X1306623D01*
X1308843Y255630D01*
Y268925D01*
X1305834Y271934D01*
X1303530D01*
X1303014Y272450D01*
Y274738D01*
X1303237Y274961D01*
X1307399D01*
X1308792Y276354D01*
G37*
G36*
G01X1304046Y276095D02*
X1304785D01*
X1304811Y276122D01*
X1307012D01*
X1308464Y277574D01*
X1310099D01*
X1310133Y277540D01*
X1317304D01*
X1317336Y277572D01*
X1325067D01*
X1326882Y279387D01*
Y287118D01*
Y296369D01*
X1326056Y297195D01*
X1309824D01*
X1307709Y295080D01*
Y282733D01*
X1305526Y280550D01*
X1303736Y278760D01*
Y276405D01*
X1304046Y276095D01*
G37*
G36*
G01X1307735Y359067D02*
X1311411D01*
X1313809Y356669D01*
Y349792D01*
X1314693Y348908D01*
Y346645D01*
X1314534Y346486D01*
X1306776D01*
X1306440Y346822D01*
Y357772D01*
X1307735Y359067D01*
G37*
G36*
G01X1319026Y395002D02*
X1306326D01*
X1305801Y395527D01*
Y398368D01*
X1305303Y398866D01*
X1303028Y401141D01*
Y420740D01*
Y422259D01*
Y424461D01*
X1303894Y425327D01*
X1321388D01*
X1322204Y426143D01*
Y429356D01*
X1322809Y429961D01*
X1323549D01*
X1329798D01*
X1330683Y429076D01*
Y409012D01*
X1334163Y405532D01*
Y404385D01*
Y401684D01*
Y395828D01*
X1333337Y395002D01*
X1333214D01*
X1319026D01*
G37*
G36*
G01X1333282Y458336D02*
Y460127D01*
X1333160Y460249D01*
X1318995D01*
X1318140Y459394D01*
Y453553D01*
X1318385Y453308D01*
X1321823D01*
X1322068Y453553D01*
Y457135D01*
X1323019Y458086D01*
X1333206D01*
X1333282Y458162D01*
Y458336D01*
G37*
G36*
G01X1333951Y447491D02*
Y449363D01*
X1332459Y450855D01*
X1314140D01*
X1313919Y450634D01*
Y447883D01*
X1314344Y447458D01*
X1333918D01*
X1333951Y447491D01*
G37*
G36*
G01X1441580Y1104797D02*
X1442972D01*
X1443604Y1104165D01*
X1443799Y1103970D01*
Y1098766D01*
X1443541Y1098508D01*
G03X1436799Y1086654I7050J-11854D01*
G03X1439265Y1078784I13791J0D01*
G01Y1053556D01*
X1436523Y1050814D01*
X1310442D01*
X1308260Y1052996D01*
Y1098072D01*
X1308788Y1098600D01*
X1313867D01*
X1314236Y1098231D01*
X1314397Y1098070D01*
Y1096229D01*
Y1058207D01*
Y1056922D01*
X1315818Y1055501D01*
X1333615D01*
X1334127D01*
X1335036Y1056410D01*
Y1056922D01*
Y1058821D01*
Y1071074D01*
G02X1335095Y1071216I200J0D01*
G01X1335309Y1071430D01*
G02X1335451Y1071489I142J-141D01*
G01X1356143D01*
G03X1356285Y1071548I0J200D01*
G01X1357643Y1072906D01*
G03X1357702Y1073048I-141J142D01*
G01Y1097741D01*
G02X1357665Y1097793I142J140D01*
G01X1357654Y1097820D01*
G02X1357644Y1097881I190J62D01*
G01Y1099671D01*
G02X1357702Y1099812I200J0D01*
G01X1357738Y1099848D01*
G02X1357788Y1099884I140J-142D01*
G02X1357879Y1099906I91J-178D01*
G01X1379035D01*
G02X1379177Y1099847I0J-200D01*
G01X1379951Y1099073D01*
G02X1380010Y1098931I-141J-142D01*
G01Y1072748D01*
G03X1380069Y1072606I200J0D01*
G01X1381297Y1071377D01*
X1402307D01*
X1402730Y1070954D01*
Y1058768D01*
Y1056439D01*
X1403192Y1055977D01*
X1403384Y1055785D01*
X1421823D01*
X1422015Y1055977D01*
X1423122Y1057084D01*
Y1058999D01*
Y1088285D01*
X1423133Y1088312D01*
Y1092847D01*
X1423127Y1092853D01*
Y1099722D01*
X1423302Y1099897D01*
X1438036D01*
X1438754D01*
X1441137Y1102280D01*
Y1102998D01*
Y1104354D01*
X1441580Y1104797D01*
G37*
G36*
G01X1318284Y1070717D02*
X1331856D01*
X1332999Y1069574D01*
Y1057661D01*
X1332384Y1057046D01*
X1317950D01*
X1316941Y1058055D01*
Y1069374D01*
X1318284Y1070717D01*
G37*
G36*
G01X1348363Y1120863D02*
X1351052D01*
X1351256Y1120659D01*
X1361942D01*
X1361958Y1120643D01*
Y1112626D01*
X1361899Y1112567D01*
X1356023D01*
X1355849Y1112393D01*
Y1107201D01*
X1355330Y1106682D01*
Y1101290D01*
X1356452Y1100168D01*
Y1073191D01*
X1355898Y1072637D01*
X1316701D01*
X1315869Y1073469D01*
Y1104852D01*
G03X1315871Y1104896I-1498J90D01*
G03X1315869Y1104940I-1500J-46D01*
G01Y1120497D01*
X1316235Y1120863D01*
X1318924D01*
X1319128Y1120659D01*
X1329814D01*
X1329830Y1120643D01*
Y1112626D01*
X1329771Y1112567D01*
X1323895D01*
X1323721Y1112393D01*
Y1107309D01*
X1323209Y1106797D01*
Y1101558D01*
X1324352Y1100415D01*
Y1097323D01*
X1325190Y1096485D01*
X1343564D01*
X1347997Y1100918D01*
Y1120497D01*
X1348363Y1120863D01*
G37*
G36*
G01X1316582Y1156179D02*
X1462900D01*
G02X1463042Y1156120I0J-200D01*
G01X1464450Y1154712D01*
G02X1464509Y1154570I-141J-142D01*
G01Y1126737D01*
G02X1464450Y1126595I-200J0D01*
G01X1463606Y1125751D01*
G02X1463464Y1125692I-142J141D01*
G01X1441362D01*
G03X1441220Y1125633I0J-200D01*
G01X1440495Y1124908D01*
G02X1440353Y1124849I-142J141D01*
G01X1432701D01*
X1432628Y1124819D01*
X1432620Y1124811D01*
Y1120677D01*
G03X1432679Y1120535I200J0D01*
G01X1432682Y1120532D01*
G03X1432824Y1120473I142J141D01*
G01X1437048D01*
G02X1437190Y1120414I0J-200D01*
G01X1437286Y1120318D01*
G03X1437428Y1120259I142J141D01*
G01X1439611D01*
G02X1439753Y1120200I0J-200D01*
G01X1439825Y1120128D01*
G02X1439884Y1119986I-141J-142D01*
G01Y1119595D01*
G02X1439826Y1119453I-200J-1D01*
G01X1439720Y1119347D01*
G02X1439578Y1119288I-142J141D01*
G01X1437185D01*
G03X1437043Y1119229I0J-200D01*
G01X1436243Y1118429D01*
G03X1436184Y1118287I141J-142D01*
G01Y1115480D01*
G03X1436243Y1115338I200J0D01*
G01X1436607Y1114974D01*
G03X1436749Y1114915I142J141D01*
G01X1439737D01*
X1439742Y1114910D01*
Y1114100D01*
X1439712Y1114027D01*
X1439695Y1114010D01*
X1436789D01*
G03X1436647Y1113951I0J-200D01*
G01X1436243Y1113547D01*
G03X1436184Y1113405I141J-142D01*
G01Y1113045D01*
G02X1436125Y1112903I-200J0D01*
G01X1436065Y1112843D01*
G02X1435923Y1112784I-142J141D01*
G01X1429129D01*
X1429106Y1112807D01*
Y1121516D01*
G03X1429047Y1121658I-200J0D01*
G01X1428710Y1121995D01*
G03X1428568Y1122054I-142J-141D01*
G01X1416668D01*
G03X1416526Y1121995I0J-200D01*
G01X1416483Y1121952D01*
G02X1416341Y1121893I-142J141D01*
G01X1414289D01*
G02X1414147Y1121952I0J200D01*
G01X1413580Y1122519D01*
G02X1413521Y1122661I141J142D01*
G01Y1124884D01*
X1413404Y1125001D01*
X1413377D01*
X1412745Y1125633D01*
G03X1412603Y1125692I-142J-141D01*
G01X1409234D01*
G03X1409092Y1125633I0J-200D01*
G01X1408367Y1124908D01*
G02X1408225Y1124849I-142J141D01*
G01X1400573D01*
X1400500Y1124819D01*
X1400492Y1124811D01*
Y1120677D01*
G03X1400551Y1120535I200J0D01*
G01X1400554Y1120532D01*
G03X1400696Y1120473I142J141D01*
G01X1404920D01*
G02X1405062Y1120414I0J-200D01*
G01X1405158Y1120318D01*
G03X1405300Y1120259I142J141D01*
G01X1407483D01*
G02X1407625Y1120200I0J-200D01*
G01X1407697Y1120128D01*
G02X1407756Y1119986I-141J-142D01*
G01Y1119595D01*
G02X1407698Y1119453I-200J-1D01*
G01X1407592Y1119347D01*
G02X1407450Y1119288I-142J141D01*
G01X1405057D01*
G03X1404915Y1119229I0J-200D01*
G01X1404115Y1118429D01*
G03X1404056Y1118287I141J-142D01*
G01Y1115480D01*
G03X1404115Y1115338I200J0D01*
G01X1404479Y1114974D01*
G03X1404621Y1114915I142J141D01*
G01X1407609D01*
X1407614Y1114910D01*
Y1114100D01*
X1407584Y1114027D01*
X1407567Y1114010D01*
X1404661D01*
G03X1404519Y1113951I0J-200D01*
G01X1404115Y1113547D01*
G03X1404056Y1113405I141J-142D01*
G01Y1113045D01*
G02X1403997Y1112903I-200J0D01*
G01X1403937Y1112843D01*
G02X1403795Y1112784I-142J141D01*
G01X1397001D01*
X1396978Y1112807D01*
Y1121516D01*
G03X1396919Y1121658I-200J0D01*
G01X1396582Y1121995D01*
G03X1396440Y1122054I-142J-141D01*
G01X1384540D01*
G03X1384398Y1121995I0J-200D01*
G01X1384355Y1121952D01*
G02X1384213Y1121893I-142J141D01*
G01X1382078D01*
X1378279Y1125692D01*
X1375775D01*
G03X1375633Y1125633I0J-200D01*
G01X1374908Y1124908D01*
G02X1374766Y1124849I-142J141D01*
G01X1367114D01*
X1367041Y1124819D01*
X1367033Y1124811D01*
Y1120677D01*
G03X1367092Y1120535I200J0D01*
G01X1367095Y1120532D01*
G03X1367237Y1120473I142J141D01*
G01X1371461D01*
G02X1371603Y1120414I0J-200D01*
G01X1371699Y1120318D01*
G03X1371841Y1120259I142J141D01*
G01X1374024D01*
G02X1374166Y1120200I0J-200D01*
G01X1374238Y1120128D01*
G02X1374297Y1119986I-141J-142D01*
G01Y1119595D01*
G02X1374239Y1119453I-200J-1D01*
G01X1374133Y1119347D01*
G02X1373991Y1119288I-142J141D01*
G01X1371598D01*
G03X1371456Y1119229I0J-200D01*
G01X1370656Y1118429D01*
G03X1370597Y1118287I141J-142D01*
G01Y1115480D01*
G03X1370656Y1115338I200J0D01*
G01X1371020Y1114974D01*
G03X1371162Y1114915I142J141D01*
G01X1374150D01*
X1374155Y1114910D01*
Y1114100D01*
X1374125Y1114027D01*
X1374108Y1114010D01*
X1371202D01*
G03X1371060Y1113951I0J-200D01*
G01X1370656Y1113547D01*
G03X1370597Y1113405I141J-142D01*
G01Y1113045D01*
G02X1370538Y1112903I-200J0D01*
G01X1370478Y1112843D01*
G02X1370336Y1112784I-142J141D01*
G01X1363542D01*
X1363519Y1112807D01*
Y1121516D01*
G03X1363460Y1121658I-200J0D01*
G01X1363123Y1121995D01*
G03X1362981Y1122054I-142J-141D01*
G01X1351081D01*
G03X1350939Y1121995I0J-200D01*
G01X1350896Y1121952D01*
G02X1350754Y1121893I-142J141D01*
G01X1348702D01*
G02X1348560Y1121952I0J200D01*
G01X1347993Y1122519D01*
G02X1347934Y1122661I141J142D01*
G01Y1124884D01*
X1347817Y1125001D01*
X1347790D01*
X1347158Y1125633D01*
G03X1347016Y1125692I-142J-141D01*
G01X1343647D01*
G03X1343505Y1125633I0J-200D01*
G01X1342780Y1124908D01*
G02X1342638Y1124849I-142J141D01*
G01X1334986D01*
X1334913Y1124819D01*
X1334905Y1124811D01*
Y1120677D01*
G03X1334964Y1120535I200J0D01*
G01X1334967Y1120532D01*
G03X1335109Y1120473I142J141D01*
G01X1339333D01*
G02X1339475Y1120414I0J-200D01*
G01X1339571Y1120318D01*
G03X1339713Y1120259I142J141D01*
G01X1341896D01*
G02X1342038Y1120200I0J-200D01*
G01X1342110Y1120128D01*
G02X1342169Y1119986I-141J-142D01*
G01Y1119595D01*
G02X1342111Y1119453I-200J-1D01*
G01X1342005Y1119347D01*
G02X1341863Y1119288I-142J141D01*
G01X1339470D01*
G03X1339328Y1119229I0J-200D01*
G01X1338528Y1118429D01*
G03X1338469Y1118287I141J-142D01*
G01Y1115480D01*
G03X1338528Y1115338I200J0D01*
G01X1338892Y1114974D01*
G03X1339034Y1114915I142J141D01*
G01X1342022D01*
X1342027Y1114910D01*
Y1114100D01*
X1341997Y1114027D01*
X1341980Y1114010D01*
X1339074D01*
G03X1338932Y1113951I0J-200D01*
G01X1338528Y1113547D01*
G03X1338469Y1113405I141J-142D01*
G01Y1113045D01*
G02X1338410Y1112903I-200J0D01*
G01X1338350Y1112843D01*
G02X1338208Y1112784I-142J141D01*
G01X1331414D01*
X1331391Y1112807D01*
Y1121516D01*
G03X1331332Y1121658I-200J0D01*
G01X1330995Y1121995D01*
G03X1330853Y1122054I-142J-141D01*
G01X1318953D01*
G03X1318811Y1121995I0J-200D01*
G01X1318768Y1121952D01*
G02X1318626Y1121893I-142J141D01*
G01X1316574D01*
G02X1316432Y1121952I0J200D01*
G01X1315865Y1122519D01*
G02X1315806Y1122661I141J142D01*
G01Y1133251D01*
G02X1315840Y1133364I200J1D01*
G03Y1148684I-11313J7660D01*
G02X1315806Y1148797I166J112D01*
G01Y1155403D01*
G02X1315865Y1155545I200J0D01*
G01X1316440Y1156120D01*
G02X1316582Y1156179I142J-141D01*
G37*
G36*
G01X1312392Y1213880D02*
X1443411D01*
X1443728Y1213563D01*
Y1196392D01*
X1443443Y1196107D01*
X1385221D01*
X1384604Y1196724D01*
Y1200705D01*
X1383643Y1201666D01*
X1371276D01*
X1370526Y1200916D01*
Y1196107D01*
X1312019D01*
X1311402Y1196724D01*
Y1212890D01*
X1312392Y1213880D01*
G37*
G36*
G01X1307836Y1274161D02*
X1375956D01*
G02X1376098Y1274102I0J-200D01*
G01X1376788Y1273412D01*
G02X1376847Y1273270I-141J-142D01*
G01Y1255638D01*
X1376787Y1255542D01*
X1376734Y1255516D01*
G03X1375887Y1254164I656J-1352D01*
G03X1376734Y1252812I1503J0D01*
G01X1376787Y1252786D01*
X1376847Y1252690D01*
Y1252234D01*
X1376787Y1252138D01*
X1376734Y1252112D01*
G03X1375887Y1250760I656J-1352D01*
G03X1376734Y1249408I1503J0D01*
G01X1376787Y1249382D01*
X1376847Y1249286D01*
Y1245529D01*
X1376787Y1245433D01*
X1376734Y1245407D01*
G03X1375887Y1244055I656J-1352D01*
G03X1376734Y1242703I1503J0D01*
G01X1376787Y1242677D01*
X1376847Y1242581D01*
Y1215608D01*
G02X1376788Y1215466I-200J0D01*
G01X1376710Y1215388D01*
G02X1376568Y1215329I-142J141D01*
G01X1362710D01*
G02X1362568Y1215388I0J200D01*
G01X1362457Y1215499D01*
G02X1362398Y1215641I141J142D01*
G01Y1254815D01*
G03X1362339Y1254957I-200J0D01*
G01X1361013Y1256283D01*
G03X1360871Y1256342I-142J-141D01*
G01X1307448D01*
G02X1307306Y1256401I0J200D01*
G01X1306798Y1256909D01*
G02X1306739Y1257051I141J142D01*
G01Y1273064D01*
G02X1306798Y1273206I200J0D01*
G01X1307694Y1274102D01*
G02X1307836Y1274161I142J-141D01*
G37*
G36*
G01X1339366Y349454D02*
Y333685D01*
G02X1339307Y333543I-200J0D01*
G01X1339153Y333389D01*
G02X1339011Y333330I-142J141D01*
G01X1323320D01*
G02X1323178Y333389I0J200D01*
G01X1322897Y333670D01*
G02X1322838Y333812I141J142D01*
G01Y349406D01*
G02X1322897Y349548I200J0D01*
G01X1323105Y349756D01*
G02X1323247Y349815I142J-141D01*
G01X1339005D01*
G02X1339147Y349756I0J-200D01*
G01X1339307Y349596D01*
G02X1339366Y349454I-141J-142D01*
G37*
G36*
G01X1333249Y453904D02*
Y456122D01*
Y456569D01*
X1333146Y456672D01*
X1332699D01*
X1324274D01*
X1324070Y456468D01*
Y453598D01*
X1324314Y453354D01*
X1332699D01*
X1333249Y453904D01*
G37*
G36*
G01X1336437Y447997D02*
Y464238D01*
X1336294Y464381D01*
X1334483D01*
X1334320Y464218D01*
Y453126D01*
Y452381D01*
X1335297Y451404D01*
Y448017D01*
X1335330Y447984D01*
X1336424D01*
X1336437Y447997D01*
G37*
G36*
G01X1325354Y1099832D02*
X1325360Y1099838D01*
G02X1325502Y1099897I142J-141D01*
G01X1342858D01*
G02X1343000Y1099838I0J-200D01*
G01X1343061Y1099777D01*
G02X1343120Y1099635I-141J-142D01*
G01Y1097686D01*
G02X1342920Y1097486I-200J0D01*
G01X1325843D01*
G02X1325702Y1097545I1J200D01*
G01X1325412Y1097835D01*
G02X1325354Y1097976I142J141D01*
G01Y1099832D01*
G37*
G36*
G01X1340740Y-83484D02*
G03I-557J0D01*
G37*
G36*
G01Y-78528D02*
G03I-557J0D01*
G37*
G36*
G01Y-68528D02*
G03I-557J0D01*
G37*
G36*
G01Y-73484D02*
G03I-557J0D01*
G37*
G36*
G01X1356675Y427220D02*
Y454981D01*
X1357002Y455308D01*
X1360909D01*
X1361479Y454738D01*
Y427163D01*
X1361251Y426935D01*
X1360705D01*
X1356960D01*
X1356675Y427220D01*
G37*
G36*
G01X1368937Y1003266D02*
X1369256D01*
G02X1369316Y1003257I1J-200D01*
G01X1369398Y1003231D01*
X1369422Y1003216D01*
G03X1370383Y1002928I962J1463D01*
G01X1370384D01*
G03X1370980Y1003032I1J1752D01*
G01X1370995Y1003038D01*
X1371030Y1003044D01*
G02X1371194Y1003001I36J-197D01*
G01X1371227Y1002973D01*
X1371265Y1002893D01*
Y1001349D01*
G02X1371206Y1001207I-200J0D01*
G01X1370582Y1000583D01*
X1370554Y1000554D01*
X1370480Y1000524D01*
X1370392Y1000436D01*
Y1000394D01*
X1370333Y1000335D01*
X1368824Y998825D01*
G03X1368765Y998683I141J-142D01*
G01Y993849D01*
G02X1368706Y993707I-200J0D01*
G01X1368324Y993325D01*
X1368296Y993296D01*
X1368222Y993266D01*
X1362848D01*
G02X1362706Y993325I0J200D01*
G01X1362324Y993707D01*
X1362295Y993735D01*
X1362265Y993809D01*
Y1001683D01*
G02X1362324Y1001825I200J0D01*
G01X1363706Y1003207D01*
G02X1363848Y1003266I142J-141D01*
G01X1364692D01*
G03X1364765Y1003264I78J1500D01*
G03X1364838Y1003266I-5J1502D01*
G01X1365951D01*
X1366049Y1003202D01*
X1366074Y1003148D01*
G03X1368814I1370J615D01*
G01X1368839Y1003202D01*
X1368937Y1003266D01*
G37*
G36*
G01X1379643Y115094D02*
X1380699D01*
X1380726Y115067D01*
Y111227D01*
G02X1380667Y111085I-200J0D01*
G01X1379037Y109456D01*
G03X1378978Y109314I141J-142D01*
G01Y106183D01*
G03X1379037Y106041I200J0D01*
G01X1379160Y105918D01*
G03X1379302Y105859I142J141D01*
G01X1390008D01*
G03X1390150Y105918I0J200D01*
G01X1390226Y105994D01*
G03X1390285Y106136I-141J142D01*
G01Y109681D01*
G03X1390226Y109823I-200J0D01*
G01X1389992Y110057D01*
G02X1389933Y110199I141J142D01*
G01Y114552D01*
X1389963Y114625D01*
X1389974Y114636D01*
X1395558D01*
X1396900D01*
X1396964Y114572D01*
X1397080Y114456D01*
G02X1397139Y114314I-141J-142D01*
G01Y105226D01*
G02X1397080Y105084I-200J0D01*
G01X1396409Y104413D01*
X1396326Y104383D01*
X1396281Y104388D01*
G03X1396099Y104396I-174J-1893D01*
G01X1393517D01*
X1392231D01*
X1391485Y103650D01*
Y101528D01*
X1391153Y101196D01*
X1379622D01*
X1379598Y101202D01*
X1372418D01*
X1371723Y101897D01*
Y102887D01*
Y114049D01*
G02X1371782Y114191I200J0D01*
G01X1371904Y114313D01*
G02X1372046Y114372I142J-141D01*
G01X1378755D01*
G03X1378897Y114431I0J200D01*
G01X1379501Y115035D01*
G02X1379643Y115094I142J-141D01*
G37*
G36*
G01X1383008Y119235D02*
X1386454D01*
X1389290Y122071D01*
X1395337D01*
X1395707Y121701D01*
Y116118D01*
X1395226Y115637D01*
X1385552D01*
X1383196D01*
X1382848Y115985D01*
Y119075D01*
X1383008Y119235D01*
G37*
G36*
G01X1371905Y120851D02*
X1377322D01*
G02X1377464Y120792I0J-200D01*
G01X1379085Y119171D01*
G03X1379227Y119112I142J141D01*
G01X1380742D01*
G02X1380884Y119053I0J-200D01*
G01X1381357Y118580D01*
G02X1381416Y118438I-141J-142D01*
G01Y116276D01*
G02X1381293Y116091I-200J0D01*
G01X1381236Y116068D01*
X1381118Y116091D01*
X1381114Y116096D01*
X1379642D01*
G03X1378828Y115777I1J-1202D01*
G02X1378692Y115724I-136J147D01*
G01X1371846D01*
G02X1371704Y115783I0J200D01*
G01X1371689Y115798D01*
X1371659Y115871D01*
Y120605D01*
G02X1371718Y120747I200J0D01*
G01X1371763Y120792D01*
G02X1371905Y120851I142J-141D01*
G37*
G36*
G01X1381580Y210785D02*
X1391020D01*
X1392821Y208984D01*
X1393917Y207888D01*
Y187037D01*
X1392970Y186090D01*
X1382198D01*
X1380754Y187534D01*
Y209959D01*
X1381580Y210785D01*
G37*
G36*
G01X1394209Y223195D02*
X1404234D01*
X1404264Y223225D01*
X1406787D01*
X1409424Y225862D01*
X1418366D01*
X1418708Y225520D01*
Y213126D01*
X1417996Y212414D01*
X1410579D01*
X1407725Y215268D01*
X1404285D01*
X1393308D01*
X1391744D01*
X1391298Y214822D01*
Y213258D01*
X1390025Y211985D01*
X1389613D01*
X1388836D01*
X1381209D01*
X1380549Y212645D01*
Y226569D01*
X1381225Y227245D01*
X1392159D01*
X1393919Y225485D01*
Y223485D01*
X1394209Y223195D01*
G37*
G36*
G01X1378803Y362362D02*
Y319674D01*
G02X1378744Y319532I-200J0D01*
G01X1378650Y319438D01*
G02X1378508Y319379I-142J141D01*
G01X1374562D01*
G02X1374420Y319438I0J200D01*
G01X1373864Y319994D01*
G02X1373805Y320136I141J142D01*
G01Y362255D01*
G02X1373864Y362397I200J0D01*
G01X1374172Y362705D01*
G02X1374314Y362764I142J-141D01*
G01X1378401D01*
G02X1378543Y362705I0J-200D01*
G01X1378744Y362504D01*
G02X1378803Y362362I-141J-142D01*
G37*
G36*
G01X1372534Y1000424D02*
Y1002180D01*
X1372526Y1002188D01*
Y1003129D01*
X1372564Y1003167D01*
X1373110D01*
X1375385D01*
X1376709Y1004491D01*
Y1006792D01*
Y1007854D01*
X1377277Y1008422D01*
X1379297Y1010441D01*
X1380051D01*
X1381229D01*
X1381290Y1010380D01*
Y1010000D01*
X1381206Y1009916D01*
X1380060D01*
X1379619D01*
X1378253Y1008550D01*
X1378209Y1008506D01*
Y1006706D01*
Y1003869D01*
X1375770Y1001430D01*
X1374741D01*
X1374534Y1001223D01*
Y1000687D01*
X1375697Y999524D01*
X1376388D01*
X1378252Y1001387D01*
G02X1378959Y1001680I707J-706D01*
G02X1379959Y1000680I0J-1000D01*
G02X1379666Y999973I-999J0D01*
G01X1377491Y997798D01*
Y995100D01*
X1376346Y993955D01*
X1371839D01*
X1371394Y994400D01*
Y999522D01*
X1371632D01*
X1372534Y1000424D01*
G37*
G36*
G01X1382831Y1024441D02*
X1383313D01*
X1396420D01*
X1396759Y1024102D01*
Y1022980D01*
Y1010435D01*
X1396559Y1010235D01*
X1382659D01*
X1382559Y1010335D01*
X1382527Y1010367D01*
Y1021367D01*
Y1024137D01*
X1382831Y1024441D01*
G37*
G36*
G01X1413950Y1120863D02*
X1416639D01*
X1416843Y1120659D01*
X1427529D01*
X1427545Y1120643D01*
Y1112626D01*
X1427486Y1112567D01*
X1421610D01*
X1421436Y1112393D01*
Y1107201D01*
X1420917Y1106682D01*
Y1101290D01*
X1422039Y1100168D01*
Y1073191D01*
X1421485Y1072637D01*
X1382288D01*
X1381456Y1073469D01*
Y1104852D01*
G03X1381458Y1104896I-1498J90D01*
G03X1381456Y1104940I-1500J-46D01*
G01Y1120497D01*
X1381822Y1120863D01*
X1384511D01*
X1384715Y1120659D01*
X1395401D01*
X1395417Y1120643D01*
Y1112626D01*
X1395358Y1112567D01*
X1389482D01*
X1389308Y1112393D01*
Y1107309D01*
X1388796Y1106797D01*
Y1101558D01*
X1389939Y1100415D01*
Y1097323D01*
X1390777Y1096485D01*
X1409151D01*
X1413584Y1100918D01*
Y1120497D01*
X1413950Y1120863D01*
G37*
G36*
G01X1400996Y1254968D02*
X1449264D01*
G03X1464681Y1231335I38727J8418D01*
G01Y1159110D01*
G02X1464622Y1158968I-200J0D01*
G01X1462969Y1157315D01*
G02X1462827Y1157256I-142J141D01*
G01X1381745D01*
X1381433Y1157568D01*
Y1190849D01*
X1384571Y1193987D01*
X1444409D01*
X1445116Y1194694D01*
Y1214153D01*
X1444095Y1215174D01*
X1401246D01*
X1400258Y1216162D01*
Y1254230D01*
X1400996Y1254968D01*
G37*
G36*
G01X1444580Y1256342D02*
X1399925D01*
X1399127Y1255544D01*
Y1215751D01*
X1398705Y1215329D01*
X1394907D01*
X1382178D01*
X1379494D01*
X1378977Y1215846D01*
Y1273497D01*
X1379714Y1274234D01*
X1382115D01*
X1447938D01*
X1448958Y1273214D01*
Y1271068D01*
Y1268253D01*
Y1256968D01*
X1448332Y1256342D01*
X1444580D01*
G37*
G36*
G01X1394939Y186998D02*
Y210417D01*
X1392931Y212425D01*
Y214067D01*
X1393323Y214459D01*
X1401745D01*
X1401953Y214251D01*
Y212947D01*
X1401901Y212895D01*
Y212503D01*
Y211567D01*
X1402086Y211382D01*
X1403022D01*
X1407248D01*
X1408576Y210054D01*
Y205828D01*
Y187369D01*
X1407421Y186214D01*
X1395723D01*
X1394939Y186998D01*
G37*
G36*
G01X1410983Y592103D02*
X1397776D01*
X1397491Y591818D01*
Y556112D01*
Y555516D01*
X1397878Y555129D01*
X1398229Y554778D01*
X1406336D01*
X1406915Y554199D01*
X1411534D01*
X1412532Y555197D01*
Y590554D01*
X1410983Y592103D01*
G37*
G36*
G01X1412434Y617902D02*
X1396315D01*
X1396172Y617759D01*
Y615948D01*
X1396335Y615785D01*
X1407427D01*
X1408172D01*
X1409149Y616762D01*
X1412536D01*
Y616949D01*
X1412542Y616955D01*
Y617794D01*
X1412434Y617902D01*
G37*
G36*
G01X1390940Y1099832D02*
X1390947Y1099838D01*
G02X1391089Y1099897I142J-141D01*
G01X1408445D01*
G02X1408587Y1099838I0J-200D01*
G01X1408648Y1099777D01*
G02X1408707Y1099635I-141J-142D01*
G01Y1097686D01*
G02X1408507Y1097486I-200J0D01*
G01X1391430D01*
G02X1391289Y1097545I1J200D01*
G01X1390999Y1097835D01*
G02X1390940Y1097976I141J142D01*
G01Y1099832D01*
G37*
G36*
G01X1410853Y86514D02*
X1419568D01*
X1419921Y86161D01*
Y73377D01*
X1419475Y72931D01*
X1411077D01*
X1410742Y73266D01*
Y86403D01*
X1410853Y86514D01*
G37*
G36*
G01X1419370Y545147D02*
Y533484D01*
X1422653Y530201D01*
Y529803D01*
Y518852D01*
G02X1422594Y518710I-200J0D01*
G01X1422546Y518662D01*
G03X1422487Y518520I141J-142D01*
G01Y504632D01*
G02X1422428Y504490I-200J0D01*
G01X1421349Y503411D01*
G02X1421207Y503352I-142J141D01*
G01X1407720D01*
G02X1407578Y503411I0J200D01*
G01X1406912Y504077D01*
G02X1406853Y504219I141J142D01*
G01Y532166D01*
X1408958Y534271D01*
Y534788D01*
Y535061D01*
X1408986Y535089D01*
X1411327D01*
X1411443Y535205D01*
Y535259D01*
Y544824D01*
Y545347D01*
X1411782Y545686D01*
X1412305D01*
X1418831D01*
X1419370Y545147D01*
G37*
G36*
G01X1414052Y615406D02*
X1428896D01*
X1429425Y614877D01*
Y607425D01*
X1428500Y606500D01*
Y594000D01*
X1429425Y593075D01*
Y573133D01*
X1432924Y569634D01*
X1439224D01*
X1440046Y570456D01*
X1442055Y572466D01*
Y577231D01*
X1442603Y577779D01*
X1443919D01*
X1444914Y578774D01*
Y580708D01*
X1445301Y581095D01*
Y583479D01*
X1445366Y583544D01*
X1446171D01*
X1446208Y583507D01*
Y579964D01*
X1446609Y579563D01*
Y579518D01*
X1447902Y578225D01*
Y570737D01*
X1445702Y568537D01*
Y556856D01*
X1445731Y556827D01*
Y551391D01*
X1447496Y549626D01*
X1450823D01*
X1451826Y548623D01*
Y536737D01*
X1451078Y535989D01*
X1424221D01*
X1422213Y533981D01*
X1420571D01*
X1420179Y534373D01*
Y542795D01*
X1420387Y543003D01*
X1421691D01*
X1421743Y542951D01*
X1422135D01*
X1422938D01*
X1423256Y543269D01*
Y544072D01*
Y548298D01*
X1423250D01*
X1422382Y549166D01*
X1415257D01*
X1414015Y550408D01*
Y554389D01*
X1413997Y554407D01*
Y615351D01*
X1414052Y615406D01*
G37*
G36*
G01X1402217Y614747D02*
X1400426D01*
X1400304Y614625D01*
Y600460D01*
X1401159Y599605D01*
X1407000D01*
X1407245Y599850D01*
Y603288D01*
X1407000Y603533D01*
X1403418D01*
X1402467Y604484D01*
Y614671D01*
X1402391Y614747D01*
X1402217D01*
G37*
G36*
G01X1412884Y615416D02*
X1411190D01*
X1409698Y613924D01*
Y596700D01*
X1410198Y596200D01*
X1412800D01*
X1412995Y596395D01*
Y615305D01*
X1412884Y615416D01*
G37*
G36*
G01X1406649Y614714D02*
X1404431D01*
X1403984D01*
X1403881Y614611D01*
Y614164D01*
Y605739D01*
X1404085Y605535D01*
X1406955D01*
X1407199Y605779D01*
Y614164D01*
X1406649Y614714D01*
G37*
G36*
G01X1430210Y621858D02*
X1413652D01*
X1413601Y621807D01*
Y616817D01*
X1413686Y616732D01*
X1430579D01*
X1435006Y612305D01*
X1454256D01*
X1454865Y612914D01*
Y624584D01*
X1453344Y626105D01*
X1434457D01*
X1430210Y621858D01*
G37*
G36*
G01X1433333Y638140D02*
X1405572D01*
X1405245Y638467D01*
Y642374D01*
X1405815Y642944D01*
X1433390D01*
X1433618Y642716D01*
Y642170D01*
Y638425D01*
X1433333Y638140D01*
G37*
G36*
G01X1404008Y1059146D02*
Y1069654D01*
X1405071Y1070717D01*
X1420986D01*
X1421955Y1069748D01*
Y1059792D01*
X1421894Y1059731D01*
Y1058074D01*
X1420894Y1057074D01*
X1404821D01*
X1404008Y1057887D01*
Y1059146D01*
G37*
G36*
G01X1439031Y89379D02*
X1439129D01*
G02X1439270Y89438I142J-141D01*
G01X1453295D01*
G02X1453437Y89379I0J-200D01*
G01X1453440Y89376D01*
Y74039D01*
G03X1453498Y73898I200J0D01*
G01X1453545Y73851D01*
G02Y73568I-141J-141D01*
G01X1453358Y73381D01*
G02X1453216Y73322I-142J141D01*
G01X1449401D01*
X1449398Y73319D01*
X1429053D01*
G02X1428911Y73378I0J200D01*
G01X1428843Y73446D01*
G02X1428784Y73588I141J142D01*
G01Y86280D01*
G02X1428843Y86422I200J0D01*
G01X1428911Y86490D01*
G02X1429053Y86549I142J-141D01*
G01X1434364D01*
G03X1434506Y86608I0J200D01*
G01X1435339Y87441D01*
G03X1435398Y87583I-141J142D01*
G01Y88917D01*
G02X1435457Y89059I200J0D01*
G01X1435777Y89379D01*
G02X1435919Y89438I142J-141D01*
G01X1438890D01*
G02X1439031Y89379I-1J-200D01*
G37*
G36*
G01X1426779Y176789D02*
X1441206D01*
X1441969Y176026D01*
Y174795D01*
X1442732Y174032D01*
X1445840D01*
X1446427Y173445D01*
Y161423D01*
X1445723Y160719D01*
X1427424D01*
Y160720D01*
X1425428D01*
X1424667Y161481D01*
Y176203D01*
X1425253Y176789D01*
X1426779D01*
G37*
G36*
G01X1453698Y219609D02*
X1455340D01*
X1455732Y219217D01*
Y210795D01*
X1455524Y210587D01*
X1454220D01*
X1454168Y210639D01*
X1453776D01*
X1453774Y210638D01*
X1453029D01*
X1452655Y210264D01*
Y209518D01*
Y204802D01*
X1442186Y194333D01*
Y189191D01*
X1445823Y185554D01*
X1450588D01*
X1451136Y185006D01*
Y183690D01*
X1452131Y182695D01*
X1454065D01*
X1454452Y182308D01*
X1456666D01*
X1456844Y182130D01*
Y181714D01*
X1456531Y181401D01*
X1453321D01*
X1452920Y181000D01*
X1452875D01*
X1451582Y179707D01*
X1426023D01*
X1424711Y181019D01*
Y216698D01*
X1425614Y217601D01*
X1451690D01*
X1453698Y219609D01*
G37*
G36*
G01X1452058Y234621D02*
Y221520D01*
X1450257Y219719D01*
X1449161Y218623D01*
X1426320D01*
X1424592Y220351D01*
Y252516D01*
X1425903Y253827D01*
X1448143D01*
X1452058Y249912D01*
Y234621D01*
G37*
G36*
G01X1426938Y277007D02*
X1434367D01*
X1446818D01*
X1448675Y275150D01*
X1451254D01*
X1451529Y274875D01*
Y272398D01*
X1450979Y271848D01*
X1448435D01*
X1448331Y271952D01*
X1444651Y268272D01*
Y265554D01*
X1441453Y262356D01*
X1426869D01*
X1426181Y263044D01*
Y276250D01*
X1426938Y277007D01*
G37*
G36*
G01X1429931Y299467D02*
X1440215D01*
X1444651Y295031D01*
Y278899D01*
X1444410Y278658D01*
X1427660D01*
X1426388Y279930D01*
Y295924D01*
X1429931Y299467D01*
G37*
G36*
G01X1431029Y453982D02*
X1428389D01*
X1427730Y454641D01*
Y457485D01*
Y458933D01*
X1427725Y458937D01*
Y459774D01*
X1427004Y460495D01*
X1423015D01*
X1422299Y459779D01*
Y459195D01*
Y457910D01*
Y455716D01*
Y451556D01*
X1422834Y451021D01*
X1431619D01*
X1431630Y451032D01*
Y453381D01*
X1431029Y453982D01*
G37*
G36*
G01X1421274Y488854D02*
Y499374D01*
Y501186D01*
X1421861Y501773D01*
X1428693D01*
X1429201Y501265D01*
Y499252D01*
Y487471D01*
Y486284D01*
X1429900Y485585D01*
X1431087D01*
X1432484Y484188D01*
Y483142D01*
Y475515D01*
X1431824Y474855D01*
X1419030D01*
X1418382Y475503D01*
Y487282D01*
X1419100Y488000D01*
X1420420D01*
X1421274Y488854D01*
G37*
G36*
G01X1535466Y554616D02*
X1548288D01*
G02X1548428Y554559I0J-200D01*
G01X1548429Y554558D01*
X1549651Y553336D01*
X1549666Y553300D01*
G03X1549936Y553030I463J193D01*
G01X1549972Y553015D01*
X1550294Y552693D01*
X1550463Y552524D01*
X1554965D01*
X1555106Y552383D01*
Y551756D01*
Y551373D01*
G02X1555047Y551231I-200J0D01*
G01X1554962Y551146D01*
X1554934Y551117D01*
X1554860Y551087D01*
X1549700D01*
G03X1549558Y551028I0J-200D01*
G01X1547444Y548914D01*
X1547416Y548885D01*
X1547342Y548855D01*
X1545933D01*
G03X1545791Y548796I0J-200D01*
G01X1538082Y541087D01*
X1538054Y541058D01*
X1537980Y541028D01*
X1527285D01*
X1527273Y541029D01*
G03X1527146Y541041I-321J-2722D01*
G01X1527145D01*
G03X1526959Y541048I-196J-2735D01*
G01X1526957D01*
G03X1526771Y541041I10J-2742D01*
G01X1526770D01*
G03X1526643Y541029I194J-2734D01*
G01X1526631Y541028D01*
X1525185D01*
X1525173Y541029D01*
G03X1525046Y541041I-321J-2722D01*
G01X1525045D01*
G03X1524859Y541048I-196J-2735D01*
G01X1524857D01*
G03X1524671Y541041I10J-2742D01*
G01X1524670D01*
G03X1524543Y541029I194J-2734D01*
G01X1524531Y541028D01*
X1508114D01*
G03X1507972Y540969I0J-200D01*
G01X1494408Y527405D01*
G03X1494349Y527263I141J-142D01*
G01Y474821D01*
G02X1494290Y474679I-200J0D01*
G01X1470642Y451030D01*
G02X1470500Y450971I-142J141D01*
G01X1447882D01*
X1447860Y450949D01*
G02X1447718Y450890I-142J141D01*
G01X1444057D01*
G02X1443915Y450949I0J200D01*
G01X1443893Y450971D01*
X1441694D01*
Y450993D01*
X1433376D01*
G02X1433176Y451193I0J200D01*
G01Y453803D01*
G02X1433376Y454003I200J0D01*
G01X1435957D01*
G03X1436099Y454062I0J200D01*
G01X1438932Y456895D01*
G03X1438991Y457037I-141J142D01*
G01Y462233D01*
G02X1439048Y462373I200J0D01*
G01X1439049Y462374D01*
X1439788Y463113D01*
G03X1439847Y463255I-141J142D01*
G01Y467488D01*
G02X1439906Y467630I200J0D01*
G01X1442329Y470053D01*
G02X1442471Y470112I142J-141D01*
G01X1457045D01*
G03X1457187Y470171I0J200D01*
G01X1459719Y472703D01*
G03X1459778Y472845I-141J142D01*
G01Y487807D01*
G03X1459719Y487949I-200J0D01*
G01X1458494Y489174D01*
G03X1458352Y489233I-142J-141D01*
G01X1434123D01*
G03X1433981Y489174I0J-200D01*
G01X1432079Y487272D01*
X1432051Y487243D01*
X1431977Y487213D01*
X1430402D01*
G02X1430202Y487413I0J200D01*
G01Y495744D01*
G02X1430274Y495897I200J-1D01*
G01X1430543Y496123D01*
X1430627Y496146D01*
X1430671Y496138D01*
X1430674Y496137D01*
X1430675D01*
G03X1430930Y496116I250J1480D01*
G03X1431440Y496205I1J1501D01*
G02X1431552Y496212I68J-188D01*
G03X1431596Y496207I44J195D01*
G01X1431883D01*
X1432652D01*
X1433087Y496642D01*
Y497411D01*
Y500592D01*
G02X1433144Y500732I200J0D01*
G01X1433145Y500733D01*
X1434005Y501593D01*
G02X1434007Y501595I142J-140D01*
G02X1434147Y501652I140J-143D01*
G01X1451878D01*
G03X1452020Y501711I0J200D01*
G01X1455607Y505298D01*
G03X1455666Y505440I-141J142D01*
G01Y528321D01*
G02X1455723Y528461I200J0D01*
G01X1455724Y528462D01*
X1478370Y551108D01*
G02X1478372Y551110I142J-140D01*
G02X1478512Y551167I140J-143D01*
G01X1511921D01*
G02X1511992Y551154I0J-200D01*
G01X1512089Y551117D01*
X1512116Y551095D01*
G03X1513284Y550664I1169J1371D01*
G03X1514452Y551095I-1J1802D01*
G01X1514479Y551117D01*
X1514576Y551154D01*
G02X1514647Y551167I71J-187D01*
G01X1528878D01*
G02X1528946Y551155I0J-200D01*
G01X1529036Y551123D01*
X1529062Y551103D01*
G03X1530304Y550671I1243J1571D01*
G03X1531570Y551122I0J2002D01*
G01X1531598Y551144D01*
X1531661Y551167D01*
X1531851D01*
G03X1531993Y551226I0J200D01*
G01X1535324Y554557D01*
G02X1535326Y554559I142J-140D01*
G02X1535466Y554616I140J-143D01*
G37*
G36*
G01X1423853Y518969D02*
Y532070D01*
X1425654Y533871D01*
X1426750Y534967D01*
X1449591D01*
X1453034Y531524D01*
Y520887D01*
Y504757D01*
X1451876Y503599D01*
X1425462D01*
X1423853Y505208D01*
Y518969D01*
G37*
G36*
G01X1428050Y965621D02*
G03I-577J0D01*
G37*
G36*
G01X1508917Y54588D02*
X1537184D01*
X1537398Y54374D01*
Y52805D01*
X1537184Y52591D01*
X1508917D01*
G03X1502980Y46654I0J-5937D01*
G01Y7874D01*
G02X1497106Y2000I-5874J0D01*
G01X1449862D01*
G02X1443988Y7874I0J5874D01*
G01Y46654D01*
G03X1442424Y50670I-5938J0D01*
G01Y50786D01*
X1442657Y51019D01*
X1444546D01*
X1444895Y50670D01*
G02X1445986Y46656I-6843J-4015D01*
G01Y7874D01*
G03X1449862Y3998I3876J0D01*
G01X1497106D01*
G03X1500982Y7874I0J3876D01*
G01Y46654D01*
G02X1508917Y54588I7935J-1D01*
G37*
G36*
G01X1438882Y95055D02*
X1453898D01*
X1453918Y95035D01*
X1457923D01*
X1458636Y94322D01*
Y74773D01*
X1457775Y73912D01*
X1455164D01*
X1454900D01*
X1454441Y74371D01*
Y90663D01*
X1454318Y90786D01*
X1453612D01*
X1450857D01*
X1439119D01*
X1439080Y90747D01*
X1438803Y91024D01*
Y94976D01*
X1438882Y95055D01*
G37*
G36*
G01X1445403Y448919D02*
X1439403D01*
X1438319D01*
X1436757D01*
X1436504Y448666D01*
Y443698D01*
X1437244Y442958D01*
X1438875D01*
X1445319D01*
X1445903Y443542D01*
Y448419D01*
X1445403Y448919D01*
G37*
G36*
G01X1433684Y475886D02*
Y485326D01*
X1435485Y487127D01*
X1436581Y488223D01*
X1457432D01*
X1458379Y487276D01*
Y476504D01*
X1456935Y475060D01*
X1434510D01*
X1433684Y475886D01*
G37*
G36*
G01X1541933Y577871D02*
X1554284D01*
G02X1554426Y577812I0J-200D01*
G01X1554912Y577326D01*
G02X1554971Y577184I-141J-142D01*
G01Y563277D01*
G02X1554912Y563135I-200J0D01*
G01X1554779Y563002D01*
G02X1554637Y562943I-142J141D01*
G01X1540450D01*
G02X1540308Y563002I0J200D01*
G01X1537494Y565816D01*
G03X1537352Y565875I-142J-141D01*
G01X1531637D01*
G02X1531510Y565920I-1J200D01*
G03X1528974I-1268J-1548D01*
G02X1528847Y565875I-126J155D01*
G01X1512185D01*
G03X1512043Y565816I0J-200D01*
G01X1510777Y564550D01*
G03X1510718Y564408I141J-142D01*
G01Y558946D01*
G02X1510659Y558804I-200J0D01*
G01X1508024Y556169D01*
G02X1507882Y556110I-142J141D01*
G01X1474067D01*
G03X1473925Y556051I0J-200D01*
G01X1469980Y552106D01*
G02X1469838Y552047I-142J141D01*
G01X1448930D01*
G02X1448788Y552106I0J200D01*
G01X1447929Y552965D01*
G02X1447870Y553107I141J142D01*
G01Y567243D01*
G02X1447929Y567385I200J0D01*
G01X1449425Y568881D01*
G02X1449567Y568940I142J-141D01*
G01X1452730D01*
G03X1452872Y568999I0J200D01*
G01X1453289Y569416D01*
G03X1453348Y569558I-141J142D01*
G01Y572492D01*
G02X1453407Y572634I200J0D01*
G01X1453980Y573207D01*
G02X1454122Y573266I142J-141D01*
G01X1461404D01*
G03X1461546Y573325I0J200D01*
G01X1469380Y581159D01*
X1469424D01*
X1469595Y581330D01*
G02X1469737Y581389I142J-141D01*
G01X1470871Y582523D01*
X1537281D01*
X1541933Y577871D01*
G37*
G36*
G01X1434106Y627231D02*
X1454158D01*
X1455094Y628167D01*
Y641266D01*
X1454544Y641816D01*
X1439931D01*
X1438913Y640798D01*
Y633084D01*
X1438405Y632576D01*
X1434314D01*
X1433763Y632025D01*
Y630928D01*
Y627574D01*
X1434106Y627231D01*
G37*
G36*
G01X1458793Y276354D02*
X1476366D01*
X1477192Y275528D01*
Y258570D01*
X1475120Y256498D01*
Y231237D01*
X1469058Y225175D01*
Y224534D01*
Y220921D01*
X1466758Y218621D01*
X1464758D01*
X1464468Y218331D01*
Y205660D01*
X1463881Y205073D01*
X1457049D01*
X1456541Y205581D01*
Y220421D01*
X1453258Y223704D01*
Y234821D01*
X1453424Y234987D01*
Y250246D01*
X1456588Y253410D01*
X1456624D01*
X1458844Y255630D01*
Y268925D01*
X1455835Y271934D01*
X1453531D01*
X1453015Y272450D01*
Y274738D01*
X1453238Y274961D01*
X1457400D01*
X1458793Y276354D01*
G37*
G36*
G01X1454047Y276095D02*
X1454786D01*
X1454812Y276122D01*
X1457013D01*
X1458465Y277574D01*
X1460100D01*
X1460134Y277540D01*
X1467305D01*
X1467337Y277572D01*
X1475068D01*
X1476883Y279387D01*
Y287118D01*
Y296369D01*
X1476057Y297195D01*
X1459825D01*
X1457710Y295080D01*
Y282733D01*
X1455527Y280550D01*
X1453737Y278760D01*
Y276405D01*
X1454047Y276095D01*
G37*
G36*
G01X1464824Y876914D02*
X1471738D01*
X1473224Y878400D01*
X1475001D01*
X1476035Y877366D01*
Y873263D01*
X1475809Y873037D01*
X1464889D01*
X1464501Y873425D01*
Y876591D01*
X1464824Y876914D01*
G37*
G36*
G01X1468513Y1037418D02*
X1473690D01*
G02X1473832Y1037359I0J-200D01*
G01X1474856Y1036335D01*
G02X1474915Y1036193I-141J-142D01*
G01Y1035092D01*
G02X1474715Y1034892I-200J0D01*
G01X1472254D01*
G03X1472113Y1034834I0J-200D01*
G01X1471094Y1033815D01*
G03X1471036Y1033674I142J-141D01*
G01Y1033636D01*
G02X1470977Y1033495I-200J1D01*
G01X1469747Y1032265D01*
G03X1469688Y1032123I141J-142D01*
G01Y1026422D01*
G02X1469629Y1026280I-200J0D01*
G01X1469484Y1026135D01*
G02X1469342Y1026076I-142J141D01*
G01X1464502D01*
G02X1464360Y1026135I0J200D01*
G01X1464332Y1026163D01*
G02X1464273Y1026305I141J142D01*
G01Y1033178D01*
G02X1464332Y1033320I200J0D01*
G01X1468371Y1037359D01*
G02X1468513Y1037418I142J-141D01*
G37*
G36*
G01X1479966Y-83456D02*
G03I-557J0D01*
G37*
G36*
G01Y-78500D02*
G03I-557J0D01*
G37*
G36*
G01Y-68500D02*
G03I-557J0D01*
G37*
G36*
G01Y-73456D02*
G03I-557J0D01*
G37*
G36*
G01X1482005Y115094D02*
X1483061D01*
X1483088Y115067D01*
Y111227D01*
G02X1483029Y111085I-200J0D01*
G01X1481399Y109456D01*
G03X1481340Y109314I141J-142D01*
G01Y106183D01*
G03X1481399Y106041I200J0D01*
G01X1481522Y105918D01*
G03X1481664Y105859I142J141D01*
G01X1492370D01*
G03X1492512Y105918I0J200D01*
G01X1492588Y105994D01*
G03X1492647Y106136I-141J142D01*
G01Y109681D01*
G03X1492588Y109823I-200J0D01*
G01X1492354Y110057D01*
G02X1492295Y110199I141J142D01*
G01Y114552D01*
X1492325Y114625D01*
X1492336Y114636D01*
X1497920D01*
X1499262D01*
X1499326Y114572D01*
X1499442Y114456D01*
G02X1499501Y114314I-141J-142D01*
G01Y105226D01*
G02X1499442Y105084I-200J0D01*
G01X1498771Y104413D01*
X1498688Y104383D01*
X1498643Y104388D01*
G03X1498461Y104396I-174J-1893D01*
G01X1495879D01*
X1494593D01*
X1493847Y103650D01*
Y101528D01*
X1493515Y101196D01*
X1481984D01*
X1481960Y101202D01*
X1474780D01*
X1474085Y101897D01*
Y102887D01*
Y114049D01*
G02X1474144Y114191I200J0D01*
G01X1474266Y114313D01*
G02X1474408Y114372I142J-141D01*
G01X1481117D01*
G03X1481259Y114431I0J200D01*
G01X1481863Y115035D01*
G02X1482005Y115094I142J-141D01*
G37*
G36*
G01X1474267Y120851D02*
X1479684D01*
G02X1479826Y120792I0J-200D01*
G01X1481447Y119171D01*
G03X1481589Y119112I142J141D01*
G01X1483104D01*
G02X1483246Y119053I0J-200D01*
G01X1483719Y118580D01*
G02X1483778Y118438I-141J-142D01*
G01Y116276D01*
G02X1483655Y116091I-200J0D01*
G01X1483598Y116068D01*
X1483480Y116091D01*
X1483476Y116096D01*
X1482004D01*
G03X1481190Y115777I1J-1202D01*
G02X1481054Y115724I-136J147D01*
G01X1474208D01*
G02X1474066Y115783I0J200D01*
G01X1474051Y115798D01*
X1474021Y115871D01*
Y120605D01*
G02X1474080Y120747I200J0D01*
G01X1474125Y120792D01*
G02X1474267Y120851I142J-141D01*
G37*
G36*
G01X1479282Y1016648D02*
X1484058D01*
X1484070Y1016636D01*
Y1014833D01*
G03X1484422Y1013983I1201J0D01*
G01X1484423D01*
X1485005Y1013401D01*
Y1013400D01*
G03X1485855Y1013048I850J849D01*
G01X1500286D01*
G03X1500407Y1013054I1J1201D01*
G01X1500453Y1013058D01*
X1500536Y1013029D01*
X1500906Y1012659D01*
G02X1500965Y1012517I-141J-142D01*
G01Y1008439D01*
G02X1500906Y1008297I-200J0D01*
G01X1500179Y1007570D01*
G02X1500038Y1007512I-141J142D01*
G01X1486381D01*
G03X1486117Y1007482I3J-1202D01*
G01X1486095Y1007477D01*
X1485590D01*
G03X1485448Y1007418I0J-200D01*
G01X1484841Y1006811D01*
G03X1484782Y1006669I141J-142D01*
G01Y1006438D01*
X1484762Y1006378D01*
X1484743Y1006352D01*
G03X1484506Y1005637I965J-717D01*
G01Y1001656D01*
G02X1484448Y1001515I-200J0D01*
G01X1484137Y1001204D01*
G02X1483995Y1001145I-142J141D01*
G01X1478949D01*
G02X1478807Y1001204I0J200D01*
G01X1478608Y1001403D01*
X1478595Y1001546D01*
X1478635Y1001605D01*
G03X1478842Y1002278I-995J674D01*
G01Y1016208D01*
G02X1478900Y1016349I200J0D01*
G01X1479140Y1016589D01*
G02X1479282Y1016648I142J-141D01*
G37*
G36*
G01X1472145Y1009035D02*
Y1016838D01*
G02X1472204Y1016980I200J0D01*
G01X1472221Y1016997D01*
G02X1472363Y1017056I142J-141D01*
G01X1477492D01*
G02X1477634Y1016997I0J-200D01*
G01X1477781Y1016850D01*
G02X1477840Y1016708I-141J-142D01*
G01Y1002279D01*
G02X1477781Y1002137I-200J0D01*
G01X1477197Y1001553D01*
G02X1477055Y1001494I-142J141D01*
G01X1473484D01*
G02X1473342Y1001553I0J200D01*
G01X1472229Y1002666D01*
G02X1472170Y1002808I141J142D01*
G01Y1009011D01*
X1472145Y1009035D01*
G37*
G36*
G01X1474711Y1033551D02*
G03X1474914Y1033626I-452J1536D01*
G01X1474953Y1033643D01*
X1476711D01*
X1476749Y1033627D01*
G03X1477373Y1033500I625J1475D01*
G01X1478996D01*
G02X1479137Y1033442I0J-200D01*
G01X1479864Y1032715D01*
G02X1479923Y1032573I-141J-142D01*
G01Y1027861D01*
X1479908Y1027809D01*
X1479894Y1027785D01*
G03X1479864Y1027680I170J-105D01*
G01Y1026159D01*
G02X1479805Y1026017I-200J0D01*
G01X1478301Y1024513D01*
G03X1478242Y1024371I141J-142D01*
G01Y1023313D01*
G02X1478183Y1023171I-200J0D01*
G01X1478182Y1023170D01*
Y1019903D01*
G02X1478123Y1019761I-200J0D01*
G01X1477772Y1019410D01*
X1477744Y1019381D01*
X1477670Y1019351D01*
X1472551D01*
G02X1472409Y1019410I0J200D01*
G01X1472096Y1019723D01*
G02X1472077Y1019745I141J141D01*
G02X1472037Y1019866I160J120D01*
G01Y1033259D01*
G02X1472096Y1033400I200J-1D01*
G01X1472123Y1033427D01*
G02X1472264Y1033486I142J-141D01*
G01X1474261D01*
G03X1474711Y1033551I-2J1602D01*
G37*
G36*
G01X1481834Y1028234D02*
X1482935D01*
G02X1483077Y1028175I0J-200D01*
G01X1483339Y1027912D01*
G02X1483398Y1027771I-141J-142D01*
G01Y1019455D01*
G02X1483339Y1019313I-200J0D01*
G01X1482792Y1018766D01*
G02X1482650Y1018707I-142J141D01*
G01X1480157D01*
G02X1480015Y1018766I0J200D01*
G01X1479812Y1018969D01*
G02X1479753Y1019111I141J142D01*
G01Y1024435D01*
G02X1479812Y1024577I200J0D01*
G01X1481092Y1025857D01*
G03X1481151Y1025999I-141J142D01*
G01Y1027551D01*
G02X1481210Y1027692I200J-1D01*
G01X1481692Y1028175D01*
G02X1481834Y1028234I142J-141D01*
G37*
G36*
G01X1505691Y1066535D02*
G02I-17700J0D01*
G37*
G36*
G01X1473891Y1105784D02*
X1488864D01*
G02X1489005Y1105726I0J-200D01*
G01X1489040Y1105691D01*
G02X1489099Y1105549I-141J-142D01*
G01Y1100990D01*
G02X1489040Y1100848I-200J0D01*
G01X1489014Y1100822D01*
X1488941Y1100792D01*
X1473781D01*
G02X1473639Y1100851I0J200D01*
G01X1473436Y1101054D01*
G02X1473377Y1101196I141J142D01*
G01Y1104872D01*
X1473378D01*
Y1105271D01*
G02X1473437Y1105413I200J0D01*
G01X1473750Y1105726D01*
G02X1473891Y1105784I141J-142D01*
G37*
G36*
G01X1480966Y1112481D02*
X1488769D01*
G02X1488911Y1112422I0J-200D01*
G01X1488928Y1112405D01*
G02X1488987Y1112263I-141J-142D01*
G01Y1107134D01*
G02X1488928Y1106992I-200J0D01*
G01X1488781Y1106845D01*
G02X1488639Y1106786I-142J141D01*
G01X1474210D01*
G02X1474068Y1106845I0J200D01*
G01X1473484Y1107429D01*
G02X1473425Y1107571I141J142D01*
G01Y1111142D01*
G02X1473484Y1111284I200J0D01*
G01X1474597Y1112397D01*
G02X1474739Y1112456I142J-141D01*
G01X1480942D01*
X1480966Y1112481D01*
G37*
G36*
G01X1473891Y1118384D02*
X1488864D01*
G02X1489006Y1118325I0J-200D01*
G01X1489040Y1118291D01*
G02X1489042Y1118289I-140J-142D01*
G02X1489099Y1118149I-143J-140D01*
G01Y1113590D01*
G02X1489068Y1113482I-200J-1D01*
G01X1480539D01*
X1480515Y1113458D01*
X1474324D01*
G03X1474183Y1113399I1J-200D01*
G01X1474176Y1113392D01*
X1473781D01*
G02X1473639Y1113451I0J200D01*
G01X1473436Y1113654D01*
X1473407Y1113682D01*
X1473377Y1113756D01*
Y1117472D01*
X1473378D01*
Y1117871D01*
G02X1473435Y1118011I200J0D01*
G01X1473436Y1118012D01*
X1473749Y1118325D01*
G02X1473891Y1118384I142J-141D01*
G37*
G36*
G01X1480966Y1125081D02*
X1488769D01*
G02X1488911Y1125022I0J-200D01*
G01X1488928Y1125005D01*
G02X1488987Y1124863I-141J-142D01*
G01Y1119734D01*
G02X1488928Y1119592I-200J0D01*
G01X1488781Y1119445D01*
G02X1488639Y1119386I-142J141D01*
G01X1474210D01*
G02X1474068Y1119445I0J200D01*
G01X1473484Y1120029D01*
G02X1473425Y1120171I141J142D01*
G01Y1123742D01*
G02X1473484Y1123884I200J0D01*
G01X1474597Y1124997D01*
G02X1474739Y1125056I142J-141D01*
G01X1480942D01*
X1480966Y1125081D01*
G37*
G36*
G01X1473891Y1130984D02*
X1488864D01*
G02X1489005Y1130926I0J-200D01*
G01X1489040Y1130891D01*
G02X1489099Y1130749I-141J-142D01*
G01Y1126107D01*
X1489074Y1126082D01*
X1480539D01*
X1480515Y1126058D01*
X1474324D01*
G03X1474183Y1125999I1J-200D01*
G01X1474176Y1125992D01*
X1473781D01*
G02X1473639Y1126051I0J200D01*
G01X1473436Y1126254D01*
G02X1473377Y1126396I141J142D01*
G01Y1130072D01*
X1473378D01*
Y1130471D01*
G02X1473437Y1130613I200J0D01*
G01X1473750Y1130926D01*
G02X1473891Y1130984I141J-142D01*
G37*
G36*
G01Y1143584D02*
X1488864D01*
G02X1489005Y1143526I0J-200D01*
G01X1489040Y1143491D01*
G02X1489099Y1143349I-141J-142D01*
G01Y1138707D01*
X1489074Y1138682D01*
X1480539D01*
X1480515Y1138658D01*
X1474324D01*
G03X1474183Y1138599I1J-200D01*
G01X1474176Y1138592D01*
X1473781D01*
G02X1473639Y1138651I0J200D01*
G01X1473436Y1138854D01*
G02X1473377Y1138996I141J142D01*
G01Y1142672D01*
X1473378D01*
Y1143071D01*
G02X1473437Y1143213I200J0D01*
G01X1473750Y1143526D01*
G02X1473891Y1143584I141J-142D01*
G37*
G36*
G01X1480966Y1137681D02*
X1488769D01*
G02X1488911Y1137622I0J-200D01*
G01X1488928Y1137605D01*
G02X1488987Y1137463I-141J-142D01*
G01Y1132334D01*
G02X1488928Y1132192I-200J0D01*
G01X1488781Y1132045D01*
G02X1488639Y1131986I-142J141D01*
G01X1474210D01*
G02X1474068Y1132045I0J200D01*
G01X1473484Y1132629D01*
G02X1473425Y1132771I141J142D01*
G01Y1136342D01*
G02X1473484Y1136484I200J0D01*
G01X1474597Y1137597D01*
G02X1474739Y1137656I142J-141D01*
G01X1480942D01*
X1480966Y1137681D01*
G37*
G36*
G01X1473891Y1156184D02*
X1488864D01*
G02X1489005Y1156126I0J-200D01*
G01X1489040Y1156091D01*
G02X1489099Y1155949I-141J-142D01*
G01Y1151307D01*
X1489074Y1151282D01*
X1480539D01*
X1480515Y1151258D01*
X1474324D01*
G03X1474183Y1151199I1J-200D01*
G01X1474176Y1151192D01*
X1473781D01*
G02X1473639Y1151251I0J200D01*
G01X1473436Y1151454D01*
G02X1473377Y1151596I141J142D01*
G01Y1155272D01*
X1473378D01*
Y1155671D01*
G02X1473437Y1155813I200J0D01*
G01X1473750Y1156126D01*
G02X1473891Y1156184I141J-142D01*
G37*
G36*
G01X1480966Y1150281D02*
X1488769D01*
G02X1488911Y1150222I0J-200D01*
G01X1488928Y1150205D01*
G02X1488987Y1150063I-141J-142D01*
G01Y1144934D01*
G02X1488928Y1144792I-200J0D01*
G01X1488781Y1144645D01*
G02X1488639Y1144586I-142J141D01*
G01X1474210D01*
G02X1474068Y1144645I0J200D01*
G01X1473484Y1145229D01*
G02X1473425Y1145371I141J142D01*
G01Y1148942D01*
G02X1473484Y1149084I200J0D01*
G01X1474597Y1150197D01*
G02X1474739Y1150256I142J-141D01*
G01X1480942D01*
X1480966Y1150281D01*
G37*
G36*
G01X1473891Y1168784D02*
X1488864D01*
G02X1489005Y1168726I0J-200D01*
G01X1489040Y1168691D01*
G02X1489099Y1168549I-141J-142D01*
G01Y1163907D01*
X1489074Y1163882D01*
X1480539D01*
X1480515Y1163858D01*
X1474324D01*
G03X1474183Y1163799I1J-200D01*
G01X1474176Y1163792D01*
X1473781D01*
G02X1473639Y1163851I0J200D01*
G01X1473436Y1164054D01*
G02X1473377Y1164196I141J142D01*
G01Y1167872D01*
X1473378D01*
Y1168271D01*
G02X1473437Y1168413I200J0D01*
G01X1473750Y1168726D01*
G02X1473891Y1168784I141J-142D01*
G37*
G36*
G01X1480966Y1175481D02*
X1488769D01*
G02X1488911Y1175422I0J-200D01*
G01X1488928Y1175405D01*
G02X1488987Y1175263I-141J-142D01*
G01Y1170134D01*
G02X1488928Y1169992I-200J0D01*
G01X1488781Y1169845D01*
G02X1488639Y1169786I-142J141D01*
G01X1474210D01*
G02X1474068Y1169845I0J200D01*
G01X1473484Y1170429D01*
G02X1473425Y1170571I141J142D01*
G01Y1174142D01*
G02X1473484Y1174284I200J0D01*
G01X1474597Y1175397D01*
G02X1474739Y1175456I142J-141D01*
G01X1480942D01*
X1480966Y1175481D01*
G37*
G36*
G01Y1162881D02*
X1488769D01*
G02X1488911Y1162822I0J-200D01*
G01X1488928Y1162805D01*
G02X1488987Y1162663I-141J-142D01*
G01Y1157534D01*
G02X1488928Y1157392I-200J0D01*
G01X1488781Y1157245D01*
G02X1488639Y1157186I-142J141D01*
G01X1474210D01*
G02X1474068Y1157245I0J200D01*
G01X1473484Y1157829D01*
G02X1473425Y1157971I141J142D01*
G01Y1161542D01*
G02X1473484Y1161684I200J0D01*
G01X1474597Y1162797D01*
G02X1474739Y1162856I142J-141D01*
G01X1480942D01*
X1480966Y1162881D01*
G37*
G36*
G01X1473891Y1181384D02*
X1488864D01*
G02X1489005Y1181326I0J-200D01*
G01X1489040Y1181291D01*
G02X1489099Y1181149I-141J-142D01*
G01Y1176507D01*
X1489074Y1176482D01*
X1480539D01*
X1480515Y1176458D01*
X1474324D01*
G03X1474183Y1176399I1J-200D01*
G01X1474176Y1176392D01*
X1473781D01*
G02X1473639Y1176451I0J200D01*
G01X1473436Y1176654D01*
G02X1473377Y1176796I141J142D01*
G01Y1180472D01*
X1473378D01*
Y1180871D01*
G02X1473437Y1181013I200J0D01*
G01X1473750Y1181326D01*
G02X1473891Y1181384I141J-142D01*
G37*
G36*
G01X1480966Y1188081D02*
X1488769D01*
G02X1488911Y1188022I0J-200D01*
G01X1488928Y1188005D01*
G02X1488987Y1187863I-141J-142D01*
G01Y1182734D01*
G02X1488928Y1182592I-200J0D01*
G01X1488781Y1182445D01*
G02X1488639Y1182386I-142J141D01*
G01X1474210D01*
G02X1474068Y1182445I0J200D01*
G01X1473484Y1183029D01*
G02X1473425Y1183171I141J142D01*
G01Y1186742D01*
G02X1473484Y1186884I200J0D01*
G01X1474597Y1187997D01*
G02X1474739Y1188056I142J-141D01*
G01X1480942D01*
X1480966Y1188081D01*
G37*
G36*
G01X1505691Y1263386D02*
G02I-17700J0D01*
G37*
G36*
G01X1485370Y119235D02*
X1488816D01*
X1491652Y122071D01*
X1497699D01*
X1498069Y121701D01*
Y116118D01*
X1497588Y115637D01*
X1487914D01*
X1485558D01*
X1485210Y115985D01*
Y119075D01*
X1485370Y119235D01*
G37*
G36*
G01X1483942Y210785D02*
X1493382D01*
X1495183Y208984D01*
X1496279Y207888D01*
Y187037D01*
X1495332Y186090D01*
X1484560D01*
X1483116Y187534D01*
Y209959D01*
X1483942Y210785D01*
G37*
G36*
G01X1497301Y186998D02*
Y210417D01*
X1495293Y212425D01*
Y214067D01*
X1495685Y214459D01*
X1504107D01*
X1504315Y214251D01*
Y212947D01*
X1504263Y212895D01*
Y212503D01*
Y211718D01*
X1504599Y211382D01*
X1505384D01*
X1509610D01*
X1510938Y210054D01*
Y205828D01*
Y187369D01*
X1509783Y186214D01*
X1498085D01*
X1497301Y186998D01*
G37*
G36*
G01X1496571Y223195D02*
X1506596D01*
X1506626Y223225D01*
X1509149D01*
X1511786Y225862D01*
X1520728D01*
X1521070Y225520D01*
Y213126D01*
X1520358Y212414D01*
X1512941D01*
X1510087Y215268D01*
X1506647D01*
X1495670D01*
X1494106D01*
X1493660Y214822D01*
Y213258D01*
X1492387Y211985D01*
X1491975D01*
X1491198D01*
X1483571D01*
X1482911Y212645D01*
Y226569D01*
X1483587Y227245D01*
X1494521D01*
X1496281Y225485D01*
Y223485D01*
X1496571Y223195D01*
G37*
G36*
G01X1498402Y919378D02*
X1500148D01*
G02X1500348Y919178I0J-200D01*
G01Y917432D01*
G02X1500319Y917329I-200J1D01*
G03X1500138Y916678I1080J-651D01*
G01Y913957D01*
G02X1500080Y913816I-200J0D01*
G01X1499466Y913202D01*
G03X1499096Y912310I892J-893D01*
G01Y908592D01*
G02X1498922Y908490I-174J98D01*
G01X1498890D01*
X1498774Y908373D01*
Y906108D01*
X1498890Y905990D01*
X1498964D01*
X1499080D01*
G02X1499265Y905867I0J-200D01*
G01X1499289Y905810D01*
X1499265Y905692D01*
X1498845Y905271D01*
G03X1498622Y904733I537J-538D01*
G01Y904342D01*
G02X1498422Y904142I-200J0D01*
G01X1498115D01*
X1497783D01*
G03X1497282Y903640I0J-501D01*
G01Y902242D01*
X1497281D01*
Y900840D01*
G03X1497782Y900338I502J0D01*
G01X1500125D01*
G02X1500267Y900279I0J-200D01*
G01X1500659Y899887D01*
X1500689Y899794D01*
X1500680Y899745D01*
G03X1500656Y899479I1478J-267D01*
G03X1502158Y897977I1502J0D01*
G03X1502358Y897990I3J1502D01*
G03X1503379Y898603I-200J1489D01*
G01X1503392Y898622D01*
X1503426Y898652D01*
X1503479Y898680D01*
G02X1503573Y898704I95J-176D01*
G01X1504631D01*
G02X1504772Y898645I-1J-200D01*
G01X1505662Y897755D01*
G02X1505720Y897614I-142J-141D01*
G01Y891656D01*
G02X1505662Y891515I-200J0D01*
G01X1505240Y891093D01*
G02X1505099Y891034I-142J141D01*
G01X1499903D01*
G03X1499402Y890533I0J-501D01*
G01Y885733D01*
G03X1499903Y885232I501J0D01*
G01X1505503D01*
G03X1506004Y885733I0J501D01*
G01Y889621D01*
G02X1506063Y889762I200J-1D01*
G01X1507020Y890720D01*
G03X1507244Y891258I-537J539D01*
G01Y898012D01*
G03X1507020Y898550I-761J-1D01*
G01X1505645Y899926D01*
G02X1505601Y900143I141J142D01*
G01X1505629Y900213D01*
G02X1505814Y900338I185J-75D01*
G01X1506299D01*
X1506783D01*
G03X1507284Y900840I0J501D01*
G01Y901318D01*
G02X1507387Y901478I200J-16D01*
G01X1512493D01*
G02X1512634Y901420I0J-200D01*
G01X1513212Y900842D01*
G02X1513270Y900701I-142J-141D01*
G01Y897829D01*
G02X1513110Y897726I-176J97D01*
G01X1508565D01*
G03X1508064Y897225I0J-501D01*
G01Y892425D01*
G03X1508565Y891924I501J0D01*
G01X1514165D01*
G03X1514666Y892425I0J501D01*
G01Y896785D01*
X1514680Y896835D01*
X1514693Y896858D01*
G03X1514794Y897236I-661J379D01*
G01Y901099D01*
G03X1514570Y901637I-761J-1D01*
G01X1513429Y902778D01*
G03X1512891Y903002I-539J-537D01*
G01X1507387D01*
G02X1507284Y903162I97J176D01*
G01Y903408D01*
X1507285D01*
Y903640D01*
G03X1506784Y904142I-502J0D01*
G01X1505144D01*
G02X1504970Y904244I0J200D01*
G01Y905888D01*
G02X1505144Y905990I174J-98D01*
G01X1505592D01*
X1505676D01*
X1505792Y906108D01*
Y908290D01*
G03X1505592Y908490I-200J0D01*
G01X1505586D01*
X1505470Y908606D01*
Y908894D01*
X1505484Y908946D01*
X1505498Y908969D01*
G03X1505697Y909939I-1290J770D01*
G03X1505498Y910510I-1489J-199D01*
G02X1505470Y910613I172J102D01*
G01Y912664D01*
G03X1505403Y913069I-1262J-1D01*
G01X1505411Y913111D01*
X1505632Y913398D01*
G02X1505789Y913476I159J-122D01*
G01X1505887D01*
G03X1506388Y913978I0J501D01*
G01Y915453D01*
G02X1506446Y915593I200J-1D01*
G03X1506888Y916677I-1109J1084D01*
G01Y919174D01*
G02X1507088Y919374I200J0D01*
G01X1507489D01*
G02X1507629Y919317I0J-200D01*
G01X1507630Y919316D01*
X1507759Y919187D01*
G02X1507761Y919185I-140J-142D01*
G02X1507818Y919045I-143J-140D01*
G01Y911459D01*
G03X1507877Y911317I200J0D01*
G01X1508868Y910326D01*
G02X1508870Y910324I-140J-142D01*
G02X1508927Y910184I-143J-140D01*
G01Y909831D01*
G02X1508907Y909743I-200J-1D01*
G03X1508724Y908951I1619J-791D01*
G03X1509834Y907287I1802J0D01*
G01X1509871Y907271D01*
X1511021Y906121D01*
G03X1511163Y906062I142J141D01*
G01X1516238D01*
G02X1516271Y906059I-2J-200D01*
G02X1516378Y906005I-32J-197D01*
G01X1519129Y903254D01*
G02X1519188Y903112I-141J-142D01*
G01Y888871D01*
X1519158Y888797D01*
X1519129Y888769D01*
X1511505Y881145D01*
G02X1511363Y881086I-142J141D01*
G01X1498714D01*
X1498640Y881116D01*
X1498612Y881145D01*
X1496500Y883257D01*
G02X1496441Y883399I141J142D01*
G01Y894541D01*
X1496459Y894580D01*
G03X1496391Y896081I-1505J684D01*
G01X1496383Y896094D01*
G03X1495784Y896693I-1429J-830D01*
G01X1495761Y896707D01*
X1494217Y898251D01*
G02X1494158Y898393I141J142D01*
G01Y915928D01*
G02X1494215Y916068I200J0D01*
G01X1494216Y916069D01*
X1495757Y917610D01*
X1495874Y917633D01*
X1495931Y917610D01*
G03X1496500Y917498I569J1389D01*
G03X1498002Y918982I0J1502D01*
G01Y919022D01*
X1498033Y919094D01*
X1498261Y919320D01*
G02X1498402Y919378I141J-142D01*
G37*
G36*
G01X1519616Y1054577D02*
X1673998D01*
X1689428D01*
X1741498Y1002507D01*
Y983158D01*
X1745016Y979640D01*
X1774216D01*
X1776327Y977529D01*
Y961345D01*
X1777294Y960378D01*
X1778612D01*
G02X1778754Y960319I0J-200D01*
G01X1778771Y960302D01*
X1798779D01*
G03X1798895Y960339I0J200D01*
G01X1798914Y960352D01*
X1799013Y960393D01*
G03X1799078Y960436I-76J185D01*
G01X1800251Y961609D01*
G03X1800310Y961751I-141J142D01*
G01Y975724D01*
G02X1800369Y975866I200J0D01*
G01X1800504Y976001D01*
G02X1800646Y976060I142J-141D01*
G01X1805380D01*
G02X1805522Y976001I0J-200D01*
G01X1806154Y975369D01*
G02X1806213Y975227I-141J-142D01*
G01Y971793D01*
G03X1806272Y971651I200J0D01*
G01X1807004Y970919D01*
G03X1807146Y970860I142J141D01*
G01X1809463D01*
G02X1809663Y970660I0J-200D01*
G01Y960110D01*
G02X1809604Y959968I-200J0D01*
G01X1796220Y946584D01*
G02X1796078Y946525I-142J141D01*
G01X1736396D01*
X1715991Y966930D01*
Y984037D01*
X1700657Y999371D01*
X1669258D01*
G03X1669116Y999430I-142J-141D01*
G01X1533464D01*
X1532909Y999985D01*
X1485788D01*
X1485567Y1000206D01*
X1485538Y1000234D01*
X1485508Y1000308D01*
Y1005636D01*
G02X1485567Y1005778I200J0D01*
G01X1486240Y1006451D01*
G02X1486382Y1006510I142J-141D01*
G01X1517661D01*
G03X1517803Y1006569I0J200D01*
G01X1521465Y1010231D01*
G03X1521524Y1010373I-141J142D01*
G01Y1032946D01*
G03X1521465Y1033088I-200J0D01*
G01X1519648Y1034905D01*
G03X1519506Y1034964I-142J-141D01*
G01X1505155D01*
G02X1505135Y1034965I0J200D01*
G02X1504976Y1035076I21J199D01*
G03X1503572Y1036041I-1404J-539D01*
G03X1502187Y1035121I0J-1503D01*
G01X1502178Y1035100D01*
X1502152Y1035063D01*
X1502036Y1034961D01*
X1502006Y1034948D01*
G03X1501941Y1034905I76J-185D01*
G01X1500692Y1033656D01*
G03X1500633Y1033514I141J-142D01*
G01Y1026957D01*
X1500603Y1026883D01*
X1500574Y1026855D01*
X1500427Y1026708D01*
G02X1500285Y1026649I-142J141D01*
G01X1486219D01*
G02X1486077Y1026708I0J200D01*
G01X1484940Y1027845D01*
X1484911Y1027873D01*
X1484881Y1027947D01*
Y1034260D01*
G02X1484940Y1034402I200J0D01*
G01X1485628Y1035090D01*
X1485708Y1035120D01*
X1485753Y1035117D01*
G03X1487982Y1035038I2229J31418D01*
G01X1487988D01*
X1487991D01*
G03X1516107Y1052339I0J31496D01*
G02X1516757Y1052431I357J-181D01*
G03X1517855Y1051954I1098J1025D01*
G03X1519358Y1053457I0J1503D01*
G03X1519246Y1054026I-1503J0D01*
G02X1519616Y1054577I370J151D01*
G37*
G36*
G01X1485537Y1025648D02*
X1500510D01*
G02X1500651Y1025589I-1J-200D01*
G01X1500686Y1025554D01*
G02X1500745Y1025412I-141J-142D01*
G01Y1020770D01*
X1500720Y1020746D01*
X1492185D01*
X1492161Y1020720D01*
X1485970D01*
G03X1485829Y1020662I0J-200D01*
G01X1485822Y1020655D01*
X1485427D01*
G02X1485285Y1020714I0J200D01*
G01X1485082Y1020917D01*
G02X1485023Y1021059I141J142D01*
G01Y1024735D01*
X1485024D01*
Y1025134D01*
G02X1485083Y1025276I200J0D01*
G01X1485396Y1025589D01*
G02X1485537Y1025648I142J-141D01*
G37*
G36*
G01X1492612Y1019744D02*
X1500415D01*
G02X1500557Y1019685I0J-200D01*
G01X1500574Y1019668D01*
G02X1500633Y1019526I-141J-142D01*
G01Y1014397D01*
G02X1500574Y1014255I-200J0D01*
G01X1500427Y1014108D01*
G02X1500285Y1014049I-142J141D01*
G01X1485856D01*
G02X1485714Y1014108I0J200D01*
G01X1485130Y1014692D01*
G02X1485071Y1014834I141J142D01*
G01Y1018405D01*
G02X1485130Y1018547I200J0D01*
G01X1486243Y1019660D01*
G02X1486385Y1019719I142J-141D01*
G01X1492588D01*
X1492612Y1019744D01*
G37*
G36*
G01X1491797Y1112589D02*
X1501913D01*
G02X1502055Y1112530I0J-200D01*
G01X1502543Y1112042D01*
G02X1502602Y1111900I-141J-142D01*
G01Y1104909D01*
G02X1502543Y1104767I-200J0D01*
G01X1502007Y1104231D01*
G02X1501865Y1104172I-142J141D01*
G01X1495739D01*
G02X1495597Y1104231I0J200D01*
G01X1495378Y1104450D01*
G02X1495319Y1104592I141J142D01*
G01Y1106143D01*
G03X1495260Y1106285I-200J0D01*
G01X1495160Y1106385D01*
G03X1495018Y1106444I-142J-141D01*
G01X1491834D01*
G02X1491692Y1106503I0J200D01*
G01X1491341Y1106854D01*
G02X1491282Y1106996I141J142D01*
G01Y1112075D01*
G02X1491341Y1112217I200J0D01*
G01X1491655Y1112531D01*
G02X1491797Y1112589I141J-142D01*
G37*
G36*
G01X1491042Y1104873D02*
X1493833D01*
G02X1493975Y1104815I1J-200D01*
G01X1494227Y1104563D01*
G02X1494286Y1104421I-141J-142D01*
G01Y1103859D01*
G03X1494345Y1103717I200J0D01*
G01X1494528Y1103534D01*
G03X1494670Y1103475I142J141D01*
G01X1494854D01*
G02X1494995Y1103416I-1J-200D01*
G01X1495183Y1103229D01*
G03X1495324Y1103170I142J141D01*
G01X1499973D01*
G02X1500173Y1102970I0J-200D01*
G01Y1101540D01*
G02X1500114Y1101398I-200J0D01*
G01X1500003Y1101287D01*
G02X1499861Y1101228I-142J141D01*
G01X1491386D01*
G02X1491244Y1101287I0J200D01*
G01X1490697Y1101834D01*
G02X1490638Y1101976I141J142D01*
G01Y1104469D01*
G02X1490697Y1104611I200J0D01*
G01X1490900Y1104814D01*
G02X1491042Y1104873I142J-141D01*
G37*
G36*
G01X1491797Y1125189D02*
X1501913D01*
G02X1502055Y1125130I0J-200D01*
G01X1502507Y1124678D01*
G02X1502566Y1124537I-141J-142D01*
G01Y1117472D01*
G02X1502507Y1117331I-200J1D01*
G01X1502007Y1116831D01*
G02X1501865Y1116772I-142J141D01*
G01X1500937D01*
G02X1500795Y1116831I0J200D01*
G01X1500372Y1117254D01*
G03X1500230Y1117313I-142J-141D01*
G01X1497315D01*
G03X1497173Y1117254I0J-200D01*
G01X1497054Y1117135D01*
G02X1496913Y1117076I-142J141D01*
G01X1495394D01*
X1495321Y1117107D01*
X1495319Y1117109D01*
Y1118743D01*
G03X1495260Y1118885I-200J0D01*
G01X1495160Y1118985D01*
G03X1495018Y1119044I-142J-141D01*
G01X1491834D01*
G02X1491692Y1119103I0J200D01*
G01X1491341Y1119454D01*
G02X1491282Y1119596I141J142D01*
G01Y1124675D01*
G02X1491341Y1124817I200J0D01*
G01X1491655Y1125131D01*
G02X1491797Y1125189I141J-142D01*
G37*
G36*
G01X1491042Y1117473D02*
X1493833D01*
G02X1493975Y1117415I1J-200D01*
G01X1494227Y1117163D01*
G02X1494286Y1117021I-141J-142D01*
G01Y1116459D01*
G03X1494345Y1116317I200J0D01*
G01X1494528Y1116134D01*
G03X1494670Y1116075I142J141D01*
G01X1499876D01*
G02X1500018Y1116016I0J-200D01*
G01X1500114Y1115920D01*
G02X1500173Y1115778I-141J-142D01*
G01Y1114140D01*
G02X1500114Y1113998I-200J0D01*
G01X1500003Y1113887D01*
G02X1499861Y1113828I-142J141D01*
G01X1491386D01*
G02X1491244Y1113887I0J200D01*
G01X1490697Y1114434D01*
G02X1490638Y1114576I141J142D01*
G01Y1117069D01*
G02X1490697Y1117211I200J0D01*
G01X1490900Y1117414D01*
G02X1491042Y1117473I142J-141D01*
G37*
G36*
G01X1491797Y1137789D02*
X1501913D01*
G02X1502055Y1137730I0J-200D01*
G01X1502507Y1137278D01*
G02X1502566Y1137137I-141J-142D01*
G01Y1130072D01*
G02X1502507Y1129931I-200J1D01*
G01X1502007Y1129431D01*
G02X1501865Y1129372I-142J141D01*
G01X1500937D01*
G02X1500795Y1129431I0J200D01*
G01X1500372Y1129854D01*
G03X1500230Y1129913I-142J-141D01*
G01X1497315D01*
G03X1497173Y1129854I0J-200D01*
G01X1497054Y1129735D01*
G02X1496913Y1129676I-142J141D01*
G01X1495394D01*
X1495321Y1129707D01*
X1495319Y1129709D01*
Y1131343D01*
G03X1495260Y1131485I-200J0D01*
G01X1495160Y1131585D01*
G03X1495018Y1131644I-142J-141D01*
G01X1491834D01*
G02X1491692Y1131703I0J200D01*
G01X1491341Y1132054D01*
G02X1491282Y1132196I141J142D01*
G01Y1137275D01*
G02X1491341Y1137417I200J0D01*
G01X1491655Y1137731D01*
G02X1491797Y1137789I141J-142D01*
G37*
G36*
G01X1491042Y1142673D02*
X1493833D01*
G02X1493975Y1142615I1J-200D01*
G01X1494227Y1142363D01*
G02X1494286Y1142221I-141J-142D01*
G01Y1141659D01*
G03X1494345Y1141517I200J0D01*
G01X1494528Y1141334D01*
G03X1494670Y1141275I142J141D01*
G01X1499876D01*
G02X1500018Y1141216I0J-200D01*
G01X1500114Y1141120D01*
G02X1500173Y1140978I-141J-142D01*
G01Y1139340D01*
G02X1500114Y1139198I-200J0D01*
G01X1500003Y1139087D01*
G02X1499861Y1139028I-142J141D01*
G01X1491386D01*
G02X1491244Y1139087I0J200D01*
G01X1490697Y1139634D01*
G02X1490638Y1139776I141J142D01*
G01Y1142269D01*
G02X1490697Y1142411I200J0D01*
G01X1490900Y1142614D01*
G02X1491042Y1142673I142J-141D01*
G37*
G36*
G01Y1130073D02*
X1493833D01*
G02X1493975Y1130015I1J-200D01*
G01X1494227Y1129763D01*
G02X1494286Y1129621I-141J-142D01*
G01Y1129059D01*
G03X1494345Y1128917I200J0D01*
G01X1494528Y1128734D01*
G03X1494670Y1128675I142J141D01*
G01X1499876D01*
G02X1500018Y1128616I0J-200D01*
G01X1500114Y1128520D01*
G02X1500173Y1128378I-141J-142D01*
G01Y1126740D01*
G02X1500114Y1126598I-200J0D01*
G01X1500003Y1126487D01*
G02X1499861Y1126428I-142J141D01*
G01X1491386D01*
G02X1491244Y1126487I0J200D01*
G01X1490697Y1127034D01*
G02X1490638Y1127176I141J142D01*
G01Y1129669D01*
G02X1490697Y1129811I200J0D01*
G01X1490900Y1130014D01*
G02X1491042Y1130073I142J-141D01*
G37*
G36*
G01X1491797Y1162989D02*
X1501913D01*
G02X1502055Y1162930I0J-200D01*
G01X1502507Y1162478D01*
G02X1502566Y1162337I-141J-142D01*
G01Y1155272D01*
G02X1502507Y1155131I-200J1D01*
G01X1502007Y1154631D01*
G02X1501865Y1154572I-142J141D01*
G01X1500937D01*
G02X1500795Y1154631I0J200D01*
G01X1500372Y1155054D01*
G03X1500230Y1155113I-142J-141D01*
G01X1497315D01*
G03X1497173Y1155054I0J-200D01*
G01X1497054Y1154935D01*
G02X1496913Y1154876I-142J141D01*
G01X1495394D01*
X1495321Y1154907D01*
X1495319Y1154909D01*
Y1156543D01*
G03X1495260Y1156685I-200J0D01*
G01X1495160Y1156785D01*
G03X1495018Y1156844I-142J-141D01*
G01X1491834D01*
G02X1491692Y1156903I0J200D01*
G01X1491341Y1157254D01*
G02X1491282Y1157396I141J142D01*
G01Y1162475D01*
G02X1491341Y1162617I200J0D01*
G01X1491655Y1162931D01*
G02X1491797Y1162989I141J-142D01*
G37*
G36*
G01Y1150389D02*
X1501913D01*
G02X1502055Y1150330I0J-200D01*
G01X1502507Y1149878D01*
G02X1502566Y1149737I-141J-142D01*
G01Y1142672D01*
G02X1502507Y1142531I-200J1D01*
G01X1502007Y1142031D01*
G02X1501865Y1141972I-142J141D01*
G01X1500937D01*
G02X1500795Y1142031I0J200D01*
G01X1500372Y1142454D01*
G03X1500230Y1142513I-142J-141D01*
G01X1497315D01*
G03X1497173Y1142454I0J-200D01*
G01X1497054Y1142335D01*
G02X1496913Y1142276I-142J141D01*
G01X1495394D01*
X1495321Y1142307D01*
X1495319Y1142309D01*
Y1143943D01*
G03X1495260Y1144085I-200J0D01*
G01X1495160Y1144185D01*
G03X1495018Y1144244I-142J-141D01*
G01X1491834D01*
G02X1491692Y1144303I0J200D01*
G01X1491341Y1144654D01*
G02X1491282Y1144796I141J142D01*
G01Y1149875D01*
G02X1491341Y1150017I200J0D01*
G01X1491655Y1150331D01*
G02X1491797Y1150389I141J-142D01*
G37*
G36*
G01X1491042Y1155273D02*
X1493833D01*
G02X1493975Y1155215I1J-200D01*
G01X1494227Y1154963D01*
G02X1494286Y1154821I-141J-142D01*
G01Y1154259D01*
G03X1494345Y1154117I200J0D01*
G01X1494528Y1153934D01*
G03X1494670Y1153875I142J141D01*
G01X1499876D01*
G02X1500018Y1153816I0J-200D01*
G01X1500114Y1153720D01*
G02X1500173Y1153578I-141J-142D01*
G01Y1151940D01*
G02X1500114Y1151798I-200J0D01*
G01X1500003Y1151687D01*
G02X1499861Y1151628I-142J141D01*
G01X1491386D01*
G02X1491244Y1151687I0J200D01*
G01X1490697Y1152234D01*
G02X1490638Y1152376I141J142D01*
G01Y1154869D01*
G02X1490697Y1155011I200J0D01*
G01X1490900Y1155214D01*
G02X1491042Y1155273I142J-141D01*
G37*
G36*
G01X1491797Y1175589D02*
X1501913D01*
G02X1502055Y1175530I0J-200D01*
G01X1502543Y1175042D01*
G02X1502602Y1174900I-141J-142D01*
G01Y1167909D01*
G02X1502543Y1167767I-200J0D01*
G01X1502007Y1167231D01*
G02X1501865Y1167172I-142J141D01*
G01X1500937D01*
G02X1500795Y1167231I0J200D01*
G01X1500372Y1167654D01*
G03X1500230Y1167713I-142J-141D01*
G01X1497315D01*
G03X1497173Y1167654I0J-200D01*
G01X1496750Y1167231D01*
G02X1496608Y1167172I-142J141D01*
G01X1495739D01*
G02X1495597Y1167231I0J200D01*
G01X1495378Y1167450D01*
G02X1495319Y1167592I141J142D01*
G01Y1169143D01*
G03X1495260Y1169285I-200J0D01*
G01X1495160Y1169385D01*
G03X1495018Y1169444I-142J-141D01*
G01X1491834D01*
G02X1491692Y1169503I0J200D01*
G01X1491341Y1169854D01*
G02X1491282Y1169996I141J142D01*
G01Y1175075D01*
G02X1491341Y1175217I200J0D01*
G01X1491655Y1175531D01*
G02X1491797Y1175589I141J-142D01*
G37*
G36*
G01X1491042Y1167873D02*
X1493833D01*
G02X1493975Y1167815I1J-200D01*
G01X1494227Y1167563D01*
G02X1494286Y1167421I-141J-142D01*
G01Y1166859D01*
G03X1494345Y1166717I200J0D01*
G01X1494528Y1166534D01*
G03X1494670Y1166475I142J141D01*
G01X1494854D01*
G02X1494995Y1166416I-1J-200D01*
G01X1495183Y1166229D01*
G03X1495324Y1166170I142J141D01*
G01X1497023D01*
G03X1497164Y1166229I-1J200D01*
G01X1497352Y1166416D01*
G02X1497493Y1166475I142J-141D01*
G01X1499876D01*
G02X1500018Y1166416I0J-200D01*
G01X1500114Y1166320D01*
G02X1500173Y1166178I-141J-142D01*
G01Y1164540D01*
G02X1500114Y1164398I-200J0D01*
G01X1500003Y1164287D01*
G02X1499861Y1164228I-142J141D01*
G01X1491386D01*
G02X1491244Y1164287I0J200D01*
G01X1490697Y1164834D01*
G02X1490638Y1164976I141J142D01*
G01Y1167469D01*
G02X1490697Y1167611I200J0D01*
G01X1490900Y1167814D01*
G02X1491042Y1167873I142J-141D01*
G37*
G36*
G01X1491797Y1188189D02*
X1501913D01*
G02X1502055Y1188130I0J-200D01*
G01X1502507Y1187678D01*
G02X1502566Y1187537I-141J-142D01*
G01Y1180472D01*
G02X1502507Y1180331I-200J1D01*
G01X1502007Y1179831D01*
G02X1501865Y1179772I-142J141D01*
G01X1500937D01*
G02X1500795Y1179831I0J200D01*
G01X1500372Y1180254D01*
G03X1500230Y1180313I-142J-141D01*
G01X1497315D01*
G03X1497173Y1180254I0J-200D01*
G01X1497054Y1180135D01*
G02X1496913Y1180076I-142J141D01*
G01X1495394D01*
X1495321Y1180107D01*
X1495319Y1180109D01*
Y1181743D01*
G03X1495260Y1181885I-200J0D01*
G01X1495160Y1181985D01*
G03X1495018Y1182044I-142J-141D01*
G01X1491834D01*
G02X1491692Y1182103I0J200D01*
G01X1491341Y1182454D01*
G02X1491282Y1182596I141J142D01*
G01Y1187675D01*
G02X1491341Y1187817I200J0D01*
G01X1491655Y1188131D01*
G02X1491797Y1188189I141J-142D01*
G37*
G36*
G01X1491042Y1180473D02*
X1493833D01*
G02X1493975Y1180415I1J-200D01*
G01X1494227Y1180163D01*
G02X1494286Y1180021I-141J-142D01*
G01Y1179459D01*
G03X1494345Y1179317I200J0D01*
G01X1494528Y1179134D01*
G03X1494670Y1179075I142J141D01*
G01X1499876D01*
G02X1500018Y1179016I0J-200D01*
G01X1500114Y1178920D01*
G02X1500173Y1178778I-141J-142D01*
G01Y1177140D01*
G02X1500114Y1176998I-200J0D01*
G01X1500003Y1176887D01*
G02X1499861Y1176828I-142J141D01*
G01X1491386D01*
G02X1491244Y1176887I0J200D01*
G01X1490697Y1177434D01*
G02X1490638Y1177576I141J142D01*
G01Y1180069D01*
G02X1490697Y1180211I200J0D01*
G01X1490900Y1180414D01*
G02X1491042Y1180473I142J-141D01*
G37*
G36*
G01X1513215Y86514D02*
X1521930D01*
X1522283Y86161D01*
Y73377D01*
X1521837Y72931D01*
X1513439D01*
X1513104Y73266D01*
Y86403D01*
X1513215Y86514D01*
G37*
G36*
G01X1512781Y600514D02*
X1522184D01*
X1522612Y600086D01*
Y589755D01*
X1523716Y588651D01*
X1526513D01*
X1527099Y588065D01*
Y584209D01*
X1526738Y583848D01*
X1512914D01*
X1512260Y584502D01*
Y599993D01*
X1512781Y600514D01*
G37*
G36*
G01X1502688Y1012136D02*
X1505479D01*
G02X1505621Y1012078I1J-200D01*
G01X1505873Y1011826D01*
G02X1505932Y1011684I-141J-142D01*
G01Y1011122D01*
G03X1505991Y1010980I200J0D01*
G01X1506174Y1010797D01*
G03X1506316Y1010738I142J141D01*
G01X1506500D01*
G02X1506641Y1010679I-1J-200D01*
G01X1506829Y1010492D01*
G03X1506970Y1010434I141J142D01*
G01X1511619D01*
G02X1511819Y1010234I0J-200D01*
G01Y1008803D01*
G02X1511760Y1008661I-200J0D01*
G01X1511649Y1008550D01*
G02X1511507Y1008491I-142J141D01*
G01X1503032D01*
G02X1502890Y1008550I0J200D01*
G01X1502343Y1009097D01*
G02X1502284Y1009239I141J142D01*
G01Y1011732D01*
G02X1502343Y1011874I200J0D01*
G01X1502546Y1012077D01*
G02X1502688Y1012136I142J-141D01*
G37*
G36*
G01X1503443Y1019852D02*
X1513559D01*
G02X1513701Y1019793I0J-200D01*
G01X1514189Y1019305D01*
G02X1514248Y1019163I-141J-142D01*
G01Y1012172D01*
G02X1514189Y1012030I-200J0D01*
G01X1513653Y1011494D01*
G02X1513511Y1011435I-142J141D01*
G01X1507385D01*
G02X1507243Y1011494I0J200D01*
G01X1507024Y1011713D01*
G02X1506965Y1011855I141J142D01*
G01Y1013406D01*
G03X1506906Y1013548I-200J0D01*
G01X1506806Y1013648D01*
G03X1506664Y1013707I-142J-141D01*
G01X1503480D01*
G02X1503338Y1013766I0J200D01*
G01X1502987Y1014117D01*
G02X1502928Y1014259I141J142D01*
G01Y1019338D01*
G02X1502987Y1019480I200J0D01*
G01X1503301Y1019794D01*
G02X1503443Y1019852I141J-142D01*
G37*
G36*
G01Y1032452D02*
X1513559D01*
G02X1513701Y1032393I0J-200D01*
G01X1514189Y1031905D01*
G02X1514248Y1031763I-141J-142D01*
G01Y1024772D01*
G02X1514189Y1024630I-200J0D01*
G01X1513653Y1024094D01*
G02X1513511Y1024035I-142J141D01*
G01X1507385D01*
G02X1507243Y1024094I0J200D01*
G01X1507024Y1024313D01*
G02X1506965Y1024455I141J142D01*
G01Y1026006D01*
G03X1506906Y1026148I-200J0D01*
G01X1506806Y1026248D01*
G03X1506664Y1026307I-142J-141D01*
G01X1503480D01*
G02X1503338Y1026366I0J200D01*
G01X1502987Y1026717D01*
G02X1502928Y1026859I141J142D01*
G01Y1031938D01*
G02X1502987Y1032080I200J0D01*
G01X1503301Y1032394D01*
G02X1503443Y1032452I141J-142D01*
G37*
G36*
G01X1502688Y1024736D02*
X1505479D01*
G02X1505621Y1024678I1J-200D01*
G01X1505873Y1024426D01*
G02X1505932Y1024284I-141J-142D01*
G01Y1023722D01*
G03X1505991Y1023580I200J0D01*
G01X1506174Y1023397D01*
G03X1506316Y1023338I142J141D01*
G01X1506500D01*
G02X1506641Y1023279I-1J-200D01*
G01X1506829Y1023092D01*
G03X1506970Y1023034I141J142D01*
G01X1511619D01*
G02X1511819Y1022834I0J-200D01*
G01Y1021403D01*
G02X1511760Y1021261I-200J0D01*
G01X1511649Y1021150D01*
G02X1511507Y1021091I-142J141D01*
G01X1503032D01*
G02X1502890Y1021150I0J200D01*
G01X1502343Y1021697D01*
G02X1502284Y1021839I141J142D01*
G01Y1024332D01*
G02X1502343Y1024474I200J0D01*
G01X1502546Y1024677D01*
G02X1502688Y1024736I142J-141D01*
G37*
G36*
G01X1503971Y1188245D02*
X1506259D01*
X1506798Y1187706D01*
Y1166474D01*
X1507149Y1166123D01*
X1507975Y1165297D01*
Y1104789D01*
X1507591Y1104405D01*
G02X1507569Y1104386I-141J141D01*
G02X1507449Y1104346I-120J160D01*
G01X1504224D01*
G02X1504104Y1104386I0J200D01*
G02X1504082Y1104405I119J160D01*
G01X1503662Y1104825D01*
G02X1503604Y1104966I142J141D01*
G01Y1112278D01*
G02X1503635Y1112385I200J0D01*
G01Y1117452D01*
X1503626Y1117461D01*
G02X1503607Y1117483I141J141D01*
G02X1503567Y1117603I160J120D01*
G01Y1124841D01*
G02X1503607Y1124961I200J0D01*
G02X1503626Y1124983I160J-119D01*
G01X1503635Y1124992D01*
Y1130052D01*
X1503626Y1130061D01*
G02X1503607Y1130083I141J141D01*
G02X1503567Y1130203I160J120D01*
G01Y1137441D01*
G02X1503607Y1137561I200J0D01*
G02X1503626Y1137583I160J-119D01*
G01X1503635Y1137592D01*
Y1142652D01*
X1503626Y1142661D01*
G02X1503607Y1142683I141J141D01*
G02X1503567Y1142803I160J120D01*
G01Y1150041D01*
G02X1503607Y1150161I200J0D01*
G02X1503626Y1150183I160J-119D01*
G01X1503635Y1150192D01*
Y1155252D01*
X1503626Y1155261D01*
G02X1503607Y1155283I141J141D01*
G02X1503567Y1155403I160J120D01*
G01Y1162641D01*
G02X1503607Y1162761I200J0D01*
G02X1503626Y1162783I160J-119D01*
G01X1503635Y1162792D01*
Y1167859D01*
G02X1503604Y1167966I169J107D01*
G01Y1175278D01*
G02X1503635Y1175385I200J0D01*
G01Y1178989D01*
X1503925Y1179279D01*
Y1180161D01*
X1503902Y1180184D01*
Y1183102D01*
X1503567Y1183437D01*
Y1187841D01*
G02X1503607Y1187961I200J0D01*
G02X1503626Y1187983I160J-119D01*
G01X1503829Y1188186D01*
G02X1503851Y1188205I141J-141D01*
G02X1503971Y1188245I120J-160D01*
G37*
G36*
G01X1512368Y1170570D02*
G03I-400J0D01*
G37*
G36*
G01Y1178050D02*
G03I-400J0D01*
G37*
G36*
G01X1512997Y1198622D02*
G03I-400J0D01*
G37*
G36*
G01Y1191142D02*
G03I-400J0D01*
G37*
G36*
G01Y1221063D02*
G03I-400J0D01*
G37*
G36*
G01Y1213583D02*
G03I-400J0D01*
G37*
G36*
G01Y1206103D02*
G03I-400J0D01*
G37*
G36*
G01Y1228542D02*
G03I-400J0D01*
G37*
G36*
G01X1512996Y1239763D02*
G03I-400J0D01*
G37*
G36*
G01Y1247242D02*
G03I-400J0D01*
G37*
G36*
G01X1515322Y-44536D02*
G03I-557J0D01*
G37*
G36*
G01Y-39580D02*
G03I-557J0D01*
G37*
G36*
G01Y-29580D02*
G03I-557J0D01*
G37*
G36*
G01Y-34536D02*
G03I-557J0D01*
G37*
G36*
G01X1529141Y176789D02*
X1543568D01*
X1544331Y176026D01*
Y174795D01*
X1545094Y174032D01*
X1548202D01*
X1548789Y173445D01*
Y161423D01*
X1548085Y160719D01*
X1529786D01*
Y160720D01*
X1527790D01*
X1527029Y161481D01*
Y176203D01*
X1527615Y176789D01*
X1529141D01*
G37*
G36*
G01X1556060Y219609D02*
X1557702D01*
X1558094Y219217D01*
Y210795D01*
X1557886Y210587D01*
X1556582D01*
X1556530Y210639D01*
X1556138D01*
X1556127Y210628D01*
X1555371D01*
X1555017Y210274D01*
Y209518D01*
Y204802D01*
X1544548Y194333D01*
Y189191D01*
X1548185Y185554D01*
X1552950D01*
X1553498Y185006D01*
Y183690D01*
X1554493Y182695D01*
X1556427D01*
X1556814Y182308D01*
X1559028D01*
X1559206Y182130D01*
Y181714D01*
X1558893Y181401D01*
X1555683D01*
X1555282Y181000D01*
X1555237D01*
X1553944Y179707D01*
X1528385D01*
X1527073Y181019D01*
Y216698D01*
X1527976Y217601D01*
X1554052D01*
X1556060Y219609D01*
G37*
G36*
G01X1554420Y234621D02*
Y221520D01*
X1552619Y219719D01*
X1551523Y218623D01*
X1528682D01*
X1526954Y220351D01*
Y252516D01*
X1528265Y253827D01*
X1550505D01*
X1554420Y249912D01*
Y234621D01*
G37*
G36*
G01X1529300Y277007D02*
X1536729D01*
X1549180D01*
X1551037Y275150D01*
X1553616D01*
X1553891Y274875D01*
Y272398D01*
X1553341Y271848D01*
X1550797D01*
X1550693Y271952D01*
X1547013Y268272D01*
Y265554D01*
X1543815Y262356D01*
X1529231D01*
X1528543Y263044D01*
Y276250D01*
X1529300Y277007D01*
G37*
G36*
G01X1532293Y299467D02*
X1542577D01*
X1547013Y295031D01*
Y278899D01*
X1546772Y278658D01*
X1530022D01*
X1528750Y279930D01*
Y295924D01*
X1532293Y299467D01*
G37*
G36*
G01X1617932Y747968D02*
Y749194D01*
Y749203D01*
G02X1617959Y749295I201J-9D01*
G02X1618035Y749368I172J-103D01*
G01X1620130D01*
G02X1620170Y749338I-99J-174D01*
G03X1621700Y748628I1529J1292D01*
G03X1623230Y749338I1J2002D01*
G02X1623270Y749368I139J-144D01*
G01X1625631D01*
G02X1625747Y749331I0J-200D01*
G01X1625757Y749324D01*
X1625785Y749255D01*
G02X1625787Y749251I-177J-91D01*
G03X1626255Y748928I468J178D01*
G01X1626813D01*
G02X1626988Y748823I-1J-200D01*
G01X1626996Y748803D01*
G02X1627008Y748687I-184J-78D01*
G01X1627003Y748661D01*
X1626975Y748609D01*
X1626082Y747717D01*
G03X1625642Y747028I1345J-1344D01*
G03X1625526Y746372I1785J-654D01*
G01Y744317D01*
G03X1627427Y742416I1901J0D01*
G01X1627429D01*
G03X1628804Y743005I-1J1901D01*
G02X1628859Y743046I145J-137D01*
G02X1628950Y743068I91J-178D01*
G01X1629836D01*
X1629846D01*
G02X1630036Y742868I-11J-200D01*
G01Y742832D01*
X1631089D01*
G03X1631948Y743490I0J890D01*
G01X1631956Y743519D01*
G02X1632023Y743622I193J-52D01*
G01X1632044Y743638D01*
X1633000D01*
G02X1633033Y743614I-101J-173D01*
G01X1633136Y743517D01*
X1633138D01*
X1633239Y743420D01*
G02X1633283Y743359I-137J-145D01*
G01X1633299Y743325D01*
X1633301Y743286D01*
G03X1634008Y741870I1999J114D01*
G02X1634038Y741830I-144J-139D01*
G01Y740139D01*
G02X1633874Y740038I-174J99D01*
G01X1633341D01*
G03X1632862Y739685I0J-501D01*
G02X1632860Y739679I-191J60D01*
G01X1632857Y739670D01*
G02X1632788Y739575I-189J65D01*
G01X1632771Y739562D01*
X1632200D01*
G03X1631308Y739192I1J-1262D01*
G01X1630808Y738692D01*
G03X1630438Y737800I892J-893D01*
G01Y736000D01*
G03X1630808Y735108I1262J1D01*
G01X1631425Y734491D01*
G03X1632316Y734122I891J892D01*
G01X1633142D01*
X1633174Y734110D01*
G03X1633341Y734082I165J473D01*
G01X1635741D01*
G03X1636242Y734583I0J501D01*
G01Y736184D01*
G03X1636147Y736477I-501J-1D01*
G01X1636146Y736478D01*
G02X1636109Y736592I163J116D01*
G01Y736725D01*
Y736727D01*
G02X1636146Y736841I200J-2D01*
G01X1636147Y736842D01*
G03X1636242Y737135I-406J294D01*
G01Y738224D01*
G02X1636246Y738261I200J-3D01*
G03X1636562Y739095I-946J835D01*
G01Y741830D01*
G02X1636592Y741870I174J-99D01*
G03X1637302Y743399I-1292J1529D01*
G01Y743400D01*
G03X1635301Y745402I-2002J0D01*
G01X1635299D01*
G03X1635172Y745397I15J-2002D01*
G01X1635168D01*
X1635105Y745394D01*
X1635081Y745403D01*
X1634692Y745792D01*
G03X1633800Y746162I-893J-892D01*
G01X1631160D01*
G03X1630332Y745852I0J-1261D01*
G02X1630200Y745802I-132J150D01*
G01X1630131D01*
G02X1629951Y745914I0J200D01*
G01X1629901Y746017D01*
G02X1629915Y746218I179J88D01*
G03X1630245Y747288I-1572J1071D01*
G03X1629274Y748947I-1903J0D01*
G01X1629259Y748955D01*
G02X1629186Y749047I113J165D01*
G01X1629165Y749105D01*
X1629142Y749169D01*
G02X1629130Y749238I188J68D01*
G01X1629137Y749290D01*
X1629140Y749302D01*
G03X1629156Y749430I-485J126D01*
G01Y751831D01*
G03X1629061Y752124I-501J-1D01*
G01X1629060Y752125D01*
G02X1629023Y752239I163J116D01*
G01Y752372D01*
Y752374D01*
G02X1629060Y752488I200J-2D01*
G01X1629061Y752489D01*
G03X1629156Y752782I-406J294D01*
G01Y754383D01*
G03X1628655Y754884I-501J0D01*
G01X1626255D01*
G03X1626088Y754856I-2J-501D01*
G01X1626056Y754844D01*
X1625123D01*
G02X1624981Y754903I0J200D01*
G01X1622289Y757595D01*
G03X1621398Y757964I-891J-892D01*
G01X1611831D01*
G02X1611689Y758023I0J200D01*
G01X1605527Y764186D01*
G02X1605468Y764328I141J142D01*
G01Y791149D01*
G02X1605591Y791333I200J0D01*
G01X1605647Y791357D01*
X1605766Y791333D01*
X1606091Y791008D01*
G03X1606983Y790638I893J892D01*
G01X1609094D01*
G02X1609236Y790580I1J-200D01*
G01X1609474Y790342D01*
G02X1609480Y790260I-192J-55D01*
G01X1609306Y790086D01*
X1609289Y790081D01*
X1609191Y790103D01*
G03X1608750Y790152I-440J-1953D01*
G01X1608736D01*
G03X1606748Y788151I14J-2002D01*
G01Y788149D01*
G03X1606753Y788022I2002J15D01*
G01Y788018D01*
X1606756Y787955D01*
X1606747Y787931D01*
X1606608Y787792D01*
G03X1606238Y786900I892J-893D01*
G01Y784498D01*
G03X1606237Y784461I1262J-53D01*
G01Y784459D01*
G03X1606607Y783567I1263J1D01*
G01X1606990Y783185D01*
G02X1606998Y783131I-192J-56D01*
G01Y783053D01*
X1607115Y782936D01*
X1607116D01*
X1607175Y782877D01*
G02X1607234Y782735I-141J-142D01*
G01Y781068D01*
Y781058D01*
G02X1607034Y780868I-200J11D01*
G01X1606998D01*
Y779815D01*
G03X1607894Y778925I890J0D01*
G01Y778926D01*
X1609072D01*
Y778925D01*
G03X1609530Y779049I5J890D01*
G01X1609561Y779066D01*
X1610223D01*
G02X1610316Y778958I-95J-176D01*
G01X1610361Y778833D01*
X1610336Y778719D01*
X1610294Y778678D01*
G03X1610291Y778675I890J-894D01*
G01X1609186Y777570D01*
X1609151Y777561D01*
G03X1607998Y776100I349J-1461D01*
G03X1609500Y774598I1502J0D01*
G03X1610961Y775751I0J1502D01*
G01X1610970Y775786D01*
X1611647Y776463D01*
G02X1611789Y776522I142J-141D01*
G01X1614656D01*
G02X1614711Y776478I-95J-175D01*
G01X1614909Y776252D01*
G02X1614951Y776179I-148J-134D01*
G01X1614963Y776138D01*
X1614958Y776095D01*
G03X1614954Y776030I497J-63D01*
G01Y773715D01*
Y773713D01*
X1614953Y773630D01*
G03X1615230Y773182I501J0D01*
G03X1615232Y773180I142J140D01*
G03X1615275Y773162I215J454D01*
G02X1615281Y773160I-60J-191D01*
G01X1615294Y773154D01*
G02X1615383Y773083I-75J-185D01*
G01X1615394Y773067D01*
Y770958D01*
G02X1615375Y770874I-200J1D01*
G01X1615350Y770819D01*
X1615319Y770791D01*
G03Y767809I1336J-1491D01*
G01X1615350Y767781D01*
X1615375Y767726D01*
G02X1615394Y767642I-181J-85D01*
G01Y765841D01*
G02X1615378Y765763I-200J0D01*
G01X1615361Y765722D01*
X1615336Y765695D01*
G03X1615098Y765089I652J-606D01*
G01Y764236D01*
G03X1615298Y764036I200J0D01*
G01X1615334D01*
Y762864D01*
Y762863D01*
G02X1615229Y762688I-200J1D01*
G01X1613391D01*
G02X1613379Y762695I95J176D01*
G03X1612608Y762929I-806J-1268D01*
G01X1612554D01*
G03Y759925I19J-1502D01*
G01X1612575D01*
G03X1613379Y760159I-1J1502D01*
G02X1613391Y760166I107J-169D01*
G01X1615505D01*
X1615536Y760149D01*
G03X1615994Y760025I453J766D01*
G01Y760026D01*
X1617172D01*
Y760025D01*
G03X1618068Y760915I6J890D01*
G01Y761768D01*
G03X1617868Y761968I-200J0D01*
G01X1617832D01*
Y763836D01*
Y763846D01*
G02X1618032Y764036I200J-11D01*
G01X1618068D01*
Y765091D01*
G03X1617929Y765568I-890J-1D01*
G01X1617916Y765589D01*
Y767642D01*
G02X1617935Y767726I200J-1D01*
G01X1617960Y767781D01*
X1617991Y767809D01*
G03Y770791I-1336J1491D01*
G01X1617960Y770819D01*
X1617935Y770874D01*
G02X1617916Y770958I181J85D01*
G01Y773005D01*
G02X1617952Y773118I200J-1D01*
G01X1617961Y773132D01*
X1618029Y773160D01*
G02X1618035Y773162I66J-189D01*
G03X1618078Y773180I-172J472D01*
G03X1618080Y773182I-140J142D01*
G03X1618357Y773630I-224J448D01*
G01X1618356Y773742D01*
Y776031D01*
G03X1618261Y776324I-501J-1D01*
G01X1618260Y776325D01*
G02X1618223Y776439I163J116D01*
G01Y776572D01*
Y776574D01*
G02X1618260Y776688I200J-2D01*
G01X1618261Y776689D01*
G03X1618356Y776982I-406J294D01*
G01Y778583D01*
G03X1617855Y779084I-501J0D01*
G01X1615455D01*
G03X1615288Y779056I-2J-501D01*
G01X1615256Y779044D01*
X1613203D01*
G02X1613127Y779117I96J176D01*
G01X1612950Y779415D01*
G02X1612922Y779513I172J102D01*
G01X1612921Y779562D01*
X1612947Y779610D01*
G03X1613129Y780327I-1321J717D01*
G03X1611646Y781829I-1502J0D01*
G01X1611625D01*
G03X1610821Y781595I1J-1502D01*
G02X1610809Y781588I-107J169D01*
G01X1609837D01*
G02X1609732Y781763I95J176D01*
G01Y782736D01*
Y782746D01*
G02X1609932Y782936I200J-11D01*
G01X1609968D01*
Y783989D01*
G03X1609072Y784879I-890J0D01*
G01Y784878D01*
X1608913D01*
G02X1608861Y784885I0J200D01*
G01X1608821Y784925D01*
G02X1608762Y785067I141J142D01*
G01Y786054D01*
G02X1608786Y786088I175J-98D01*
G01X1608887Y786138D01*
G02X1608955Y786158I89J-179D01*
G03X1609536Y786309I-207J1991D01*
G03X1610280Y786858I-785J1842D01*
G02X1610320Y786888I139J-144D01*
G01X1611944D01*
G02X1612086Y786830I1J-200D01*
G01X1612278Y786638D01*
G03X1613170Y786268I893J892D01*
G01X1614631D01*
G02X1614747Y786231I0J-200D01*
G01X1614757Y786224D01*
X1614785Y786155D01*
G02X1614787Y786151I-177J-91D01*
G03X1615255Y785828I468J178D01*
G01X1617655D01*
G03X1618156Y786328I0J501D01*
G01Y788731D01*
G03X1618061Y789024I-501J-1D01*
G01X1618060Y789025D01*
G02X1618023Y789139I163J116D01*
G01Y789272D01*
Y789274D01*
G02X1618060Y789388I200J-2D01*
G01X1618061Y789389D01*
G03X1618156Y789682I-406J294D01*
G01Y791283D01*
G03X1617655Y791784I-501J0D01*
G01X1615255D01*
G03X1615088Y791756I-2J-501D01*
G01X1615056Y791744D01*
X1611723D01*
G02X1611581Y791803I0J200D01*
G01X1611516Y791868D01*
G02X1611457Y792010I141J142D01*
G01Y793225D01*
G02X1611516Y793367I200J0D01*
G01X1611746Y793596D01*
X1611820Y793625D01*
X1611873D01*
G03X1613375Y795127I0J1502D01*
G03X1611892Y796629I-1502J0D01*
G01X1611871D01*
G03X1611067Y796395I1J-1502D01*
G02X1611055Y796388I-107J169D01*
G01X1609737D01*
G02X1609632Y796563I95J176D01*
G01Y797536D01*
Y797546D01*
G02X1609832Y797736I200J-11D01*
G01X1609868D01*
Y798789D01*
G03X1609665Y799355I-890J0D01*
G02X1609644Y799386I154J127D01*
G01Y801668D01*
G02X1609689Y801794I200J0D01*
G01X1609710Y801820D01*
X1609804Y801839D01*
G03X1610930Y802508I-403J1961D01*
G02X1610970Y802538I139J-144D01*
G01X1611495D01*
G02X1611637Y802479I0J-200D01*
G01X1613379Y800738D01*
G03X1614271Y800368I893J892D01*
G01X1614331D01*
G02X1614447Y800331I0J-200D01*
G01X1614457Y800324D01*
X1614485Y800255D01*
G02X1614487Y800251I-177J-91D01*
G03X1614955Y799928I468J178D01*
G01X1617355D01*
G03X1617856Y800428I0J501D01*
G01Y802831D01*
G03X1617761Y803124I-501J-1D01*
G01X1617760Y803125D01*
G02X1617723Y803239I163J116D01*
G01Y803372D01*
Y803374D01*
G02X1617760Y803488I200J-2D01*
G01X1617761Y803489D01*
G03X1617856Y803782I-406J294D01*
G01Y805383D01*
G03X1617355Y805884I-501J0D01*
G01X1614955D01*
G03X1614788Y805856I-2J-501D01*
G01X1614756Y805844D01*
X1614623D01*
G02X1614481Y805903I0J200D01*
G01X1612759Y807625D01*
G03X1612411Y807871I-892J-892D01*
G01X1612363Y807894D01*
X1612324Y807926D01*
X1612313Y807941D01*
X1612252Y808309D01*
G02X1612257Y808397I197J33D01*
G01X1612565Y808705D01*
G03X1612752Y808944I-893J891D01*
G01X1612765Y808965D01*
X1614696Y810895D01*
G02X1614838Y810954I142J-141D01*
G01X1624069D01*
G02X1624150Y810867I-99J-174D01*
G01X1624295Y810510D01*
G02X1624305Y810393I-185J-75D01*
G01X1624301Y810372D01*
G03X1624213Y810292I804J-972D01*
G01X1623167Y809246D01*
G02X1623112Y809238I-56J192D01*
G01X1622041D01*
G03X1621607Y808988I0J-502D01*
G01X1621518Y808834D01*
X1621447Y808784D01*
X1621416Y808778D01*
G03X1620744Y808428I220J-1242D01*
G01X1620108Y807792D01*
G03X1619738Y806900I892J-893D01*
G01Y804800D01*
G03X1620108Y803908I1262J1D01*
G01X1620325Y803691D01*
G03X1621216Y803322I891J892D01*
G01X1621842D01*
X1621874Y803310D01*
G03X1622041Y803282I165J473D01*
G01X1624441D01*
G03X1624942Y803783I0J501D01*
G01Y805384D01*
G03X1624847Y805677I-501J-1D01*
G01X1624846Y805678D01*
G02X1624809Y805792I163J116D01*
G01Y805925D01*
Y805927D01*
G02X1624846Y806041I200J-2D01*
G01X1624847Y806042D01*
G03X1624942Y806335I-406J294D01*
G01Y807405D01*
G02X1624949Y807456I200J-1D01*
G02X1624950Y807461I197J-37D01*
G01X1625569Y808080D01*
G02X1625711Y808138I141J-142D01*
G01X1626830D01*
G02X1626870Y808108I-99J-174D01*
G03X1628399Y807398I1529J1292D01*
G01X1628400D01*
G03X1629785Y807954I0J2003D01*
G01X1629803Y807972D01*
G02X1629943Y808027I138J-145D01*
G01X1629988D01*
X1630079Y807936D01*
G02X1630138Y807794I-141J-142D01*
G01Y805704D01*
G02X1630121Y805679I-173J100D01*
G03X1629898Y805090I667J-589D01*
G01Y804236D01*
G03X1630098Y804036I200J0D01*
G01X1630134D01*
Y803528D01*
Y803518D01*
G02X1629944Y803328I-201J10D01*
G01X1628027D01*
G03Y799526I0J-1901D01*
G01X1631383D01*
G03X1633284Y801427I0J1901D01*
G01Y801429D01*
G03X1632695Y802804I-1901J-1D01*
G02X1632654Y802859I137J145D01*
G02X1632632Y802950I178J91D01*
G01Y803836D01*
Y803846D01*
G02X1632832Y804036I200J-11D01*
G01X1632868D01*
Y805090D01*
G03X1632670Y805649I-890J-1D01*
G02X1632662Y805662I167J111D01*
G01Y808400D01*
G03X1632292Y809292I-1262J-1D01*
G01X1631292Y810292D01*
G03X1630400Y810662I-893J-892D01*
G01X1629969D01*
X1629948Y810672D01*
X1629897Y810729D01*
G03X1628400Y811402I-1497J-1328D01*
G01X1628399D01*
G03X1626870Y810692I0J-2002D01*
G02X1626830Y810662I-139J144D01*
G01X1625961D01*
G02X1625880Y810749I99J174D01*
G01X1625735Y811106D01*
G02X1625725Y811223I185J75D01*
G01X1625729Y811244D01*
G03X1625817Y811324I-804J972D01*
G01X1628407Y813913D01*
G02X1628549Y813972I142J-141D01*
G01X1643287D01*
G02X1643429Y813913I0J-200D01*
G01X1645743Y811599D01*
G02X1645802Y811457I-141J-142D01*
G01Y703013D01*
G02X1645743Y702871I-200J0D01*
G01X1642119Y699247D01*
G02X1641977Y699188I-142J141D01*
G01X1629056D01*
G02X1628856Y699388I0J200D01*
G01Y701131D01*
G03X1628761Y701424I-501J-1D01*
G01X1628760Y701425D01*
G02X1628723Y701539I163J116D01*
G01Y701672D01*
Y701674D01*
G02X1628760Y701788I200J-2D01*
G01X1628761Y701789D01*
G03X1628856Y702082I-406J294D01*
G01Y703683D01*
G03X1628355Y704184I-501J0D01*
G01X1625955D01*
G03X1625788Y704156I-2J-501D01*
G01X1625756Y704144D01*
X1624223D01*
G02X1624081Y704203I0J200D01*
G01X1622070Y706214D01*
X1622061Y706249D01*
G03X1620600Y707402I-1461J-349D01*
G03X1619098Y705900I0J-1502D01*
G03X1620251Y704439I1502J0D01*
G01X1620286Y704430D01*
X1620579Y704137D01*
G02X1620638Y703995I-141J-142D01*
G01Y702205D01*
G02X1620584Y702068I-200J0D01*
G01X1620505Y701983D01*
G02X1620380Y701920I-147J136D01*
G03X1619070Y701222I219J-1990D01*
G02X1619030Y701192I-139J144D01*
G01X1615268D01*
G02X1615253Y701201I95J176D01*
G03X1614691Y701402I-563J-689D01*
G01X1613836D01*
G03X1613636Y701202I0J-200D01*
G01Y701166D01*
X1612464D01*
X1612463D01*
G02X1612288Y701271I1J200D01*
G01Y703521D01*
G02X1612347Y703663I200J0D01*
G01X1613114Y704430D01*
X1613149Y704439D01*
G03X1614302Y705900I-349J1461D01*
G03X1612800Y707402I-1502J0D01*
G03X1611339Y706249I0J-1502D01*
G01X1611330Y706214D01*
X1610135Y705019D01*
G03X1609766Y704128I892J-891D01*
G01Y703314D01*
G02X1609756Y703297I-177J93D01*
G01X1609582Y703224D01*
X1609523Y703218D01*
X1609493Y703224D01*
X1608965Y703752D01*
G03X1608823Y703811I-142J-141D01*
G01X1586872D01*
G02X1586781Y703833I0J200D01*
G02X1586731Y703869I90J178D01*
G01X1577270Y713330D01*
G03X1577128Y713389I-142J-141D01*
G01X1532839D01*
G02X1532764Y713403I-1J200D01*
G01X1532728Y713418D01*
X1526436Y719710D01*
G02X1526400Y719760I142J140D01*
G02X1526378Y719851I178J91D01*
G01Y825454D01*
G02X1526436Y825595I200J0D01*
G01X1526596Y825756D01*
G03X1527117Y826572I-1580J1583D01*
G03X1527252Y827337I-2102J765D01*
G01Y848459D01*
G02X1527256Y848497I200J-2D01*
G02X1527309Y848599I196J-37D01*
G01X1527759Y849049D01*
G02X1527901Y849108I142J-141D01*
G01X1569807D01*
G02X1569949Y849049I0J-200D01*
G01X1597653Y821344D01*
G02X1597712Y821202I-141J-142D01*
G01Y801289D01*
G03X1598082Y800397I1262J1D01*
G01X1601195Y797284D01*
G02X1601253Y797132I-142J-141D01*
G01Y797131D01*
G03X1601249Y797012I1998J-127D01*
G03X1602790Y795064I2002J0D01*
G01X1602792D01*
X1602858Y795048D01*
X1602944Y794939D01*
Y763722D01*
G03X1603314Y762830I1262J1D01*
G01X1610333Y755811D01*
G03X1611224Y755442I891J892D01*
G01X1620791D01*
G02X1620933Y755383I0J-200D01*
G01X1622615Y753701D01*
G02X1622674Y753559I-141J-142D01*
G01Y752962D01*
G02X1622597Y752805I-200J1D01*
G01X1622312Y752582D01*
X1622224Y752563D01*
X1622190Y752571D01*
G03X1621669Y752632I-491J-1940D01*
G03X1620170Y751922I31J-2002D01*
G02X1620130Y751892I-139J144D01*
G01X1617664D01*
X1617636Y751903D01*
G03X1617497Y751951I-359J-814D01*
G03X1617250Y751979I-223J-862D01*
G01X1617246Y751978D01*
X1616094D01*
Y751979D01*
G03X1615198Y751089I-6J-890D01*
G01Y750236D01*
G03X1615398Y750036I200J0D01*
G01X1615434D01*
Y748168D01*
Y748158D01*
G02X1615234Y747968I-200J11D01*
G01X1615198D01*
Y746915D01*
G03X1615401Y746349I890J0D01*
G02X1615422Y746318I-154J-127D01*
G01Y745335D01*
G02X1615415Y745323I-176J95D01*
G03X1615181Y744552I1268J-806D01*
G01Y744498D01*
G03X1618185I1502J19D01*
G01Y744519D01*
G03X1617951Y745323I-1502J-1D01*
G02X1617944Y745335I169J107D01*
G01Y746318D01*
G02X1617965Y746349I175J-96D01*
G03X1618168Y746915I-687J566D01*
G01Y747768D01*
G03X1617968Y747968I-200J0D01*
G01X1617932D01*
G37*
G36*
G01X1517653Y908367D02*
G03I-500J0D01*
G37*
G36*
G01X1515517Y1032391D02*
X1518363D01*
G02X1518505Y1032332I0J-200D01*
G01X1518871Y1031966D01*
G02X1518930Y1031824I-141J-142D01*
G01Y1011694D01*
G02X1518871Y1011552I-200J0D01*
G01X1518505Y1011186D01*
G02X1518363Y1011127I-142J141D01*
G01X1515561D01*
G02X1515419Y1011186I0J200D01*
G01X1515128Y1011477D01*
X1515107Y1011601D01*
X1515134Y1011658D01*
G03X1515250Y1012171I-1086J515D01*
G01Y1019164D01*
G03X1514993Y1019905I-1202J-2D01*
G02X1514950Y1020029I157J124D01*
G01Y1023906D01*
G02X1514993Y1024030I200J0D01*
G03X1515250Y1024771I-945J743D01*
G01Y1031764D01*
G03X1515217Y1032040I-1202J-4D01*
G01X1515205Y1032091D01*
X1515233Y1032190D01*
X1515375Y1032332D01*
G02X1515517Y1032391I142J-141D01*
G37*
G36*
G01X1524219Y1258465D02*
G03I-400J0D01*
G37*
G36*
G01X1611280Y54588D02*
X1639405D01*
X1639599Y54394D01*
Y52785D01*
X1639405Y52591D01*
X1611280D01*
G03X1605343Y46654I0J-5937D01*
G01Y7874D01*
G02X1599469Y2000I-5874J0D01*
G01X1552224D01*
G02X1546350Y7874I0J5874D01*
G01Y46654D01*
G03X1545263Y50079I-5939J0D01*
G01Y50191D01*
X1545272Y50200D01*
X1547511D01*
G02X1548348Y46654I-7097J-3547D01*
G01Y7874D01*
G03X1552224Y3998I3876J0D01*
G01X1599469D01*
G03X1603346Y7874I0J3877D01*
G01Y46654D01*
G02X1611280Y54588I7934J0D01*
G37*
G36*
G01X1541592Y89438D02*
X1555657D01*
G02X1555799Y89379I0J-200D01*
G01X1555802Y89376D01*
Y74039D01*
G03X1555860Y73898I200J0D01*
G01X1555907Y73851D01*
G02Y73568I-141J-141D01*
G01X1555720Y73381D01*
G02X1555578Y73322I-142J141D01*
G01X1551763D01*
X1551760Y73319D01*
X1531415D01*
G02X1531273Y73378I0J200D01*
G01X1531205Y73446D01*
G02X1531146Y73588I141J142D01*
G01Y86280D01*
G02X1531205Y86422I200J0D01*
G01X1531273Y86490D01*
G02X1531415Y86549I142J-141D01*
G01X1536726D01*
G03X1536868Y86608I0J200D01*
G01X1537701Y87441D01*
G03X1537760Y87583I-141J142D01*
G01Y88917D01*
G02X1537819Y89059I200J0D01*
G01X1538139Y89379D01*
G02X1538281Y89438I142J-141D01*
G01X1541252D01*
G02X1541393Y89379I-1J-200D01*
G01X1541491D01*
X1541519Y89408D01*
X1541592Y89438D01*
G37*
G36*
G01X1541244Y95055D02*
X1556260D01*
X1556280Y95035D01*
X1560285D01*
X1560998Y94322D01*
Y74773D01*
X1560137Y73912D01*
X1557526D01*
X1557262D01*
X1556803Y74371D01*
Y90663D01*
X1556680Y90786D01*
X1555974D01*
X1553219D01*
X1541481D01*
X1541442Y90747D01*
X1541165Y91024D01*
Y94976D01*
X1541244Y95055D01*
G37*
G36*
G01X1546658Y1071455D02*
G03I-400J0D01*
G37*
G36*
G01D02*
G03I-400J0D01*
G37*
G36*
G01X1539179Y1258465D02*
G03I-400J0D01*
G37*
G36*
G01X1546660D02*
G03I-400J0D01*
G37*
G36*
G01X1531699D02*
G03I-400J0D01*
G37*
G36*
G01X1561155Y276354D02*
X1578728D01*
X1579554Y275528D01*
Y258570D01*
X1577399Y256415D01*
Y231268D01*
X1571420Y225289D01*
Y220921D01*
X1569120Y218621D01*
X1567120D01*
X1566830Y218331D01*
Y205660D01*
X1566243Y205073D01*
X1559411D01*
X1558903Y205581D01*
Y220421D01*
X1555620Y223704D01*
Y234821D01*
X1555786Y234987D01*
Y250246D01*
X1558950Y253410D01*
X1558986D01*
X1561206Y255630D01*
Y268925D01*
X1558197Y271934D01*
X1555893D01*
X1555377Y272450D01*
Y274738D01*
X1555600Y274961D01*
X1559762D01*
X1561155Y276354D01*
G37*
G36*
G01X1556409Y276095D02*
X1557148D01*
X1557174Y276122D01*
X1559375D01*
X1560827Y277574D01*
X1562462D01*
X1562496Y277540D01*
X1569667D01*
X1569699Y277572D01*
X1577430D01*
X1579245Y279387D01*
Y287118D01*
Y296369D01*
X1578419Y297195D01*
X1562187D01*
X1560072Y295080D01*
Y282733D01*
X1557889Y280550D01*
X1556099Y278760D01*
Y276405D01*
X1556409Y276095D01*
G37*
G36*
G01X1548549Y304906D02*
G03I-577J0D01*
G37*
G36*
G01X1816805Y1200738D02*
X1837996D01*
G02X1838138Y1200679I0J-200D01*
G01X1838714Y1200103D01*
G02X1838773Y1199961I-141J-142D01*
G01Y972020D01*
X1838745Y971949D01*
X1838718Y971921D01*
G03X1838706Y971908I140J-141D01*
G01X1838700Y971900D01*
X1837791Y970991D01*
G03X1837732Y970849I141J-142D01*
G01Y967027D01*
X1837704Y966956D01*
X1837677Y966928D01*
G03X1837665Y966915I140J-141D01*
G01X1837659Y966907D01*
X1823783Y953031D01*
G03X1823724Y952889I141J-142D01*
G01Y938007D01*
G02X1823665Y937865I-200J0D01*
G01X1822813Y937013D01*
G02X1822671Y936954I-142J141D01*
G01X1810838D01*
G02X1810763Y936969I1J200D01*
G01X1810683Y937001D01*
X1810666Y937006D01*
G03X1810614Y937013I-52J-193D01*
G01X1755387D01*
G02X1755284Y937041I-1J200D01*
G03X1754125Y937362I-1161J-1940D01*
G01X1746600D01*
G03X1745441Y937041I2J-2261D01*
G02X1745338Y937013I-102J172D01*
G01X1738778D01*
G03X1738636Y936954I0J-200D01*
G01X1735037Y933355D01*
G03X1734978Y933213I141J-142D01*
G01Y873449D01*
G03X1735037Y873307I200J0D01*
G01X1740751Y867593D01*
G03X1740893Y867534I142J141D01*
G01X1822283D01*
G02X1822425Y867475I0J-200D01*
G01X1823665Y866235D01*
G02X1823724Y866093I-141J-142D01*
G01Y482381D01*
X1823696Y482310D01*
X1823669Y482282D01*
G03X1823657Y482269I140J-141D01*
G01X1823651Y482261D01*
X1822952Y481562D01*
G02X1822810Y481503I-142J141D01*
G01X1797973D01*
X1797900Y481534D01*
X1797872Y481563D01*
G03X1797866Y481568I-131J-151D01*
G01X1797859Y481573D01*
X1776630Y502802D01*
G03X1776488Y502861I-142J-141D01*
G01X1720030D01*
X1719957Y502892D01*
X1719929Y502921D01*
G03X1719923Y502926I-131J-151D01*
G01X1719916Y502931D01*
X1714498Y508349D01*
G02X1714439Y508491I141J142D01*
G01Y549932D01*
G02X1714498Y550074I200J0D01*
G01X1718540Y554116D01*
G03X1718599Y554258I-141J142D01*
G01Y572399D01*
G03X1718540Y572541I-200J0D01*
G01X1708118Y582963D01*
G02X1708059Y583105I141J142D01*
G01Y625101D01*
G03X1708000Y625243I-200J0D01*
G01X1699797Y633446D01*
G03X1699655Y633505I-142J-141D01*
G01X1653817D01*
G02X1653731Y633524I-1J200D01*
G01X1653654Y633561D01*
X1653628Y633587D01*
G03X1647745Y633716I-3007J-2937D01*
G03X1647616Y633589I2884J-3058D01*
G01X1647586Y633559D01*
X1647512Y633524D01*
G02X1647427Y633505I-85J181D01*
G01X1643197D01*
X1643124Y633536D01*
X1643096Y633565D01*
G03X1643090Y633570I-131J-151D01*
G01X1643083Y633575D01*
X1626570Y650088D01*
G02X1626511Y650230I141J142D01*
G01Y686123D01*
G03X1626452Y686265I-200J0D01*
G01X1620770Y691947D01*
G02X1621052Y692630I283J283D01*
G01X1643626D01*
G03X1644391Y692765I0J2237D01*
G03X1645207Y693286I-767J2101D01*
G01X1651804Y699883D01*
G03X1652325Y700699I-1580J1583D01*
G03X1652460Y701464I-2102J765D01*
G01Y810686D01*
G02X1652519Y810828I200J0D01*
G01X1671401Y829711D01*
G03X1672056Y831292I-1581J1581D01*
G01Y958906D01*
G03X1671401Y960487I-2236J0D01*
G01X1653008Y978881D01*
G02X1652962Y978990I153J129D01*
G01Y979753D01*
G02X1653021Y979895I200J0D01*
G01X1653025Y979899D01*
X1653043Y979916D01*
G03X1653705Y981515I-1600J1599D01*
G03X1653701Y981646I-2262J-4D01*
G01X1653697Y981699D01*
G03X1651443Y983776I-2254J-185D01*
G01Y983777D01*
G03X1649844Y983115I0J-2262D01*
G01X1649657Y982928D01*
G03X1649655Y982926I140J-142D01*
G01X1649605Y982875D01*
G02X1649321Y982874I-142J140D01*
G01X1649287Y982908D01*
X1649164Y983032D01*
G03X1647565Y983694I-1599J-1600D01*
G03X1645304Y981433I0J-2261D01*
G01X1645303Y981432D01*
G03X1645965Y979833I2262J0D01*
G01X1646211Y979587D01*
X1646278Y979521D01*
G02X1646338Y979378I-140J-143D01*
G01Y979004D01*
G02X1646215Y978820I-200J1D01*
G01X1646158Y978796D01*
X1646040Y978820D01*
X1637879Y986980D01*
G03X1637005Y987342I-874J-874D01*
G01X1554541D01*
G02X1554399Y987401I0J200D01*
G01X1553929Y987871D01*
G02X1553870Y988013I141J142D01*
G01Y994047D01*
G02X1553929Y994189I200J0D01*
G01X1557791Y998051D01*
G02X1557933Y998110I142J-141D01*
G01X1699022D01*
G02X1699164Y998051I0J-200D01*
G01X1713645Y983570D01*
G02X1713704Y983428I-141J-142D01*
G01Y966266D01*
G03X1713763Y966124I200J0D01*
G01X1734930Y944957D01*
G03X1735072Y944898I142J141D01*
G01X1797177D01*
G03X1797319Y944957I0J200D01*
G01X1813472Y961110D01*
G03X1813531Y961252I-141J142D01*
G01Y969228D01*
G02X1813590Y969370I200J0D01*
G01X1815432Y971212D01*
G03X1815491Y971354I-141J142D01*
G01Y974551D01*
G03X1815432Y974693I-200J0D01*
G01X1813590Y976535D01*
G02X1813531Y976677I141J142D01*
G01Y989760D01*
G03X1813472Y989902I-200J0D01*
G01X1810072Y993302D01*
G03X1809930Y993361I-142J-141D01*
G01X1800861D01*
G03X1800719Y993302I0J-200D01*
G01X1799474Y992057D01*
G03X1799415Y991915I141J-142D01*
G01Y978411D01*
G02X1799356Y978269I-200J0D01*
G01X1799329Y978242D01*
G03X1799270Y978100I141J-142D01*
G01Y976919D01*
G03X1799328Y976779I200J1D01*
G01X1799358Y976748D01*
G02X1799415Y976608I-143J-140D01*
G01Y976409D01*
G02X1799356Y976267I-200J0D01*
G01X1799340Y976251D01*
X1799325Y976215D01*
G03X1799310Y976139I185J-76D01*
G01Y975776D01*
G03X1799309Y975753I1200J-64D01*
G01Y975742D01*
G03X1799308Y975725I1198J-79D01*
G01Y962245D01*
G02X1799249Y962103I-200J0D01*
G01X1798509Y961363D01*
G02X1798367Y961304I-142J141D01*
G01X1779266D01*
G02X1779125Y961362I0J200D01*
G01X1778629Y961858D01*
G02X1778570Y962000I141J142D01*
G01Y970673D01*
G02X1778629Y970815I200J0D01*
G01X1779391Y971577D01*
G02X1779533Y971636I142J-141D01*
G01X1785964D01*
G02X1786106Y971577I0J-200D01*
G01X1786515Y971168D01*
G02X1786574Y971026I-141J-142D01*
G01Y965211D01*
G03X1786633Y965069I200J0D01*
G01X1787296Y964406D01*
G03X1787438Y964347I142J141D01*
G01X1791383D01*
G03X1791525Y964406I0J200D01*
G01X1792529Y965410D01*
G03X1792588Y965552I-141J142D01*
G01Y981459D01*
G03X1792529Y981601I-200J0D01*
G01X1791523Y982607D01*
G02X1791464Y982749I141J142D01*
G01Y985986D01*
G02X1791523Y986128I200J0D01*
G01X1792672Y987277D01*
G02X1792814Y987336I142J-141D01*
G01X1793660D01*
G03X1793802Y987395I0J200D01*
G01X1794343Y987936D01*
G03X1794402Y988078I-141J142D01*
G01Y995696D01*
G03X1794343Y995838I-200J0D01*
G01X1793009Y997172D01*
G03X1792867Y997231I-142J-141D01*
G01X1778346D01*
G03X1778204Y997172I0J-200D01*
G01X1777002Y995970D01*
G03X1776943Y995828I141J-142D01*
G01Y988782D01*
G02X1776884Y988640I-200J0D01*
G01X1770318Y982074D01*
G02X1770176Y982015I-142J141D01*
G01X1745714D01*
G02X1745572Y982074I0J200D01*
G01X1743844Y983802D01*
G02X1743785Y983944I141J142D01*
G01Y1001545D01*
G02X1743844Y1001687I200J0D01*
G01X1745246Y1003089D01*
G02X1745388Y1003148I142J-141D01*
G01X1760674D01*
G03X1761176Y1003650I0J502D01*
G01Y1006376D01*
G02X1761376Y1006576I200J0D01*
G01X1763096D01*
X1763098Y1006574D01*
Y1005113D01*
X1763097Y1003650D01*
G03X1763598Y1003148I502J0D01*
G01X1766399D01*
G03X1766900Y1003648I0J501D01*
G01Y1006376D01*
G02X1767100Y1006576I200J0D01*
G01X1768383D01*
G02X1768525Y1006517I0J-200D01*
G01X1768531Y1006511D01*
G02X1768590Y1006369I-141J-142D01*
G01Y1003650D01*
G03X1769092Y1003148I502J0D01*
G01X1771892D01*
G03X1772394Y1003650I0J502D01*
G01Y1006376D01*
G02X1772594Y1006576I200J0D01*
G01X1773716D01*
G02X1773916Y1006376I0J-200D01*
G01Y1005378D01*
G03X1774001Y1004816I1901J0D01*
G01X1774007Y1004798D01*
X1774020Y1004758D01*
X1774034Y1004718D01*
G02X1774046Y1004651I-188J-68D01*
G01Y1003650D01*
G03X1774548Y1003148I502J0D01*
G01X1777348D01*
G03X1777850Y1003650I0J502D01*
G01Y1006376D01*
G02X1778050Y1006576I200J0D01*
G01X1779226D01*
G02X1779426Y1006376I0J-200D01*
G01Y1005312D01*
G03X1779482Y1004854I1901J0D01*
G01X1779488Y1004830D01*
Y1004241D01*
X1779487Y1003650D01*
G03X1779988Y1003148I502J0D01*
G01X1782789D01*
G03X1783290Y1003648I0J501D01*
G01Y1006376D01*
G02X1783490Y1006576I200J0D01*
G01X1784678D01*
G02X1784878Y1006376I0J-200D01*
G01Y1005014D01*
X1784877Y1003650D01*
G03X1785378Y1003148I502J0D01*
G01X1788179D01*
G03X1788680Y1003648I0J501D01*
G01Y1005125D01*
X1788681Y1005131D01*
G03X1788682Y1005152I-1899J101D01*
G01Y1005162D01*
G03X1788683Y1005173I-1892J178D01*
G01Y1005178D01*
G03X1788684Y1005252I-1900J63D01*
G01Y1006376D01*
G02X1788884Y1006576I200J0D01*
G01X1790176D01*
G02X1790376Y1006376I0J-200D01*
G01Y1003650D01*
G03X1790878Y1003148I502J0D01*
G01X1793678D01*
G03X1794180Y1003650I0J502D01*
G01Y1006376D01*
G02X1794380Y1006576I200J0D01*
G01X1795538D01*
G02X1795738Y1006376I0J-200D01*
G01Y1005330D01*
G03X1795777Y1004948I1902J1D01*
G03X1795810Y1004810I1865J373D01*
G01X1795818Y1004784D01*
Y1003650D01*
G03X1796320Y1003148I502J0D01*
G01X1799120D01*
G03X1799622Y1003650I0J502D01*
G01Y1006376D01*
G02X1799822Y1006576I200J0D01*
G01X1800330D01*
G02X1800530Y1006376I0J-200D01*
G01Y1006185D01*
G03X1800944Y1005001I1902J1D01*
G01X1800964Y1004976D01*
X1800998Y1004882D01*
G02X1801010Y1004814I-188J-68D01*
G01Y1002857D01*
G03X1801113Y1002554I502J2D01*
G01X1801133Y1002527D01*
X1801154Y1002466D01*
Y1000254D01*
Y1000054D01*
X1801340D01*
X1806670D01*
X1806870D01*
Y1000240D01*
Y1002412D01*
G02X1806872Y1002442I200J2D01*
G01X1806876Y1002466D01*
X1806914Y1002557D01*
G03X1807014Y1002857I-402J301D01*
G01Y1005677D01*
G02X1807697Y1005959I400J-1D01*
G01X1808073Y1005583D01*
G02X1808132Y1005441I-141J-142D01*
G01Y1002857D01*
G03X1808234Y1002554I501J0D01*
G01X1808237Y1002551D01*
G02X1808276Y1002446I-161J-119D01*
G01Y1000054D01*
X1808462D01*
X1813790D01*
X1813990D01*
Y1002427D01*
G02X1813992Y1002441I199J-21D01*
G01X1813996Y1002465D01*
X1814034Y1002556D01*
G03X1814109Y1002700I-401J301D01*
G03X1814134Y1002858I-476J156D01*
G01Y1005035D01*
G02X1814817Y1005317I400J-1D01*
G01X1814905Y1005229D01*
G02X1814964Y1005087I-141J-142D01*
G01Y1002857D01*
G03X1815066Y1002554I501J0D01*
G01X1815069Y1002551D01*
G02X1815108Y1002446I-161J-119D01*
G01Y1000054D01*
X1815294D01*
X1820622D01*
X1820822D01*
Y1002427D01*
G02X1820824Y1002441I199J-21D01*
G01X1820828Y1002465D01*
X1820866Y1002556D01*
G03X1820941Y1002700I-401J301D01*
G03X1820966Y1002858I-476J156D01*
G01Y1005520D01*
G02X1821084Y1005702I200J0D01*
G01X1821085D01*
G02X1821308Y1005661I82J-182D01*
G01X1821754Y1005214D01*
G02X1821812Y1005073I-142J-141D01*
G01Y1002893D01*
G03X1821898Y1002615I502J3D01*
G03X1821915Y1002590I423J270D01*
G01X1821934Y1002566D01*
X1821944Y1002537D01*
G02X1821956Y1002470I-188J-68D01*
G01Y1000292D01*
Y1000092D01*
X1827672D01*
Y1000278D01*
Y1002449D01*
G02X1827674Y1002479I200J2D01*
G01X1827678Y1002503D01*
X1827716Y1002594D01*
G03X1827816Y1002894I-402J301D01*
G01Y1006895D01*
G03X1827316Y1007396I-501J0D01*
G01X1825034D01*
G02X1824892Y1007455I0J200D01*
G01X1820895Y1011453D01*
G02X1820836Y1011595I141J142D01*
G01Y1012805D01*
G03X1820695Y1013522I-1902J-2D01*
G01X1820688Y1013538D01*
X1820677Y1013593D01*
Y1013594D01*
X1820673Y1013614D01*
Y1015664D01*
G03X1820614Y1015806I-200J0D01*
G01X1818657Y1017763D01*
G02X1818598Y1017905I141J142D01*
G01Y1062028D01*
G02X1818657Y1062170I200J0D01*
G01X1820614Y1064127D01*
G03X1820667Y1064222I-141J141D01*
G01X1820674Y1064249D01*
X1820700Y1064296D01*
X1827826Y1071422D01*
G03X1827885Y1071564I-141J142D01*
G01Y1091917D01*
G02X1827944Y1092059I200J0D01*
G01X1830941Y1095056D01*
G03X1831000Y1095198I-141J142D01*
G01Y1105917D01*
G02X1831059Y1106059I200J0D01*
G01X1832941Y1107941D01*
G03X1833000Y1108083I-141J142D01*
G01Y1110417D01*
G03X1832941Y1110559I-200J0D01*
G01X1832059Y1111441D01*
G03X1831917Y1111500I-142J-141D01*
G01X1827083D01*
G03X1826941Y1111441I0J-200D01*
G01X1826559Y1111059D01*
G02X1826417Y1111000I-142J141D01*
G01X1813870D01*
X1813799Y1111028D01*
X1813771Y1111055D01*
G03X1813758Y1111067I-141J-140D01*
G01X1813750Y1111073D01*
X1813382Y1111441D01*
G02X1813362Y1111464I141J142D01*
G01X1813344Y1111488D01*
G03X1813324Y1111512I-163J-115D01*
G01X1812395Y1112441D01*
X1812366Y1112469D01*
X1812336Y1112543D01*
Y1155105D01*
G03X1812277Y1155247I-200J0D01*
G01X1809683Y1157841D01*
G03X1809541Y1157900I-142J-141D01*
G01X1779027D01*
G03X1778885Y1157841I0J-200D01*
G01X1778557Y1157513D01*
G03X1778498Y1157371I141J-142D01*
G01Y1123110D01*
G02X1778439Y1122968I-200J0D01*
G01X1775084Y1119613D01*
X1775056Y1119584D01*
X1774982Y1119554D01*
X1761524D01*
G02X1761382Y1119613I0J200D01*
G01X1760011Y1120984D01*
X1759982Y1121012D01*
X1759952Y1121086D01*
Y1162722D01*
G02X1760009Y1162862I200J0D01*
G01X1764069Y1166922D01*
G02X1764071Y1166924I142J-140D01*
G02X1764211Y1166981I140J-143D01*
G01X1810621D01*
G03X1810763Y1167040I0J200D01*
G01X1813264Y1169541D01*
G03X1813323Y1169683I-141J142D01*
G01Y1197256D01*
G02X1813382Y1197398I200J0D01*
G01X1816663Y1200679D01*
G02X1816805Y1200738I142J-141D01*
G37*
G36*
G01X1554139Y1071455D02*
G03I-400J0D01*
G37*
G36*
G01D02*
G03I-400J0D01*
G37*
G36*
G01X1561619D02*
G03I-400J0D01*
G37*
G36*
G01D02*
G03I-400J0D01*
G37*
G36*
G01X1554140Y1258465D02*
G03I-400J0D01*
G37*
G36*
G01X1561620D02*
G03I-400J0D01*
G37*
G36*
G01X1584367Y115094D02*
X1585423D01*
X1585450Y115067D01*
Y111227D01*
G02X1585391Y111085I-200J0D01*
G01X1583761Y109456D01*
G03X1583702Y109314I141J-142D01*
G01Y106183D01*
G03X1583761Y106041I200J0D01*
G01X1583884Y105918D01*
G03X1584026Y105859I142J141D01*
G01X1594732D01*
G03X1594874Y105918I0J200D01*
G01X1594950Y105994D01*
G03X1595009Y106136I-141J142D01*
G01Y109681D01*
G03X1594950Y109823I-200J0D01*
G01X1594716Y110057D01*
G02X1594657Y110199I141J142D01*
G01Y114552D01*
X1594687Y114625D01*
X1594698Y114636D01*
X1600282D01*
X1601624D01*
X1601688Y114572D01*
X1601804Y114456D01*
G02X1601863Y114314I-141J-142D01*
G01Y105226D01*
G02X1601804Y105084I-200J0D01*
G01X1601133Y104413D01*
X1601050Y104383D01*
X1601005Y104388D01*
G03X1600823Y104396I-174J-1893D01*
G01X1598241D01*
X1596955D01*
X1596209Y103650D01*
Y101528D01*
X1595877Y101196D01*
X1584346D01*
X1584322Y101202D01*
X1577142D01*
X1576447Y101897D01*
Y102887D01*
Y114049D01*
G02X1576506Y114191I200J0D01*
G01X1576628Y114313D01*
G02X1576770Y114372I142J-141D01*
G01X1583479D01*
G03X1583621Y114431I0J200D01*
G01X1584225Y115035D01*
G02X1584367Y115094I142J-141D01*
G37*
G36*
G01X1576629Y120851D02*
X1582046D01*
G02X1582188Y120792I0J-200D01*
G01X1583809Y119171D01*
G03X1583951Y119112I142J141D01*
G01X1585466D01*
G02X1585608Y119053I0J-200D01*
G01X1586081Y118580D01*
G02X1586140Y118438I-141J-142D01*
G01Y116276D01*
G02X1586017Y116091I-200J0D01*
G01X1585960Y116068D01*
X1585842Y116091D01*
X1585838Y116096D01*
X1584366D01*
G03X1583552Y115777I1J-1202D01*
G02X1583416Y115724I-136J147D01*
G01X1576570D01*
G02X1576428Y115783I0J200D01*
G01X1576413Y115798D01*
X1576383Y115871D01*
Y120605D01*
G02X1576442Y120747I200J0D01*
G01X1576487Y120792D01*
G02X1576629Y120851I142J-141D01*
G37*
G36*
G01X1567805Y576428D02*
X1575653D01*
X1576059Y576022D01*
Y564567D01*
X1575496Y564004D01*
X1574003D01*
X1573520Y563521D01*
X1567979D01*
X1567489Y564011D01*
Y576112D01*
X1567805Y576428D01*
G37*
G36*
G01X1576580Y1071455D02*
G03I-400J0D01*
G37*
G36*
G01D02*
G03I-400J0D01*
G37*
G36*
G01X1569099D02*
G03I-400J0D01*
G37*
G36*
G01D02*
G03I-400J0D01*
G37*
G36*
G01X1576581Y1258465D02*
G03I-400J0D01*
G37*
G36*
G01X1569101D02*
G03I-400J0D01*
G37*
G36*
G01X1595240Y-83484D02*
G03I-557J0D01*
G37*
G36*
G01Y-78528D02*
G03I-557J0D01*
G37*
G36*
G01Y-68528D02*
G03I-557J0D01*
G37*
G36*
G01Y-73484D02*
G03I-557J0D01*
G37*
G36*
G01X1585240Y-44564D02*
G03I-557J0D01*
G37*
G36*
G01Y-29608D02*
G03I-557J0D01*
G37*
G36*
G01Y-34564D02*
G03I-557J0D01*
G37*
G36*
G01Y-39608D02*
G03I-557J0D01*
G37*
G36*
G01X1587732Y119235D02*
X1591178D01*
X1594014Y122071D01*
X1600061D01*
X1600431Y121701D01*
Y116118D01*
X1599950Y115637D01*
X1590276D01*
X1587920D01*
X1587572Y115985D01*
Y119075D01*
X1587732Y119235D01*
G37*
G36*
G01X1586304Y210785D02*
X1595744D01*
X1597545Y208984D01*
X1598641Y207888D01*
Y187037D01*
X1597694Y186090D01*
X1586922D01*
X1585478Y187534D01*
Y209959D01*
X1586304Y210785D01*
G37*
G36*
G01X1598933Y223195D02*
X1608958D01*
X1608988Y223225D01*
X1611511D01*
X1614148Y225862D01*
X1623090D01*
X1623432Y225520D01*
Y213126D01*
X1622720Y212414D01*
X1615303D01*
X1612449Y215268D01*
X1609009D01*
X1598032D01*
X1596468D01*
X1596022Y214822D01*
Y213258D01*
X1594749Y211985D01*
X1594337D01*
X1593560D01*
X1585933D01*
X1585273Y212645D01*
Y226569D01*
X1585949Y227245D01*
X1596883D01*
X1598643Y225485D01*
Y223485D01*
X1598933Y223195D01*
G37*
G36*
G01X1591540Y1071455D02*
G03I-400J0D01*
G37*
G36*
G01D02*
G03I-400J0D01*
G37*
G36*
G01X1584060D02*
G03I-400J0D01*
G37*
G36*
G01D02*
G03I-400J0D01*
G37*
G36*
G01X1591542Y1258465D02*
G03I-400J0D01*
G37*
G36*
G01X1584061D02*
G03I-400J0D01*
G37*
G36*
G01X1599663Y186998D02*
Y210417D01*
X1597655Y212425D01*
Y214067D01*
X1598047Y214459D01*
X1606469D01*
X1606677Y214251D01*
Y212947D01*
X1606625Y212895D01*
Y212503D01*
Y211861D01*
X1607104Y211382D01*
X1607746D01*
X1611972D01*
X1613300Y210054D01*
Y205828D01*
Y187369D01*
X1612145Y186214D01*
X1600447D01*
X1599663Y186998D01*
G37*
G36*
G01X1598800Y351002D02*
G03I-577J0D01*
G37*
G36*
G01X1606501Y1071454D02*
G03I-400J0D01*
G37*
G36*
G01D02*
G03I-400J0D01*
G37*
G36*
G01X1599021Y1071455D02*
G03I-400J0D01*
G37*
G36*
G01D02*
G03I-400J0D01*
G37*
G36*
G01X1606502Y1258465D02*
G03I-400J0D01*
G37*
G36*
G01X1599023D02*
G03I-400J0D01*
G37*
G36*
G01X1615577Y86514D02*
X1624292D01*
X1624645Y86161D01*
Y73377D01*
X1624199Y72931D01*
X1615801D01*
X1615466Y73266D01*
Y86403D01*
X1615577Y86514D01*
G37*
G36*
G01X1621462Y1071455D02*
G03I-400J0D01*
G37*
G36*
G01D02*
G03I-400J0D01*
G37*
G36*
G01X1613981D02*
G03I-400J0D01*
G37*
G36*
G01D02*
G03I-400J0D01*
G37*
G36*
G01X1621463Y1258465D02*
G03I-400J0D01*
G37*
G36*
G01X1613982D02*
G03I-400J0D01*
G37*
G36*
G01X1643994Y89438D02*
X1658019D01*
G02X1658161Y89379I0J-200D01*
G01X1658164Y89376D01*
Y74039D01*
G03X1658222Y73898I200J0D01*
G01X1658269Y73851D01*
G02Y73568I-141J-141D01*
G01X1658082Y73381D01*
G02X1657940Y73322I-142J141D01*
G01X1654125D01*
X1654122Y73319D01*
X1633777D01*
G02X1633635Y73378I0J200D01*
G01X1633567Y73446D01*
G02X1633508Y73588I141J142D01*
G01Y86280D01*
G02X1633567Y86422I200J0D01*
G01X1633635Y86490D01*
G02X1633777Y86549I142J-141D01*
G01X1639088D01*
G03X1639230Y86608I0J200D01*
G01X1640063Y87441D01*
G03X1640122Y87583I-141J142D01*
G01Y88917D01*
G02X1640181Y89059I200J0D01*
G01X1640501Y89379D01*
G02X1640643Y89438I142J-141D01*
G01X1643614D01*
G02X1643755Y89379I-1J-200D01*
G01X1643853D01*
G02X1643994Y89438I142J-141D01*
G37*
G36*
G01X1631503Y176789D02*
X1645930D01*
X1646693Y176026D01*
Y174795D01*
X1647456Y174032D01*
X1650564D01*
X1651151Y173445D01*
Y161423D01*
X1650447Y160719D01*
X1632148D01*
Y160720D01*
X1630152D01*
X1629391Y161481D01*
Y176203D01*
X1629977Y176789D01*
X1631503D01*
G37*
G36*
G01X1658422Y219609D02*
X1660064D01*
X1660456Y219217D01*
Y210795D01*
X1660248Y210587D01*
X1658944D01*
X1658892Y210639D01*
X1658500D01*
Y210634D01*
X1657638D01*
X1657379Y210375D01*
Y209512D01*
Y204802D01*
X1646910Y194333D01*
Y189191D01*
X1650547Y185554D01*
X1655312D01*
X1655860Y185006D01*
Y183690D01*
X1656855Y182695D01*
X1658789D01*
X1659176Y182308D01*
X1661390D01*
X1661568Y182130D01*
Y181714D01*
X1661255Y181401D01*
X1658045D01*
X1657644Y181000D01*
X1657599D01*
X1656306Y179707D01*
X1630747D01*
X1629435Y181019D01*
Y216698D01*
X1630338Y217601D01*
X1656414D01*
X1658422Y219609D01*
G37*
G36*
G01X1656782Y234621D02*
Y221520D01*
X1654981Y219719D01*
X1653885Y218623D01*
X1631044D01*
X1629316Y220351D01*
Y252516D01*
X1630627Y253827D01*
X1652867D01*
X1656782Y249912D01*
Y234621D01*
G37*
G36*
G01X1631662Y277007D02*
X1639091D01*
X1651542D01*
X1653399Y275150D01*
X1655978D01*
X1656253Y274875D01*
Y272398D01*
X1655703Y271848D01*
X1653159D01*
X1653055Y271952D01*
X1649375Y268272D01*
Y265554D01*
X1646177Y262356D01*
X1631593D01*
X1630905Y263044D01*
Y276250D01*
X1631662Y277007D01*
G37*
G36*
G01X1634655Y299467D02*
X1644939D01*
X1649375Y295031D01*
Y278899D01*
X1649134Y278658D01*
X1632384D01*
X1631112Y279930D01*
Y295924D01*
X1634655Y299467D01*
G37*
G36*
G01X1644400Y429084D02*
X1636552D01*
X1636146Y429490D01*
Y440646D01*
X1637491Y441991D01*
X1644509D01*
X1644716Y441784D01*
Y429400D01*
X1644400Y429084D01*
G37*
G36*
G01X1643903Y1071455D02*
G03I-400J0D01*
G37*
G36*
G01X1636422D02*
G03I-400J0D01*
G37*
G36*
G01D02*
G03I-400J0D01*
G37*
G36*
G01X1643903D02*
G03I-400J0D01*
G37*
G36*
G01X1628942D02*
G03I-400J0D01*
G37*
G36*
G01D02*
G03I-400J0D01*
G37*
G36*
G01X1636423Y1258465D02*
G03I-400J0D01*
G37*
G36*
G01X1643904D02*
G03I-400J0D01*
G37*
G36*
G01X1628943D02*
G03I-400J0D01*
G37*
G36*
G01X1713642Y54588D02*
X1740397D01*
Y52591D01*
X1713642D01*
G03X1707705Y46654I0J-5937D01*
G01Y7874D01*
G02X1701831Y2000I-5874J0D01*
G01X1654587D01*
G02X1648713Y7874I0J5874D01*
G01Y46607D01*
X1650710D01*
Y7874D01*
G03X1654585Y3998I3876J0D01*
G01X1701831D01*
G03X1705708Y7874I0J3877D01*
G01Y46654D01*
G02X1713642Y54588I7934J0D01*
G37*
G36*
G01X1643606Y95055D02*
X1658622D01*
X1658642Y95035D01*
X1662647D01*
X1663360Y94322D01*
Y74773D01*
X1662499Y73912D01*
X1659888D01*
X1659624D01*
X1659165Y74371D01*
Y90663D01*
X1659042Y90786D01*
X1658336D01*
X1655581D01*
X1643843D01*
X1643804Y90747D01*
X1643527Y91024D01*
Y94976D01*
X1643606Y95055D01*
G37*
G36*
G01X1663517Y276354D02*
X1681090D01*
X1681916Y275528D01*
Y258570D01*
X1679708Y256362D01*
Y231728D01*
X1673782Y225802D01*
Y220921D01*
X1671482Y218621D01*
X1669482D01*
X1669192Y218331D01*
Y205660D01*
X1668605Y205073D01*
X1661773D01*
X1661265Y205581D01*
Y220421D01*
X1657982Y223704D01*
Y234821D01*
X1658148Y234987D01*
Y250246D01*
X1661312Y253410D01*
X1661348D01*
X1663568Y255630D01*
Y268925D01*
X1660559Y271934D01*
X1658255D01*
X1657739Y272450D01*
Y274738D01*
X1657962Y274961D01*
X1662124D01*
X1663517Y276354D01*
G37*
G36*
G01X1658771Y276095D02*
X1659510D01*
X1659536Y276122D01*
X1661737D01*
X1663189Y277574D01*
X1664824D01*
X1664858Y277540D01*
X1672029D01*
X1672061Y277572D01*
X1679792D01*
X1681607Y279387D01*
Y287118D01*
Y296369D01*
X1680781Y297195D01*
X1664549D01*
X1662434Y295080D01*
Y282733D01*
X1660251Y280550D01*
X1658461Y278760D01*
Y276405D01*
X1658771Y276095D01*
G37*
G36*
G01X1657351Y442631D02*
X1668587D01*
X1668616Y442602D01*
X1704309D01*
X1710332Y436579D01*
X1725001D01*
X1726611Y434969D01*
Y432764D01*
Y428021D01*
Y411754D01*
G02X1726553Y411613I-200J0D01*
G01X1725903Y410963D01*
G02X1725762Y410905I-141J142D01*
G01X1723210D01*
X1716280D01*
X1706613D01*
X1693596Y423922D01*
X1675868D01*
X1670486Y429304D01*
X1657322D01*
X1657188Y429438D01*
Y442468D01*
X1657351Y442631D01*
G37*
G36*
G01X1717376Y482893D02*
X1741551D01*
Y473993D01*
X1741461Y473903D01*
X1735665D01*
X1733971Y472209D01*
Y457025D01*
X1733623Y456677D01*
X1730533D01*
X1730373Y456837D01*
Y458826D01*
X1730292D01*
X1727259Y461859D01*
X1716296D01*
X1705133Y450696D01*
X1664196D01*
X1661921Y452971D01*
X1657368D01*
X1657262Y453077D01*
Y454290D01*
X1657357Y454385D01*
X1662967D01*
X1664846Y456264D01*
X1666942D01*
X1673965Y463287D01*
X1697770D01*
X1717376Y482893D01*
G37*
G36*
G01X1658863Y1071455D02*
G03I-400J0D01*
G37*
G36*
G01X1651383D02*
G03I-400J0D01*
G37*
G36*
G01D02*
G03I-400J0D01*
G37*
G36*
G01X1658863D02*
G03I-400J0D01*
G37*
G36*
G01X1651384Y1258465D02*
G03I-400J0D01*
G37*
G36*
G01X1658864D02*
G03I-400J0D01*
G37*
G36*
G01X1680368Y421690D02*
X1691912D01*
X1694090Y419512D01*
Y410583D01*
X1692456Y408949D01*
X1679824D01*
X1676207D01*
X1675481Y409675D01*
Y419785D01*
X1677386Y421690D01*
X1680368D01*
G37*
G36*
G01X1735658Y469053D02*
X1740618D01*
X1740634Y469037D01*
X1741079D01*
X1743362Y466754D01*
X1752059D01*
X1753074Y465739D01*
Y458596D01*
X1767725D01*
Y449570D01*
X1766176Y448021D01*
X1756206D01*
X1754147Y445962D01*
Y445880D01*
X1753016Y444749D01*
X1738954D01*
X1737289Y443084D01*
Y438941D01*
X1736850Y438502D01*
X1711566D01*
X1705713Y444355D01*
X1667815D01*
X1667437Y444733D01*
Y448862D01*
X1667920Y449345D01*
X1710248D01*
X1716158Y443435D01*
X1728681D01*
X1728682Y443434D01*
X1734475D01*
X1735236Y444195D01*
Y452584D01*
G03X1735177Y452726I-200J0D01*
G01X1734573Y453330D01*
G02X1734514Y453472I141J142D01*
G01Y454528D01*
X1734541Y454555D01*
X1738381D01*
G02X1738523Y454496I0J-200D01*
G01X1740152Y452866D01*
G03X1740294Y452807I142J141D01*
G01X1743425D01*
G03X1743567Y452866I0J200D01*
G01X1743690Y452989D01*
G03X1743749Y453131I-141J142D01*
G01Y463837D01*
G03X1743690Y463979I-200J0D01*
G01X1743614Y464055D01*
G03X1743472Y464114I-142J-141D01*
G01X1739927D01*
G03X1739785Y464055I0J-200D01*
G01X1739551Y463821D01*
G02X1739409Y463762I-142J141D01*
G01X1735056D01*
X1734983Y463792D01*
X1734972Y463803D01*
Y468367D01*
X1735658Y469053D01*
G37*
G36*
G01X1673825Y1071455D02*
G03I-400J0D01*
G37*
G36*
G01D02*
G03I-400J0D01*
G37*
G36*
G01X1666344D02*
G03I-400J0D01*
G37*
G36*
G01D02*
G03I-400J0D01*
G37*
G36*
G01X1673825Y1258465D02*
G03I-400J0D01*
G37*
G36*
G01X1666345D02*
G03I-400J0D01*
G37*
G36*
G01X1686729Y115094D02*
X1687785D01*
X1687812Y115067D01*
Y111227D01*
G02X1687753Y111085I-200J0D01*
G01X1686123Y109456D01*
G03X1686064Y109314I141J-142D01*
G01Y106183D01*
G03X1686123Y106041I200J0D01*
G01X1686246Y105918D01*
G03X1686388Y105859I142J141D01*
G01X1697094D01*
G03X1697236Y105918I0J200D01*
G01X1697312Y105994D01*
G03X1697371Y106136I-141J142D01*
G01Y109681D01*
G03X1697312Y109823I-200J0D01*
G01X1697078Y110057D01*
G02X1697019Y110199I141J142D01*
G01Y114552D01*
X1697049Y114625D01*
X1697060Y114636D01*
X1702644D01*
X1703986D01*
X1704050Y114572D01*
X1704166Y114456D01*
G02X1704225Y114314I-141J-142D01*
G01Y105226D01*
G02X1704166Y105084I-200J0D01*
G01X1703495Y104413D01*
X1703412Y104383D01*
X1703367Y104388D01*
G03X1703185Y104396I-174J-1893D01*
G01X1700603D01*
X1699317D01*
X1698571Y103650D01*
Y101528D01*
X1698239Y101196D01*
X1686708D01*
X1686684Y101202D01*
X1679504D01*
X1678809Y101897D01*
Y102887D01*
Y114049D01*
G02X1678868Y114191I200J0D01*
G01X1678990Y114313D01*
G02X1679132Y114372I142J-141D01*
G01X1685841D01*
G03X1685983Y114431I0J200D01*
G01X1686587Y115035D01*
G02X1686729Y115094I142J-141D01*
G37*
G36*
G01X1690094Y119235D02*
X1693540D01*
X1696376Y122071D01*
X1702423D01*
X1702793Y121701D01*
Y116118D01*
X1702312Y115637D01*
X1692638D01*
X1690282D01*
X1689934Y115985D01*
Y119075D01*
X1690094Y119235D01*
G37*
G36*
G01X1678991Y120851D02*
X1684408D01*
G02X1684550Y120792I0J-200D01*
G01X1686171Y119171D01*
G03X1686313Y119112I142J141D01*
G01X1687828D01*
G02X1687970Y119053I0J-200D01*
G01X1688443Y118580D01*
G02X1688502Y118438I-141J-142D01*
G01Y116276D01*
G02X1688379Y116091I-200J0D01*
G01X1688322Y116068D01*
X1688204Y116091D01*
X1688200Y116096D01*
X1686728D01*
G03X1685914Y115777I1J-1202D01*
G02X1685778Y115724I-136J147D01*
G01X1678932D01*
G02X1678790Y115783I0J200D01*
G01X1678775Y115798D01*
X1678745Y115871D01*
Y120605D01*
G02X1678804Y120747I200J0D01*
G01X1678849Y120792D01*
G02X1678991Y120851I142J-141D01*
G37*
G36*
G01X1688666Y210785D02*
X1698106D01*
X1699907Y208984D01*
X1701003Y207888D01*
Y187037D01*
X1700056Y186090D01*
X1689284D01*
X1687840Y187534D01*
Y209959D01*
X1688666Y210785D01*
G37*
G36*
G01X1701295Y223195D02*
X1711320D01*
X1711350Y223225D01*
X1713873D01*
X1716510Y225862D01*
X1725452D01*
X1725794Y225520D01*
Y213126D01*
X1725082Y212414D01*
X1717665D01*
X1714811Y215268D01*
X1711371D01*
X1700394D01*
X1698830D01*
X1698384Y214822D01*
Y213258D01*
X1697111Y211985D01*
X1696699D01*
X1695922D01*
X1688295D01*
X1687635Y212645D01*
Y226569D01*
X1688311Y227245D01*
X1699245D01*
X1701005Y225485D01*
Y223485D01*
X1701295Y223195D01*
G37*
G36*
G01X1688785Y1071455D02*
G03I-400J0D01*
G37*
G36*
G01D02*
G03I-400J0D01*
G37*
G36*
G01X1681305D02*
G03I-400J0D01*
G37*
G36*
G01D02*
G03I-400J0D01*
G37*
G36*
G01X1688785Y1258465D02*
G03I-400J0D01*
G37*
G36*
G01X1681305D02*
G03I-400J0D01*
G37*
G36*
G01X1702025Y186998D02*
Y210417D01*
X1700017Y212425D01*
Y214067D01*
X1700409Y214459D01*
X1708831D01*
X1709039Y214251D01*
Y212947D01*
X1708987Y212895D01*
Y212503D01*
X1708990Y212500D01*
Y211619D01*
X1709227Y211382D01*
X1710108D01*
X1714334D01*
X1715662Y210054D01*
Y205828D01*
Y187369D01*
X1714507Y186214D01*
X1702809D01*
X1702025Y186998D01*
G37*
G36*
G01X1741912Y1066535D02*
G02I-17700J0D01*
G37*
G36*
G01X1700007Y1090158D02*
G03I-400J0D01*
G37*
G36*
G01Y1082677D02*
G03I-400J0D01*
G37*
G36*
G01Y1101378D02*
G03I-400J0D01*
G37*
G36*
G01Y1123819D02*
G03I-400J0D01*
G37*
G36*
G01Y1116339D02*
G03I-400J0D01*
G37*
G36*
G01Y1108859D02*
G03I-400J0D01*
G37*
G36*
G01X1700636Y1136909D02*
G03I-400J0D01*
G37*
G36*
G01X1700007Y1131300D02*
G03I-400J0D01*
G37*
G36*
G01Y1198621D02*
G03I-400J0D01*
G37*
G36*
G01Y1221062D02*
G03I-400J0D01*
G37*
G36*
G01Y1213582D02*
G03I-400J0D01*
G37*
G36*
G01Y1206102D02*
G03I-400J0D01*
G37*
G36*
G01Y1228543D02*
G03I-400J0D01*
G37*
G36*
G01X1741912Y1263386D02*
G02I-17700J0D01*
G37*
G36*
G01X1700007Y1239762D02*
G03I-400J0D01*
G37*
G36*
G01Y1247243D02*
G03I-400J0D01*
G37*
G36*
G01X1717939Y86514D02*
X1726654D01*
X1727007Y86161D01*
Y73377D01*
X1726561Y72931D01*
X1718163D01*
X1717828Y73266D01*
Y86403D01*
X1717939Y86514D01*
G37*
G36*
G01X1726418Y397951D02*
Y397268D01*
X1726203Y397053D01*
X1723904D01*
X1723063Y396212D01*
X1721506D01*
X1721482Y396188D01*
X1717219D01*
X1716937Y396470D01*
Y400288D01*
X1720131Y403482D01*
X1720887D01*
X1726418Y397951D01*
G37*
G36*
G01X1728244Y401826D02*
Y398942D01*
X1728173Y398871D01*
X1727337D01*
X1727048D01*
X1721996Y403923D01*
Y408358D01*
X1723541Y409903D01*
X1726017D01*
X1726606Y409314D01*
Y403464D01*
X1728244Y401826D01*
G37*
G36*
G01X1740539Y496318D02*
Y486878D01*
X1738738Y485077D01*
X1737642Y483981D01*
X1716791D01*
X1715844Y484928D01*
Y495700D01*
X1717288Y497144D01*
X1739713D01*
X1740539Y496318D01*
G37*
G36*
G01X1728714Y1218396D02*
Y1218470D01*
X1730161Y1219917D01*
X1730606D01*
X1732869Y1217654D01*
X1734871D01*
X1737059Y1215466D01*
Y1214018D01*
X1732016Y1208975D01*
X1726674D01*
X1723354Y1212295D01*
Y1213036D01*
X1728714Y1218396D01*
G37*
G36*
G01X1734466Y-83456D02*
G03I-557J0D01*
G37*
G36*
G01Y-78500D02*
G03I-557J0D01*
G37*
G36*
G01Y-68500D02*
G03I-557J0D01*
G37*
G36*
G01Y-73456D02*
G03I-557J0D01*
G37*
G36*
G01X1746117Y89379D02*
X1746215D01*
G02X1746356Y89438I142J-141D01*
G01X1760381D01*
G02X1760523Y89379I0J-200D01*
G01X1760526Y89376D01*
Y74039D01*
G03X1760584Y73898I200J0D01*
G01X1760631Y73851D01*
G02Y73568I-141J-141D01*
G01X1760444Y73381D01*
G02X1760302Y73322I-142J141D01*
G01X1756487D01*
X1756484Y73319D01*
X1736139D01*
G02X1735997Y73378I0J200D01*
G01X1735929Y73446D01*
G02X1735870Y73588I141J142D01*
G01Y86280D01*
G02X1735929Y86422I200J0D01*
G01X1735997Y86490D01*
G02X1736139Y86549I142J-141D01*
G01X1741450D01*
G03X1741592Y86608I0J200D01*
G01X1742425Y87441D01*
G03X1742484Y87583I-141J142D01*
G01Y88917D01*
G02X1742543Y89059I200J0D01*
G01X1742863Y89379D01*
G02X1743005Y89438I142J-141D01*
G01X1745976D01*
G02X1746117Y89379I-1J-200D01*
G37*
G36*
G01X1733865Y176789D02*
X1748292D01*
X1749055Y176026D01*
Y174795D01*
X1749818Y174032D01*
X1752926D01*
X1753513Y173445D01*
Y161423D01*
X1752809Y160719D01*
X1734510D01*
Y160720D01*
X1732514D01*
X1731753Y161481D01*
Y176203D01*
X1732339Y176789D01*
X1733865D01*
G37*
G36*
G01X1760784Y219609D02*
X1762426D01*
X1762818Y219217D01*
Y210795D01*
X1762610Y210587D01*
X1761306D01*
X1761254Y210639D01*
X1760862D01*
X1760851Y210628D01*
X1760105D01*
X1759741Y210264D01*
Y209518D01*
Y204802D01*
X1749272Y194333D01*
Y189191D01*
X1752909Y185554D01*
X1757674D01*
X1758222Y185006D01*
Y183690D01*
X1759217Y182695D01*
X1761151D01*
X1761538Y182308D01*
X1763752D01*
X1763930Y182130D01*
Y181714D01*
X1763617Y181401D01*
X1760407D01*
X1760006Y181000D01*
X1759961D01*
X1758668Y179707D01*
X1733109D01*
X1731797Y181019D01*
Y216698D01*
X1732700Y217601D01*
X1758776D01*
X1760784Y219609D01*
G37*
G36*
G01X1759144Y234621D02*
Y221520D01*
X1757343Y219719D01*
X1756247Y218623D01*
X1733406D01*
X1731678Y220351D01*
Y252516D01*
X1732989Y253827D01*
X1755229D01*
X1759144Y249912D01*
Y234621D01*
G37*
G36*
G01X1734024Y277007D02*
X1741453D01*
X1753904D01*
X1755761Y275150D01*
X1758340D01*
X1758615Y274875D01*
Y272398D01*
X1758065Y271848D01*
X1755521D01*
X1755417Y271952D01*
X1751737Y268272D01*
Y265554D01*
X1748539Y262356D01*
X1733955D01*
X1733267Y263044D01*
Y276250D01*
X1734024Y277007D01*
G37*
G36*
G01X1737017Y299467D02*
X1747301D01*
X1751737Y295031D01*
Y278899D01*
X1751496Y278658D01*
X1734746D01*
X1733474Y279930D01*
Y295924D01*
X1737017Y299467D01*
G37*
G36*
G01X1734075Y397747D02*
Y391404D01*
X1733908Y391237D01*
X1727598D01*
X1727418Y391417D01*
Y397681D01*
X1727585Y397848D01*
X1733974D01*
X1734075Y397747D01*
G37*
G36*
G01X1730601Y402260D02*
G02X1730586Y402183I-200J-1D01*
G01X1730353Y401620D01*
G03X1730277Y401384I1386J-577D01*
G01X1730271Y401356D01*
X1730244Y401308D01*
X1730214Y401278D01*
Y399147D01*
G02X1730155Y399005I-200J0D01*
G01X1730095Y398945D01*
G02X1729953Y398886I-142J141D01*
G01X1729703D01*
G02X1729561Y398945I0J200D01*
G01X1729366Y399140D01*
G02X1729307Y399282I141J142D01*
G01Y401859D01*
G03X1729248Y402001I-200J0D01*
G01X1729245Y402003D01*
Y402159D01*
G03X1729187Y402299I-200J-1D01*
G01X1727672Y403815D01*
G02X1727613Y403956I141J142D01*
G01Y436739D01*
X1728257Y437383D01*
X1737686D01*
X1738310Y438007D01*
Y442600D01*
X1739172Y443462D01*
X1753261D01*
X1756357Y446558D01*
X1770917D01*
X1771017Y446458D01*
X1790969D01*
X1790995Y446432D01*
Y431809D01*
X1790562Y431376D01*
X1778892D01*
X1778107Y430591D01*
Y426913D01*
X1777564Y426370D01*
X1759697D01*
X1759097Y425770D01*
Y415233D01*
X1759093Y415229D01*
Y400678D01*
X1761218Y398553D01*
Y394595D01*
X1761028Y394405D01*
X1752295D01*
X1752221Y394479D01*
Y397045D01*
X1751569Y397697D01*
X1743263D01*
X1743102Y397858D01*
Y410288D01*
X1741343Y412047D01*
X1735600D01*
X1733767Y410214D01*
Y405785D01*
X1732576Y404594D01*
X1731679D01*
G03X1731537Y404535I0J-200D01*
G01X1730660Y403658D01*
G03X1730601Y403516I141J-142D01*
G01Y402260D01*
G37*
G36*
G01X1728757Y450345D02*
Y451151D01*
G02X1728816Y451293I200J0D01*
G01X1730437Y452914D01*
G03X1730496Y453056I-141J142D01*
G01Y454571D01*
G02X1730555Y454713I200J0D01*
G01X1731028Y455186D01*
G02X1731170Y455245I142J-141D01*
G01X1733332D01*
G02X1733517Y455122I0J-200D01*
G01X1733540Y455065D01*
X1733517Y454947D01*
X1733512Y454943D01*
Y453471D01*
G03X1733831Y452657I1202J1D01*
G02X1733884Y452521I-147J-136D01*
G01Y445675D01*
G02X1733825Y445533I-200J0D01*
G01X1733810Y445518D01*
X1733737Y445488D01*
X1729291D01*
X1726702D01*
X1726344Y445846D01*
Y447932D01*
X1728757Y450345D01*
G37*
G36*
G01X1745968Y95055D02*
X1760984D01*
X1761004Y95035D01*
X1765009D01*
X1765722Y94322D01*
Y74773D01*
X1764861Y73912D01*
X1762250D01*
X1761986D01*
X1761527Y74371D01*
Y90663D01*
X1761404Y90786D01*
X1760698D01*
X1757943D01*
X1746205D01*
X1746166Y90747D01*
X1745889Y91024D01*
Y94976D01*
X1745968Y95055D01*
G37*
G36*
G01X1792354Y446867D02*
X1797399D01*
X1797480Y446786D01*
Y430343D01*
X1799353Y428470D01*
X1808394D01*
X1809065Y427799D01*
Y378592D01*
X1805057Y374584D01*
X1776388D01*
X1770926Y380046D01*
X1767730D01*
X1764715Y383061D01*
X1760156D01*
X1759975Y383242D01*
Y385317D01*
X1759432Y385860D01*
X1749690D01*
X1749488Y386062D01*
Y393183D01*
X1749710Y393405D01*
X1764799D01*
X1765137Y393743D01*
G02X1765279Y393802I142J-141D01*
G01X1776212D01*
X1776214Y393800D01*
X1791776D01*
X1792574Y394598D01*
Y406210D01*
X1789007Y409777D01*
Y426628D01*
X1792228Y429849D01*
X1792354Y429974D01*
Y446867D01*
G37*
G36*
G01X1742463Y471921D02*
Y483798D01*
X1741683Y484578D01*
Y495368D01*
Y496794D01*
X1741992Y497103D01*
X1752029D01*
X1752942Y496190D01*
Y481973D01*
X1752898Y481929D01*
X1750394D01*
X1750174Y481709D01*
Y481488D01*
Y471761D01*
Y468882D01*
Y468185D01*
X1749933Y467944D01*
X1743652D01*
X1742463Y469133D01*
Y470108D01*
Y470402D01*
Y471921D01*
G37*
G36*
G01X1744964Y906839D02*
X1758282D01*
X1759087Y907644D01*
X1764856D01*
X1765184Y907972D01*
Y908428D01*
X1764860Y908752D01*
X1759128D01*
X1755656Y912224D01*
X1754397Y913483D01*
X1744336D01*
X1743661Y912808D01*
Y907358D01*
X1744180Y906839D01*
X1744964D01*
G37*
G36*
G01X1759725Y906642D02*
X1764975D01*
G02X1765116Y906584I0J-200D01*
G01X1765141Y906559D01*
G02X1765200Y906417I-141J-142D01*
G01Y906083D01*
G02X1765141Y905941I-200J0D01*
G01X1764936Y905736D01*
G02X1764794Y905677I-142J141D01*
G01X1763831D01*
X1763808Y905682D01*
G03X1763480Y905720I-331J-1424D01*
G01X1762067D01*
G03X1761739Y905682I3J-1462D01*
G01X1761716Y905677D01*
X1761677D01*
X1761664Y905664D01*
X1761618Y905649D01*
G03X1761034Y905291I450J-1390D01*
G01X1757301Y901559D01*
G02X1757159Y901500I-142J141D01*
G01X1754652D01*
G03X1754510Y901441I0J-200D01*
G01X1752303Y899234D01*
G02X1752161Y899175I-142J141D01*
G01X1744635D01*
G02X1744493Y899234I0J200D01*
G01X1743729Y899998D01*
G02X1743670Y900140I141J142D01*
G01Y905480D01*
G02X1743729Y905622I200J0D01*
G01X1743886Y905779D01*
G02X1744027Y905838I142J-141D01*
G01X1758614D01*
G03X1758755Y905896I0J200D01*
G01X1758801Y905941D01*
G02X1758942Y906000I142J-141D01*
G01X1759000D01*
X1759584Y906584D01*
G02X1759725Y906642I141J-142D01*
G37*
G36*
G01X1802238Y1071494D02*
X1813597D01*
X1813622Y1071519D01*
X1816384D01*
X1817384Y1070519D01*
Y1018150D01*
X1816682Y1017448D01*
X1813936D01*
X1757824D01*
X1755050D01*
X1754509Y1017989D01*
Y1053512D01*
X1757527Y1056530D01*
Y1068048D01*
X1760754Y1071275D01*
X1763834D01*
X1772684D01*
G02X1772826Y1071216I0J-200D01*
G01X1772909Y1071133D01*
G02X1772968Y1070992I-141J-142D01*
G01Y1031668D01*
G03X1773026Y1031527I200J0D01*
G01X1773036Y1031516D01*
G02X1773095Y1031375I-141J-142D01*
G01Y1029844D01*
G03X1773154Y1029702I200J0D01*
G01X1774293Y1028563D01*
G03X1774435Y1028504I142J141D01*
G01X1799778D01*
G03X1799920Y1028563I0J200D01*
G01X1801877Y1030520D01*
G03X1801936Y1030662I-141J142D01*
G01Y1071192D01*
G02X1801995Y1071334I200J0D01*
G01X1802096Y1071435D01*
G02X1802238Y1071494I142J-141D01*
G37*
G36*
G01X1765879Y276354D02*
X1783452D01*
X1784278Y275528D01*
Y258570D01*
Y233935D01*
X1776144Y225801D01*
Y220921D01*
X1773844Y218621D01*
X1771844D01*
X1771554Y218331D01*
Y205660D01*
X1770967Y205073D01*
X1764135D01*
X1763627Y205581D01*
Y220421D01*
X1760344Y223704D01*
Y234821D01*
X1760510Y234987D01*
Y250246D01*
X1763674Y253410D01*
X1763710D01*
X1765930Y255630D01*
Y268925D01*
X1762921Y271934D01*
X1760617D01*
X1760101Y272450D01*
Y274738D01*
X1760324Y274961D01*
X1764486D01*
X1765879Y276354D01*
G37*
G36*
G01X1761133Y276095D02*
X1761872D01*
X1761898Y276122D01*
X1764099D01*
X1765551Y277574D01*
X1767186D01*
X1767220Y277540D01*
X1774391D01*
X1774423Y277572D01*
X1782154D01*
X1783969Y279387D01*
Y287118D01*
Y296369D01*
X1783143Y297195D01*
X1766911D01*
X1764796Y295080D01*
Y282733D01*
X1762613Y280550D01*
X1760823Y278760D01*
Y276405D01*
X1761133Y276095D01*
G37*
G36*
G01X1776113Y395002D02*
X1763413D01*
X1762888Y395527D01*
Y398368D01*
X1762390Y398866D01*
X1760115Y401141D01*
Y420740D01*
Y422259D01*
Y424461D01*
X1760981Y425327D01*
X1778475D01*
X1779291Y426143D01*
Y429356D01*
X1779896Y429961D01*
X1780636D01*
X1786885D01*
X1787770Y429076D01*
Y409012D01*
X1791250Y405532D01*
Y404385D01*
Y401684D01*
Y395828D01*
X1790424Y395002D01*
X1790301D01*
X1776113D01*
G37*
G36*
G01X1791038Y447491D02*
Y449363D01*
X1789546Y450855D01*
X1771227D01*
X1771056Y450684D01*
Y447833D01*
X1771431Y447458D01*
X1791005D01*
X1791038Y447491D01*
G37*
G36*
G01X1773000Y903800D02*
X1788900D01*
X1789400Y903300D01*
Y887500D01*
X1788900Y887000D01*
X1773200D01*
X1772600Y887600D01*
Y903400D01*
X1773000Y903800D01*
G37*
G36*
G01X1771922Y911222D02*
X1774335D01*
X1774588Y911475D01*
Y919069D01*
X1779467Y923948D01*
Y931518D01*
X1779185Y931800D01*
X1777107D01*
X1773462D01*
X1772848Y931186D01*
Y925640D01*
Y922381D01*
X1771636Y921169D01*
Y911508D01*
X1771922Y911222D01*
G37*
G36*
G01X1791022Y1086455D02*
X1791024Y1086421D01*
G03X1791083Y1086293I200J14D01*
G01X1799007Y1078369D01*
X1803268D01*
X1804473Y1077164D01*
Y1074031D01*
X1804014Y1073572D01*
X1801677D01*
X1800461Y1072356D01*
Y1031592D01*
G02X1800402Y1031450I-200J0D01*
G01X1799799Y1030847D01*
X1799771Y1030818D01*
X1799697Y1030788D01*
X1775264D01*
G02X1775122Y1030847I0J200D01*
G01X1774028Y1031941D01*
X1773999Y1031969D01*
X1773969Y1032043D01*
Y1071744D01*
X1773357Y1072356D01*
X1763887D01*
X1762992Y1073251D01*
Y1091283D01*
Y1092421D01*
X1764043Y1093472D01*
X1786746D01*
X1788196Y1092022D01*
X1790266Y1089952D01*
X1790916Y1089302D01*
G02X1790974Y1089161I-142J-141D01*
G01Y1086609D01*
G03X1790990Y1086531I200J0D01*
G01X1791022Y1086455D01*
G37*
G36*
G01X1781301Y1156263D02*
X1808856D01*
G02X1808998Y1156204I0J-200D01*
G01X1811027Y1154175D01*
G02X1811086Y1154033I-141J-142D01*
G01Y1110527D01*
G02X1811027Y1110385I-200J0D01*
G01X1807388Y1106746D01*
G02X1807246Y1106687I-142J141D01*
G01X1807237D01*
G03X1807095Y1106628I0J-200D01*
G01X1806257Y1105790D01*
G02X1806115Y1105731I-142J141D01*
G01X1791946D01*
G03X1791804Y1105672I0J-200D01*
G01X1790381Y1104249D01*
G03X1790322Y1104107I141J-142D01*
G01Y1098592D01*
G03X1790381Y1098450I200J0D01*
G01X1791606Y1097225D01*
G03X1791748Y1097166I142J141D01*
G01X1796011D01*
G02X1796153Y1097107I0J-200D01*
G01X1797226Y1096034D01*
G02X1797285Y1095892I-141J-142D01*
G01Y1095078D01*
G03X1797344Y1094936I200J0D01*
G01X1798221Y1094059D01*
G03X1798363Y1094000I142J141D01*
G01X1799619D01*
G02X1799696Y1093985I1J-200D01*
G01X1800259Y1093752D01*
G03X1800475Y1093681I575J1387D01*
G01X1800476D01*
G03X1800495Y1093676I391J1449D01*
G01X1800523Y1093670D01*
X1800572Y1093642D01*
X1800601Y1093613D01*
X1802732D01*
G02X1802874Y1093554I0J-200D01*
G01X1802934Y1093494D01*
G02X1802993Y1093352I-141J-142D01*
G01Y1093102D01*
G02X1802934Y1092960I-200J0D01*
G01X1802739Y1092765D01*
X1802711Y1092736D01*
X1802637Y1092706D01*
X1800020D01*
G03X1799913Y1092675I0J-200D01*
G01X1799889Y1092660D01*
X1799835Y1092644D01*
X1799721D01*
G03X1799580Y1092586I0J-200D01*
G01X1799072Y1092079D01*
X1798064Y1091071D01*
G02X1797922Y1091012I-142J141D01*
G01X1791551D01*
G02X1791409Y1091071I0J200D01*
G01X1787643Y1094837D01*
G03X1787501Y1094896I-142J-141D01*
G01X1766443D01*
G02X1766301Y1094955I0J200D01*
G01X1765344Y1095912D01*
G02X1765288Y1096083I142J141D01*
G01X1765344Y1096449D01*
X1765399Y1096526D01*
X1765441Y1096549D01*
G03X1766246Y1097879I-696J1330D01*
G03X1764744Y1099381I-1502J0D01*
G03X1764620Y1099376I-2J-1502D01*
G01X1764577Y1099372D01*
X1764499Y1099399D01*
X1764252Y1099627D01*
G02X1764187Y1099774I135J148D01*
G01Y1100035D01*
G02X1764252Y1100182I200J-1D01*
G01X1764499Y1100410D01*
X1764577Y1100437D01*
X1764620Y1100433D01*
G03X1764744Y1100428I122J1497D01*
G03Y1103432I0J1502D01*
G03X1764620Y1103427I-2J-1502D01*
G01X1764577Y1103423D01*
X1764499Y1103450D01*
X1764252Y1103678D01*
G02X1764187Y1103825I135J148D01*
G01Y1116958D01*
G02X1764246Y1117100I200J0D01*
G01X1765331Y1118185D01*
G02X1765473Y1118244I142J-141D01*
G01X1775603D01*
G03X1775745Y1118303I0J200D01*
G01X1780371Y1122929D01*
G03X1780430Y1123071I-141J142D01*
G01Y1155392D01*
G02X1780489Y1155534I200J0D01*
G01X1781159Y1156204D01*
G02X1781301Y1156263I142J-141D01*
G37*
G36*
G01X1790336Y453904D02*
Y456122D01*
Y456569D01*
X1790233Y456672D01*
X1789786D01*
X1781361D01*
X1781157Y456468D01*
Y453598D01*
X1781401Y453354D01*
X1789786D01*
X1790336Y453904D01*
G37*
G36*
G01X1790369Y458336D02*
Y460127D01*
X1790247Y460249D01*
X1776082D01*
X1775227Y459394D01*
Y453553D01*
X1775472Y453308D01*
X1778910D01*
X1779155Y453553D01*
Y457135D01*
X1780106Y458086D01*
X1790293D01*
X1790369Y458162D01*
Y458336D01*
G37*
G36*
G01X1775841Y911235D02*
X1776319D01*
X1776534Y911450D01*
Y916876D01*
X1777358Y917700D01*
X1777818D01*
X1782459Y922341D01*
X1785090D01*
X1787269Y924520D01*
Y931169D01*
X1786584Y931854D01*
X1780861D01*
X1780505Y931498D01*
Y923388D01*
X1775600Y918483D01*
Y911476D01*
X1775841Y911235D01*
G37*
G36*
G01X1778863Y981460D02*
X1785463D01*
X1786463Y980460D01*
Y978960D01*
X1787463Y977960D01*
X1791163D01*
X1791463Y977660D01*
Y973460D01*
X1791263Y973260D01*
X1778663D01*
X1778363Y973560D01*
Y980960D01*
X1778863Y981460D01*
G37*
G36*
G01X1788063Y971960D02*
X1790663D01*
X1791063Y971560D01*
Y965960D01*
X1790563Y965460D01*
X1788363D01*
X1787963Y965860D01*
Y971860D01*
X1788063Y971960D01*
G37*
G36*
G01X1785363Y991660D02*
X1789863D01*
X1790463Y991060D01*
Y982360D01*
Y982014D01*
X1791550Y980927D01*
Y979047D01*
X1791465Y978962D01*
X1788061D01*
X1787863Y979160D01*
Y981360D01*
X1784563Y984660D01*
Y990860D01*
X1785363Y991660D01*
G37*
G36*
G01X1805641Y1183963D02*
X1786270D01*
X1782688D01*
X1782366Y1184285D01*
Y1199285D01*
X1785583Y1202502D01*
X1790121Y1207040D01*
Y1213822D01*
X1790391Y1214092D01*
X1790931D01*
X1791311Y1213712D01*
Y1200662D01*
X1792436Y1199537D01*
X1792441D01*
X1793776Y1198202D01*
X1793876Y1198102D01*
X1799800D01*
X1801575D01*
X1802670Y1199197D01*
Y1202709D01*
X1802815Y1202854D01*
X1804573D01*
X1807132Y1200295D01*
Y1184453D01*
X1806642Y1183963D01*
X1805641D01*
G37*
G36*
G01X1775848Y1272455D02*
X1808905D01*
X1811405Y1269955D01*
Y1235446D01*
Y1230015D01*
X1810136Y1228746D01*
X1804648D01*
X1804232Y1229162D01*
Y1235417D01*
Y1264493D01*
X1802019Y1266706D01*
X1792511D01*
X1788051Y1262246D01*
Y1210310D01*
X1787951Y1210210D01*
X1776754D01*
G03X1777494Y1215000I-15140J4791D01*
G03X1774161Y1224734I-15881J0D01*
G01Y1256623D01*
X1774141Y1256643D01*
Y1260949D01*
X1774149Y1260957D01*
Y1270756D01*
X1775848Y1272455D01*
G37*
G36*
G01X1779780Y1209210D02*
X1787831D01*
X1787981Y1209060D01*
Y1207680D01*
X1787371Y1207070D01*
X1779774D01*
X1779593Y1207251D01*
Y1209023D01*
X1779780Y1209210D01*
G37*
G36*
G01X1794280Y1201532D02*
X1792671D01*
X1792461Y1201742D01*
Y1215042D01*
X1791014Y1216489D01*
X1789159Y1218344D01*
Y1253590D01*
X1789938Y1254369D01*
X1802193D01*
X1803145Y1253417D01*
Y1236495D01*
Y1231736D01*
Y1230410D01*
X1801651Y1228916D01*
X1800325D01*
X1799257Y1227848D01*
X1793681Y1222272D01*
Y1206152D01*
X1794648Y1205185D01*
Y1201900D01*
X1794280Y1201532D01*
G37*
G36*
G01X1799822Y-44666D02*
G03I-557J0D01*
G37*
G36*
G01Y-39710D02*
G03I-557J0D01*
G37*
G36*
G01Y-29710D02*
G03I-557J0D01*
G37*
G36*
G01Y-34666D02*
G03I-557J0D01*
G37*
G36*
G01X1793524Y447997D02*
Y464238D01*
X1793381Y464381D01*
X1791570D01*
X1791407Y464218D01*
Y453126D01*
Y452381D01*
X1792384Y451404D01*
Y448017D01*
X1792462Y447940D01*
X1792474Y447952D01*
X1793479D01*
X1793524Y447997D01*
G37*
G36*
G01X1809363Y977960D02*
Y972560D01*
X1809063Y972260D01*
X1807563D01*
X1807363Y972460D01*
Y976060D01*
X1806363Y977060D01*
X1800463D01*
X1800271Y977252D01*
Y977768D01*
X1800363Y977860D01*
X1803963D01*
X1804663Y978560D01*
X1809163D01*
X1809363Y978360D01*
Y977960D01*
G37*
G36*
G01X1809063Y979760D02*
X1805163D01*
X1804863Y980060D01*
Y981460D01*
X1805263Y981860D01*
X1809163D01*
X1809263Y981760D01*
X1809363Y981660D01*
Y979960D01*
X1809163Y979760D01*
X1809063D01*
G37*
G36*
G01X1802463Y979060D02*
X1800663D01*
X1800463Y979260D01*
Y985360D01*
Y985760D01*
Y990513D01*
X1800622Y990672D01*
X1803007D01*
X1803228Y990451D01*
Y986125D01*
X1802863Y985760D01*
Y979260D01*
X1802663Y979060D01*
X1802463D01*
G37*
G36*
G01X1804463Y986060D02*
X1808363D01*
X1808613Y985810D01*
Y983760D01*
X1808413Y983560D01*
X1804563D01*
X1804363Y983760D01*
Y985960D01*
X1804463Y986060D01*
G37*
G36*
G01X1804132Y1097474D02*
X1810475D01*
X1810642Y1097307D01*
Y1090997D01*
X1810462Y1090817D01*
X1804198D01*
X1804031Y1090984D01*
Y1097373D01*
X1804132Y1097474D01*
G37*
G36*
G01X1803883Y1089772D02*
X1804656D01*
X1804826Y1089602D01*
Y1087303D01*
X1805667Y1086462D01*
Y1084905D01*
X1805691Y1084881D01*
Y1080618D01*
X1805409Y1080336D01*
X1801591D01*
X1798397Y1083530D01*
Y1084286D01*
X1803883Y1089772D01*
G37*
G36*
G01X1800053Y1091643D02*
X1802937D01*
X1803008Y1091572D01*
Y1090736D01*
Y1090447D01*
X1797956Y1085395D01*
X1793521D01*
X1791976Y1086940D01*
Y1089416D01*
X1792565Y1090005D01*
X1798415D01*
X1800053Y1091643D01*
G37*
G36*
G01X1795442Y1207701D02*
Y1209091D01*
X1795601Y1209250D01*
X1798771D01*
X1798983Y1209037D01*
Y1208039D01*
Y1207452D01*
X1801570Y1204865D01*
Y1200431D01*
X1801332Y1200193D01*
X1799385D01*
X1799104D01*
X1798628Y1200669D01*
Y1203546D01*
X1795442Y1206732D01*
Y1207701D01*
G37*
G36*
G01X1803350Y1227695D02*
G03I-506J0D01*
G37*
G36*
G01X1800544Y1255967D02*
X1793722D01*
X1793049Y1256640D01*
Y1262048D01*
Y1264102D01*
X1793228Y1264281D01*
X1793542Y1264595D01*
X1800859D01*
X1801173Y1264281D01*
X1801532Y1263922D01*
Y1261789D01*
Y1256224D01*
X1801275Y1255967D01*
X1800544D01*
G37*
G36*
G01X1813762Y427220D02*
Y454981D01*
X1814089Y455308D01*
X1817996D01*
X1818566Y454738D01*
Y427163D01*
X1818338Y426935D01*
X1817792D01*
X1814047D01*
X1813762Y427220D01*
G37*
G36*
G01X1827173Y1567323D02*
G02I-9850J0D01*
G37*
%LPC*%
G75*
G36*
G01X788431Y1332484D02*
Y1332776D01*
G03X788366Y1332924I-200J0D01*
G02X787881Y1334029I1017J1105D01*
G01Y1334030D01*
G02X789383Y1335532I1502J0D01*
G01X789384D01*
G02X790489Y1335047I0J-1502D01*
G03X790637Y1334982I148J135D01*
G01X790929D01*
G03X791077Y1335047I0J200D01*
G02X792182Y1335532I1105J-1017D01*
G01X792183D01*
G02X793685Y1334030I0J-1502D01*
G01Y1334029D01*
G02X793200Y1332924I-1502J0D01*
G03X793135Y1332776I135J-148D01*
G01Y1332484D01*
G03X793200Y1332336I200J0D01*
G02X793685Y1331231I-1017J-1105D01*
G01Y1331230D01*
G02X792183Y1329728I-1502J0D01*
G01X792182D01*
G02X791077Y1330213I0J1502D01*
G03X790929Y1330278I-148J-135D01*
G01X790637D01*
G03X790489Y1330213I0J-200D01*
G02X789384Y1329728I-1105J1017D01*
G01X789383D01*
G02X787881Y1331230I0J1502D01*
G01Y1331231D01*
G02X788366Y1332336I1502J0D01*
G03X788431Y1332484I-135J148D01*
G37*
G36*
G01X55251Y69570D02*
G03X55371Y69622I-15J199D01*
G02X60494I2562J-2811D01*
G01X60522Y69596D01*
X60591Y69570D01*
X60692D01*
Y69469D01*
X60718Y69400D01*
X60744Y69372D01*
G02Y64250I-2811J-2561D01*
G03X60692Y64130I147J-135D01*
G01Y57950D01*
X57222D01*
G03X57106Y57902I15J-199D01*
G02X54695Y57008I-2412J2807D01*
G01X47393D01*
G02X43692Y60709I0J3701D01*
G02X45509Y63895I3702J0D01*
G03X45606Y64043I-102J172D01*
G01Y69570D01*
X55251D01*
G37*
G36*
G01X201115Y694079D02*
G02Y697083I0J1502D01*
G02X202617Y695610I0J-1502D01*
G03X203023Y695218I400J8D01*
G01X203046D01*
G02Y692214I0J-1502D01*
G02X201544Y693687I0J1502D01*
G03X201138Y694079I-400J-8D01*
G01X201115D01*
G37*
G36*
G01X363015Y708863D02*
G02Y711867I0J1502D01*
G02X364161Y711335I0J-1500D01*
G01X364190Y711302D01*
X364267Y711265D01*
X364658Y711260D01*
X364736Y711295D01*
X364765Y711328D01*
G02X365887Y711831I1122J-1000D01*
G02Y708827I0J-1502D01*
G02X364741Y709359I0J1500D01*
G01X364712Y709392D01*
X364635Y709429D01*
X364244Y709434D01*
X364166Y709399D01*
X364137Y709366D01*
G02X363015Y708863I-1122J1000D01*
G37*
G36*
G01X381631Y812645D02*
G02Y815649I0J1502D01*
G02X382843Y815035I0J-1503D01*
G01X382871Y814996D01*
X382953Y814954D01*
X383368Y814948D01*
X383452Y814988D01*
X383481Y815026D01*
G02X384666Y815605I1185J-923D01*
G02X386055Y814674I0J-1502D01*
G01X386076Y814623D01*
X386161Y814558D01*
X386617Y814502D01*
X386715Y814545D01*
X386748Y814589D01*
G02X387958Y815202I1210J-888D01*
G02Y812198I0J-1502D01*
G02X386569Y813129I0J1502D01*
G01X386548Y813180D01*
X386463Y813245D01*
X386007Y813301D01*
X385909Y813258D01*
X385876Y813214D01*
G02X384666Y812601I-1210J888D01*
G02X383454Y813215I0J1503D01*
G01X383426Y813254D01*
X383344Y813296D01*
X382929Y813302D01*
X382845Y813262D01*
X382816Y813224D01*
G02X381631Y812645I-1185J923D01*
G37*
G36*
G01X230810Y829400D02*
G02X231312Y829902I502J0D01*
G01X244812D01*
G02X245314Y829400I0J-502D01*
G01Y828472D01*
X245413Y828359D01*
X245488Y828349D01*
G02X246333Y827933I-188J-1449D01*
G01X247344Y826922D01*
G02X247772Y825889I-1033J-1033D01*
G01Y825866D01*
G03X247846Y825711I200J0D01*
G01X248122Y825486D01*
X248208Y825465D01*
X248253Y825474D01*
G02X248556Y825505I304J-1471D01*
G02Y822501I0J-1502D01*
G02X248253Y822532I1J1502D01*
G01X248208Y822541D01*
X248122Y822520D01*
X247846Y822295D01*
G03X247772Y822140I126J-155D01*
G01Y819347D01*
X247777Y819326D01*
G02X247813Y819000I-1466J-327D01*
G02X247777Y818674I-1502J1D01*
G01X247772Y818653D01*
Y817750D01*
G03X247972Y817550I200J0D01*
G01X248561D01*
G03X248702Y817608I0J200D01*
G01X249180Y818086D01*
G03X249238Y818227I-142J141D01*
G01Y819553D01*
X249234Y819574D01*
G02X249198Y819900I1466J327D01*
G02X250700Y821402I1502J0D01*
G02X252036Y820586I0J-1502D01*
G01X252062Y820536D01*
X252155Y820478D01*
X252620Y820471D01*
X252715Y820526D01*
X252742Y820576D01*
G02X254058Y821353I1316J-726D01*
G02Y818349I0J-1502D01*
G02X252573Y819628I0J1502D01*
G03X252178Y819633I-198J-30D01*
G02X252166Y819574I-1477J270D01*
G01X252162Y819553D01*
Y817539D01*
G02X251733Y816506I-1461J1D01*
G01X250885Y815658D01*
X250857Y815602D01*
X250852Y815570D01*
G02X249973Y814814I-880J134D01*
G01X249036D01*
X248920Y814932D01*
Y814937D01*
X248809Y814992D01*
G02X248747Y815025I655J1306D01*
G03X248649Y815050I-97J-175D01*
G01X247123D01*
G03X247025Y815025I-1J-200D01*
G02X246963Y814992I-717J1273D01*
G01X246912Y814966D01*
X246852Y814871D01*
Y814814D01*
X245799D01*
G02X244909Y815711I0J890D01*
G01X244910D01*
Y815885D01*
X244902Y815911D01*
G02X244850Y816300I1409J386D01*
G01Y818653D01*
X244845Y818674D01*
G02X244809Y819000I1466J327D01*
G02X244845Y819326I1502J-1D01*
G01X244850Y819347D01*
Y823698D01*
G03X244650Y823898I-200J0D01*
G01X231312D01*
G02X230810Y824400I0J502D01*
G01Y829400D01*
G37*
G36*
G01X219314Y839400D02*
G02X219816Y839902I502J0D01*
G01X233316D01*
G02X233818Y839400I0J-502D01*
G01Y838561D01*
G03X234017Y838362I200J0D01*
G01X238053D01*
X238074Y838366D01*
G02X238400Y838402I327J-1466D01*
G01X238401D01*
G02X238998Y838278I-1J-1502D01*
G01X239036Y838262D01*
X244593D01*
X244614Y838266D01*
G02X244799Y838286I188J-870D01*
G01X245736D01*
X245852Y838168D01*
Y838163D01*
X245963Y838108D01*
G02X246025Y838075I-655J-1306D01*
G03X246123Y838050I97J175D01*
G01X247649D01*
G03X247747Y838075I1J200D01*
G02X247809Y838108I717J-1273D01*
G01X247860Y838134D01*
X247920Y838229D01*
Y838286D01*
X248973D01*
G02X249158Y838266I-3J-890D01*
G01X249179Y838262D01*
X251753D01*
X251774Y838266D01*
G02X252100Y838302I327J-1466D01*
G02Y835298I0J-1502D01*
G02X251774Y835334I1J1502D01*
G01X251753Y835338D01*
X249179D01*
X249158Y835334D01*
G02X248973Y835314I-188J870D01*
G01X248036D01*
X247920Y835432D01*
Y835437D01*
X247809Y835492D01*
G02X247747Y835525I655J1306D01*
G03X247649Y835550I-97J-175D01*
G01X246123D01*
G03X246025Y835525I-1J-200D01*
G02X245963Y835492I-717J1273D01*
G01X245912Y835466D01*
X245852Y835371D01*
Y835314D01*
X244799D01*
G02X244614Y835334I3J890D01*
G01X244593Y835338D01*
X238500D01*
G02X238001Y835426I1J1462D01*
G01X237968Y835438D01*
X234017D01*
G03X233818Y835239I1J-199D01*
G01Y834400D01*
G02X233316Y833898I-502J0D01*
G01X219816D01*
G02X219314Y834400I0J502D01*
G01Y839400D01*
G37*
G36*
G01X311210Y861400D02*
G02X311712Y861902I502J0D01*
G01X325212D01*
G02X325714Y861400I0J-502D01*
G01Y856400D01*
G02X325212Y855898I-502J0D01*
G01X311712D01*
G02X311210Y856400I0J502D01*
G01Y857239D01*
G03X311011Y857438I-199J0D01*
G01X288229D01*
G03X288098Y857389I0J-200D01*
G02X286785Y856898I-1313J1511D01*
G01X286783D01*
G02X285470Y857389I0J2002D01*
G03X285339Y857438I-131J-151D01*
G01X281949D01*
G03X281750Y857239I0J-199D01*
G01Y856451D01*
G03X281775Y856353I200J-1D01*
G02X281808Y856291I-1273J-717D01*
G01X281834Y856240D01*
X281929Y856180D01*
X281986D01*
Y855127D01*
G02X281230Y854248I-890J1D01*
G01X281198Y854243D01*
X281142Y854215D01*
X278994Y852067D01*
G02X277961Y851638I-1034J1032D01*
G01X270047D01*
X270026Y851634D01*
G02X269700Y851598I-327J1466D01*
G02Y854602I0J1502D01*
G02X270026Y854566I-1J-1502D01*
G01X270047Y854562D01*
X277273D01*
G03X277414Y854620I0J200D01*
G01X279192Y856398D01*
G03X279250Y856539I-142J141D01*
G01Y857916D01*
G03X279212Y858034I-200J1D01*
G02X279081Y858248I1176J867D01*
G01X279014D01*
Y858402D01*
X279004Y858433D01*
G02X278928Y858900I1385J465D01*
G02X279015Y859399I1461J2D01*
G03X279025Y859437I-187J70D01*
G02X279605Y860139I880J-136D01*
G03X279640Y860155I-65J189D01*
G02X280389Y860362I750J-1255D01*
G01X285339D01*
G03X285470Y860411I0J200D01*
G02X286783Y860902I1313J-1511D01*
G01X286785D01*
G02X288098Y860411I0J-2002D01*
G03X288229Y860362I131J151D01*
G01X311011D01*
G03X311210Y860561I-1J199D01*
G01Y861400D01*
G37*
G36*
G01X299714Y871400D02*
G02X300216Y871902I502J0D01*
G01X313716D01*
G02X314218Y871400I0J-502D01*
G01Y866400D01*
G02X313716Y865898I-502J0D01*
G01X300216D01*
G02X299714Y866400I0J502D01*
G01Y867239D01*
G03X299515Y867438I-199J0D01*
G01X288916D01*
G03X288785Y867389I0J-200D01*
G02X287472Y866898I-1313J1511D01*
G01X287470D01*
G02X286157Y867389I0J2002D01*
G03X286026Y867438I-131J-151D01*
G01X281949D01*
G03X281750Y867239I0J-199D01*
G01Y866551D01*
G03X281775Y866453I200J-1D01*
G02X281808Y866391I-1273J-717D01*
G01X281834Y866340D01*
X281929Y866280D01*
X281986D01*
Y865227D01*
G02X281230Y864348I-890J1D01*
G01X281198Y864343D01*
X281142Y864315D01*
X280194Y863367D01*
G02X279161Y862938I-1034J1032D01*
G01X275747D01*
X275726Y862934D01*
G02X275400Y862898I-327J1466D01*
G02Y865902I0J1502D01*
G02X275726Y865866I-1J-1502D01*
G01X275747Y865862D01*
X278473D01*
G03X278614Y865920I0J200D01*
G01X279192Y866498D01*
G03X279250Y866639I-142J141D01*
G01Y868069D01*
G03X279224Y868169I-200J1D01*
G02X279186Y868238I1261J739D01*
G01X279160Y868289D01*
X279064Y868348D01*
X279014D01*
Y869401D01*
G02X279911Y870291I890J0D01*
G01Y870290D01*
X280038D01*
X280066Y870299D01*
G02X280489Y870362I425J-1399D01*
G01X286026D01*
G03X286157Y870411I0J200D01*
G02X287470Y870902I1313J-1511D01*
G01X287472D01*
G02X288785Y870411I0J-2002D01*
G03X288916Y870362I131J151D01*
G01X299515D01*
G03X299714Y870561I-1J199D01*
G01Y871400D01*
G37*
G36*
G01X230810Y896700D02*
G02X231312Y897202I502J0D01*
G01X244812D01*
G02X245314Y896700I0J-502D01*
G01Y895861D01*
G03X245513Y895662I200J0D01*
G01X279155D01*
G03X279286Y895711I0J200D01*
G02X280599Y896202I1313J-1511D01*
G01X280601D01*
G02X281914Y895711I0J-2002D01*
G03X282045Y895662I131J151D01*
G01X286089D01*
G02X286897Y895418I-1J-1462D01*
G03X286987Y895386I110J167D01*
G02X287786Y894501I-91J-886D01*
G01Y893564D01*
X287668Y893448D01*
X287663D01*
X287608Y893337D01*
G02X287575Y893275I-1306J655D01*
G03X287550Y893177I175J-97D01*
G01Y891651D01*
G03X287575Y891553I200J-1D01*
G02X287608Y891491I-1273J-717D01*
G01X287634Y891440D01*
X287729Y891380D01*
X287786D01*
Y890327D01*
G02X286889Y889437I-890J0D01*
G01Y889438D01*
X286715D01*
X286689Y889430D01*
G02X286300Y889378I-386J1409D01*
G01X278747D01*
X278726Y889373D01*
G02X278400Y889337I-327J1466D01*
G02X276898Y890839I0J1502D01*
G02X277476Y892023I1502J0D01*
G01X277527Y892063D01*
X277563Y892185D01*
X277419Y892604D01*
G03X277231Y892738I-189J-66D01*
G01X245513D01*
G03X245314Y892539I1J-199D01*
G01Y891700D01*
G02X244812Y891198I-502J0D01*
G01X231312D01*
G02X230810Y891700I0J502D01*
G01Y896700D01*
G37*
G36*
G01X219314Y906700D02*
G02X219816Y907202I502J0D01*
G01X233316D01*
G02X233818Y906700I0J-502D01*
G01Y905861D01*
G03X234017Y905662I200J0D01*
G01X278055D01*
G03X278186Y905711I0J200D01*
G02X279499Y906202I1313J-1511D01*
G01X279501D01*
G02X280814Y905711I0J-2002D01*
G03X280945Y905662I131J151D01*
G01X285478D01*
X285501Y905667D01*
G02X285711Y905691I205J-866D01*
G01Y905690D01*
X285885D01*
X285911Y905698D01*
G02X286300Y905750I386J-1409D01*
G02X286689Y905698I3J-1461D01*
G01X286715Y905690D01*
X286889D01*
Y905691D01*
G02X287786Y904801I7J-890D01*
G01Y903864D01*
X287668Y903748D01*
X287663D01*
X287608Y903637D01*
G02X287575Y903575I-1306J655D01*
G03X287550Y903477I175J-97D01*
G01Y901951D01*
G03X287575Y901853I200J-1D01*
G02X287608Y901791I-1273J-717D01*
G01X287634Y901740D01*
X287729Y901680D01*
X287786D01*
Y900627D01*
G02X287030Y899748I-890J1D01*
G01X286998Y899743D01*
X286942Y899715D01*
X285594Y898367D01*
G02X284561Y897938I-1034J1032D01*
G01X275747D01*
X275726Y897934D01*
G02X275400Y897898I-327J1466D01*
G02Y900902I0J1502D01*
G02X275726Y900866I-1J-1502D01*
G01X275747Y900862D01*
X283873D01*
G03X284014Y900920I0J200D01*
G01X284992Y901898D01*
G03X285050Y902039I-142J141D01*
G01Y902539D01*
G03X284851Y902738I-199J0D01*
G01X280945D01*
G03X280814Y902689I0J-200D01*
G02X279501Y902198I-1313J1511D01*
G01X279499D01*
G02X278186Y902689I0J2002D01*
G03X278055Y902738I-131J-151D01*
G01X234017D01*
G03X233818Y902539I1J-199D01*
G01Y901700D01*
G02X233316Y901198I-502J0D01*
G01X219816D01*
G02X219314Y901700I0J502D01*
G01Y906700D01*
G37*
G36*
G01X312210Y931900D02*
G02X312712Y932402I502J0D01*
G01X326212D01*
G02X326714Y931900I0J-502D01*
G01Y926900D01*
G02X326212Y926398I-502J0D01*
G01X312712D01*
G02X312210Y926900I0J502D01*
G01Y927739D01*
G03X312011Y927938I-199J0D01*
G01X290025D01*
G03X289894Y927889I0J-200D01*
G02X288581Y927398I-1313J1511D01*
G01X288580D01*
G02X287179Y927970I0J2002D01*
G03X287039Y928028I-141J-142D01*
G01X283750D01*
G03X283550Y927828I0J-200D01*
G01Y927151D01*
G03X283575Y927053I200J-1D01*
G02X283608Y926991I-1273J-717D01*
G01X283634Y926940D01*
X283729Y926880D01*
X283786D01*
Y925827D01*
G02X282889Y924937I-890J0D01*
G01Y924938D01*
X282715D01*
X282689Y924930D01*
G02X282300Y924878I-386J1409D01*
G01X279608D01*
X279587Y924873D01*
G02X279261Y924837I-327J1466D01*
G02Y927841I0J1502D01*
G02X279587Y927805I-1J-1502D01*
G01X279608Y927800D01*
X280850D01*
G03X281050Y928000I0J200D01*
G01Y928677D01*
G03X281025Y928775I-200J1D01*
G02X280992Y928837I1273J717D01*
G01X280966Y928888D01*
X280871Y928948D01*
X280814D01*
Y930001D01*
G02X281711Y930891I890J0D01*
G01Y930890D01*
X281885D01*
X281911Y930898D01*
G02X282300Y930950I386J-1409D01*
G01X287244D01*
G03X287365Y930992I-2J200D01*
G02X288580Y931402I1214J-1592D01*
G02X289894Y930911I1J-2002D01*
G03X290025Y930862I131J151D01*
G01X312011D01*
G03X312210Y931061I-1J199D01*
G01Y931900D01*
G37*
G36*
G01X300714Y941900D02*
G02X301216Y942402I502J0D01*
G01X314716D01*
G02X315218Y941900I0J-502D01*
G01Y936900D01*
G02X314716Y936398I-502J0D01*
G01X301216D01*
G02X300714Y936900I0J502D01*
G01Y937739D01*
G03X300515Y937938I-199J0D01*
G01X289529D01*
G03X289398Y937889I0J-200D01*
G02X288085Y937398I-1313J1511D01*
G01X288083D01*
G02X286595Y938061I0J2002D01*
G03X286447Y938128I-149J-133D01*
G01X283850D01*
G03X283650Y937928I0J-200D01*
G01Y937251D01*
G03X283675Y937153I200J-1D01*
G02X283708Y937091I-1273J-717D01*
G01X283734Y937040D01*
X283829Y936980D01*
X283886D01*
Y935927D01*
G02X282989Y935037I-890J0D01*
G01Y935038D01*
X282815D01*
X282789Y935030D01*
G02X282400Y934978I-386J1409D01*
G01X279086D01*
X279065Y934973D01*
G02X278739Y934937I-327J1466D01*
G02Y937941I0J1502D01*
G02X279065Y937905I-1J-1502D01*
G01X279086Y937900D01*
X280950D01*
G03X281150Y938100I0J200D01*
G01Y938777D01*
G03X281125Y938875I-200J1D01*
G02X281092Y938937I1273J717D01*
G01X281066Y938988D01*
X280971Y939048D01*
X280914D01*
Y940101D01*
G02X281811Y940991I890J0D01*
G01Y940990D01*
X281985D01*
X282011Y940998D01*
G02X282400Y941050I386J-1409D01*
G01X286891D01*
G03X286999Y941082I-1J200D01*
G02X288084Y941402I1086J-1682D01*
G01X288085D01*
G02X289398Y940911I0J-2002D01*
G03X289529Y940862I131J151D01*
G01X300515D01*
G03X300714Y941061I0J199D01*
G01Y941900D01*
G37*
G36*
G01X473992Y951044D02*
G02Y954048I0J1502D01*
G02X475107Y953553I0J-1503D01*
G01X475132Y953525D01*
X475195Y953492D01*
X475529Y953452D01*
X475598Y953469D01*
X475629Y953490D01*
G02X476475Y953751I846J-1241D01*
G02X477730Y953074I0J-1502D01*
G01X477758Y953032D01*
X477843Y952985D01*
X478274Y952976D01*
X478361Y953020D01*
X478390Y953061D01*
G02X479613Y953691I1223J-872D01*
G02Y950687I0J-1502D01*
G02X478358Y951364I0J1502D01*
G01X478330Y951406D01*
X478245Y951453D01*
X477814Y951462D01*
X477727Y951418D01*
X477698Y951377D01*
G02X476475Y950747I-1223J872D01*
G02X475360Y951242I0J1503D01*
G01X475335Y951270D01*
X475272Y951303D01*
X474938Y951343D01*
X474869Y951326D01*
X474838Y951305D01*
G02X473992Y951044I-846J1241D01*
G37*
G36*
G01X453690Y1255597D02*
Y1261771D01*
G02X454192Y1262272I502J-1D01*
G01X456992D01*
G02X457494Y1261771I1J-501D01*
G01Y1255890D01*
X457496Y1255874D01*
G02X457520Y1255570I-1877J-301D01*
G02X456931Y1254193I-1901J-1D01*
G01X456900Y1254164D01*
X456868Y1254090D01*
Y1253986D01*
X456701D01*
X456647Y1253970D01*
X456623Y1253955D01*
G02X455619Y1253668I-1005J1615D01*
G02X454615Y1253955I1J1902D01*
G01X454591Y1253970D01*
X454537Y1253986D01*
X454486D01*
X454370Y1254102D01*
Y1254134D01*
X454307Y1254193D01*
G02X454274Y1254225I1307J1381D01*
G01X454247Y1254252D01*
G02X453690Y1255597I1345J1345D01*
G37*
G36*
G01X417319Y1309546D02*
X416919Y1309383D01*
G03X416794Y1309198I75J-185D01*
G01Y1301544D01*
G03X416917Y1301359I200J0D01*
G01X417258Y1301217D01*
G03X417474Y1301258I77J185D01*
G01X417476Y1301260D01*
X417477Y1301261D01*
G02X418537Y1301699I1060J-1064D01*
G02Y1298695I0J-1502D01*
G02X417477Y1299133I0J1502D01*
G01X417476Y1299134D01*
X417474Y1299136D01*
G03X417258Y1299177I-139J-144D01*
G01X416917Y1299035D01*
G03X416794Y1298850I77J-185D01*
G01Y1292497D01*
G02X416441Y1291648I-1202J2D01*
G01X414408Y1289614D01*
G02X414331Y1289566I-142J142D01*
G01X413902Y1289420D01*
G02X413816Y1289410I-66J189D01*
G01X413588Y1289435D01*
X413584D01*
G03X413526Y1289438I-55J-497D01*
G01X413525D01*
G03X413222Y1289335I1J-499D01*
G03X413210Y1289325I122J-158D01*
G02X412405Y1289018I-802J895D01*
G01X401851D01*
G02X400999Y1289369I-3J1202D01*
G01X399743Y1290626D01*
G02X399390Y1291475I849J851D01*
G01Y1293644D01*
X399314Y1293749D01*
X399252Y1293769D01*
G02Y1296627I465J1429D01*
G01X399314Y1296647D01*
X399390Y1296752D01*
Y1305370D01*
G02X399793Y1306266I1202J-2D01*
G01X400178Y1306609D01*
G02X400251Y1306650I132J-150D01*
G01X400659Y1306778D01*
G02X400741Y1306785I58J-191D01*
G01X400742D01*
X400953Y1306761D01*
X400954D01*
G03X401011Y1306758I55J497D01*
G03X401511Y1307258I0J500D01*
G03X401011Y1307758I-500J0D01*
G03X400954Y1307755I-2J-500D01*
G01X400922Y1307751D01*
X400742Y1307731D01*
X400741D01*
G02X400659Y1307738I-24J198D01*
G01X400251Y1307866D01*
G02X400178Y1307907I59J191D01*
G01X399793Y1308250D01*
G02X399390Y1309146I799J898D01*
G01Y1311586D01*
G03X399315Y1311741I-200J-1D01*
G01X399074Y1311936D01*
G03X398993Y1311975I-125J-156D01*
G01X398950Y1311985D01*
X398905Y1311976D01*
X398903D01*
G02X398584Y1311941I-322J1467D01*
G02X397082Y1313443I0J1502D01*
G02X398584Y1314945I1502J0D01*
G02X398903Y1314910I-3J-1502D01*
G01X398905D01*
X398950Y1314901D01*
X398993Y1314911D01*
G03X399074Y1314950I-44J195D01*
G01X399315Y1315145D01*
G03X399390Y1315300I-125J156D01*
G01Y1316087D01*
G02X399769Y1316962I1202J-1D01*
G01X399772Y1316964D01*
X401218Y1318410D01*
X401220Y1318413D01*
G02X402095Y1318792I876J-823D01*
G01X405421D01*
G02X406296Y1318413I-1J-1202D01*
G01X406298Y1318410D01*
X406546Y1318162D01*
X406549Y1318160D01*
G02X406928Y1317285I-823J-876D01*
G01Y1314515D01*
G03X407127Y1314316I199J1D01*
G01X409728D01*
G03X409870Y1314375I0J200D01*
G01X410045Y1314550D01*
G03X410104Y1314692I-141J142D01*
G01Y1318941D01*
G02X410483Y1319816I1202J-1D01*
G03X410488Y1319820I-122J158D01*
G01X410944Y1320276D01*
G03X410948Y1320281I-154J127D01*
G02X411823Y1320660I876J-823D01*
G01X414512D01*
G02X415387Y1320281I-1J-1202D01*
G01X415389Y1320278D01*
X416412Y1319255D01*
X416415Y1319253D01*
G02X416794Y1318378I-823J-876D01*
G01Y1311848D01*
G03X416919Y1311663I200J0D01*
G01X417319Y1311500D01*
X417437Y1311525D01*
X417480Y1311569D01*
G02X418558Y1312025I1078J-1046D01*
G02Y1309021I0J-1502D01*
G02X417480Y1309477I0J1502D01*
G01X417437Y1309521D01*
X417319Y1309546D01*
G37*
G36*
G01X430771Y1314669D02*
G02X430365Y1315696I1096J1027D01*
G02X433369I1502J0D01*
G02X432979Y1314687I-1502J1D01*
G01X432977Y1314685D01*
X432952Y1314656D01*
X432939Y1314623D01*
G03X432925Y1314549I186J-74D01*
G01X432927Y1314278D01*
G03X432980Y1314143I200J1D01*
G01X432981Y1314142D01*
G02X433387Y1313115I-1096J-1027D01*
G02X430383I-1502J0D01*
G02X430773Y1314124I1502J-1D01*
G01X430775Y1314126D01*
X430800Y1314155D01*
X430813Y1314188D01*
G03X430827Y1314262I-186J74D01*
G01X430825Y1314533D01*
G03X430772Y1314668I-200J-1D01*
G01X430771Y1314669D01*
G37*
G36*
G01X430914Y1324465D02*
G02X429530Y1323548I-1384J586D01*
G02Y1326554I0J1503D01*
G02X430480Y1326216I0J-1504D01*
G03X431101Y1326370I253J310D01*
G02X432485Y1327287I1384J-586D01*
G02Y1324281I0J-1503D01*
G02X431535Y1324619I0J1504D01*
G03X430914Y1324465I-253J-310D01*
G37*
G36*
G01X439290Y1151209D02*
X439811Y1151730D01*
G02X439953Y1151788I141J-142D01*
G01X458938D01*
G02X459080Y1151729I0J-200D01*
G01X459243Y1151566D01*
G02X459302Y1151424I-141J-142D01*
G01Y1130619D01*
G02X459243Y1130477I-200J0D01*
G01X459214Y1130448D01*
G02X459072Y1130389I-142J141D01*
G01X439647D01*
G02X439505Y1130448I0J200D01*
G01X439284Y1130669D01*
G02X439225Y1130811I141J142D01*
G01Y1131257D01*
X439222Y1131260D01*
Y1131669D01*
X439231D01*
Y1151067D01*
G02X439290Y1151209I200J0D01*
G37*
G36*
G01X504877D02*
X505398Y1151730D01*
G02X505540Y1151788I141J-142D01*
G01X524525D01*
G02X524667Y1151729I0J-200D01*
G01X524830Y1151566D01*
G02X524889Y1151424I-141J-142D01*
G01Y1130619D01*
G02X524830Y1130477I-200J0D01*
G01X524801Y1130448D01*
G02X524659Y1130389I-142J141D01*
G01X505234D01*
G02X505092Y1130448I0J200D01*
G01X504871Y1130669D01*
G02X504812Y1130811I141J142D01*
G01Y1131257D01*
X504809Y1131260D01*
Y1131669D01*
X504818D01*
Y1151067D01*
G02X504877Y1151209I200J0D01*
G37*
G36*
G01X408698Y1151814D02*
G02X408840Y1151873I142J-141D01*
G01X426949D01*
G02X427091Y1151814I0J-200D01*
G01X427311Y1151594D01*
G02X427370Y1151452I-141J-142D01*
G01Y1131669D01*
X427375D01*
Y1131106D01*
X427370Y1131101D01*
Y1130815D01*
G02X427311Y1130673I-200J0D01*
G01X427086Y1130448D01*
G02X426944Y1130389I-142J141D01*
G01X407965D01*
X407949Y1130405D01*
X407404D01*
X407331Y1130435D01*
X407306Y1130460D01*
Y1133409D01*
G02X407365Y1133551I200J0D01*
G01X407374Y1133560D01*
G03X407433Y1133702I-141J142D01*
G01Y1150466D01*
G02X407492Y1150608I200J0D01*
G01X408698Y1151814D01*
G37*
G36*
G01X474285D02*
G02X474427Y1151873I142J-141D01*
G01X492536D01*
G02X492678Y1151814I0J-200D01*
G01X492898Y1151594D01*
G02X492957Y1151452I-141J-142D01*
G01Y1131669D01*
X492962D01*
Y1131106D01*
X492957Y1131101D01*
Y1130815D01*
G02X492898Y1130673I-200J0D01*
G01X492673Y1130448D01*
G02X492531Y1130389I-142J141D01*
G01X473465D01*
X473450Y1130373D01*
X473065D01*
G02X472923Y1130432I0J200D01*
G01X472905Y1130450D01*
X472875Y1130523D01*
Y1133357D01*
G02X472934Y1133499I200J0D01*
G01X472961Y1133526D01*
G03X473020Y1133668I-141J142D01*
G01Y1150466D01*
G02X473079Y1150608I200J0D01*
G01X474285Y1151814D01*
G37*
G36*
G01X873404Y993105D02*
G02X872183Y992478I-1221J875D01*
G02Y995482I0J1502D01*
G02X873496Y994710I0J-1503D01*
G03X874170Y994671I349J194D01*
G02X875391Y995298I1221J-875D01*
G02Y992294I0J-1502D01*
G02X874078Y993066I0J1503D01*
G03X873404Y993105I-349J-194D01*
G37*
G36*
G01X889529Y993587D02*
X889497Y993554D01*
G02X888400Y993077I-1098J1025D01*
G02Y996081I0J1502D01*
G02X889627Y995446I0J-1503D01*
G01X889653Y995408D01*
X889730Y995365D01*
X890132Y995337D01*
X890214Y995370D01*
X890246Y995403D01*
G02X891343Y995880I1098J-1025D01*
G02X892663Y995094I0J-1501D01*
G01X892690Y995046D01*
X892781Y994990D01*
X893240Y994984D01*
X893333Y995036D01*
X893361Y995084D01*
G02X894660Y995832I1299J-754D01*
G02X895888Y995195I0J-1502D01*
G01X895917Y995153D01*
X896006Y995109D01*
X896440Y995120D01*
X896526Y995169D01*
X896553Y995212D01*
G02X897825Y995915I1272J-799D01*
G02Y992911I0J-1502D01*
G02X896597Y993548I0J1502D01*
G01X896568Y993590D01*
X896479Y993634D01*
X896045Y993623D01*
X895959Y993574D01*
X895932Y993531D01*
G02X894660Y992828I-1272J799D01*
G02X893340Y993614I0J1501D01*
G01X893313Y993662D01*
X893222Y993718D01*
X892763Y993724D01*
X892670Y993672D01*
X892642Y993624D01*
G02X891343Y992876I-1299J754D01*
G02X890116Y993511I0J1503D01*
G01X890090Y993549D01*
X890013Y993592D01*
X889611Y993620D01*
X889529Y993587D01*
G37*
G36*
G01X1039502Y1335766D02*
X1043704D01*
G02X1044204Y1335265I-1J-501D01*
G01Y1332865D01*
G02X1043702Y1332364I-502J1D01*
G01X1039500D01*
G02X1039000Y1332865I1J501D01*
G01Y1335265D01*
G02X1039502Y1335766I502J-1D01*
G37*
G36*
G01X1049204Y1339278D02*
G02X1050635Y1338630I1J-1902D01*
G01X1050659Y1338603D01*
X1050723Y1338568D01*
X1051022Y1338529D01*
G03X1051158Y1338561I25J198D01*
G01X1051159D01*
G02X1052221Y1338886I1063J-1577D01*
G02X1054122Y1336984I-1J-1902D01*
G01Y1336981D01*
G02X1053566Y1335639I-1902J2D01*
G01X1053471Y1335545D01*
G03X1053412Y1335403I141J-142D01*
G01Y1323611D01*
G02X1051511Y1321710I-1901J0D01*
G01X1051509D01*
G02X1050134Y1322299I1J1901D01*
G01X1050106Y1322329D01*
X1050030Y1322362D01*
X1049842D01*
X1049766Y1322329D01*
X1049738Y1322299D01*
G02X1049706Y1322266I-1381J1307D01*
G01X1049187Y1321747D01*
G02X1047842Y1321190I-1345J1345D01*
G01X1042925D01*
G02X1042115Y1321371I0J1903D01*
G03X1042030Y1321390I-85J-181D01*
G01X1040825D01*
G02X1040324Y1321892I1J502D01*
G01Y1324294D01*
G02X1040825Y1324794I501J-1D01*
G01X1042030D01*
G03X1042115Y1324813I0J200D01*
G02X1042925Y1324994I810J-1722D01*
G01X1046260D01*
G03X1046460Y1325194I0J200D01*
G01Y1336537D01*
G02X1047016Y1337879I1902J-2D01*
G01X1047859Y1338722D01*
G02X1049204Y1339278I1344J-1346D01*
G37*
G36*
G01X1026484Y821496D02*
Y827596D01*
G02X1027585Y828698I1101J1D01*
G01X1033685D01*
G02X1034786Y827596I-1J-1102D01*
G01Y821496D01*
G02X1033685Y820394I-1101J-1D01*
G01X1027585D01*
G02X1026484Y821496I1J1102D01*
G37*
G36*
G01X1353464Y1151209D02*
X1353985Y1151730D01*
G02X1354127Y1151788I141J-142D01*
G01X1373112D01*
G02X1373254Y1151729I0J-200D01*
G01X1373417Y1151566D01*
G02X1373476Y1151424I-141J-142D01*
G01Y1130619D01*
G02X1373417Y1130477I-200J0D01*
G01X1373388Y1130448D01*
G02X1373246Y1130389I-142J141D01*
G01X1353821D01*
G02X1353679Y1130448I0J200D01*
G01X1353458Y1130669D01*
G02X1353399Y1130811I141J142D01*
G01Y1131257D01*
X1353396Y1131260D01*
Y1131669D01*
X1353405D01*
Y1151067D01*
G02X1353464Y1151209I200J0D01*
G37*
G36*
G01X1419051D02*
X1419572Y1151730D01*
G02X1419714Y1151788I141J-142D01*
G01X1438699D01*
G02X1438841Y1151729I0J-200D01*
G01X1439004Y1151566D01*
G02X1439063Y1151424I-141J-142D01*
G01Y1130619D01*
G02X1439004Y1130477I-200J0D01*
G01X1438975Y1130448D01*
G02X1438833Y1130389I-142J141D01*
G01X1419408D01*
G02X1419266Y1130448I0J200D01*
G01X1419045Y1130669D01*
G02X1418986Y1130811I141J142D01*
G01Y1131257D01*
X1418983Y1131260D01*
Y1131669D01*
X1418992D01*
Y1151067D01*
G02X1419051Y1151209I200J0D01*
G37*
G36*
G01X1322872Y1151814D02*
G02X1323014Y1151873I142J-141D01*
G01X1341123D01*
G02X1341265Y1151814I0J-200D01*
G01X1341485Y1151594D01*
G02X1341544Y1151452I-141J-142D01*
G01Y1131669D01*
X1341549D01*
Y1131106D01*
X1341544Y1131101D01*
Y1130815D01*
G02X1341485Y1130673I-200J0D01*
G01X1341260Y1130448D01*
G02X1341118Y1130389I-142J141D01*
G01X1322143D01*
Y1130376D01*
X1321577D01*
G02X1321435Y1130435I0J200D01*
G01X1321425Y1130445D01*
X1321395Y1130518D01*
Y1133334D01*
G02X1321454Y1133476I200J0D01*
G01X1321548Y1133570D01*
G03X1321607Y1133712I-141J142D01*
G01Y1150466D01*
G02X1321666Y1150608I200J0D01*
G01X1322872Y1151814D01*
G37*
G36*
G01X1388459D02*
G02X1388601Y1151873I142J-141D01*
G01X1406710D01*
G02X1406852Y1151814I0J-200D01*
G01X1407072Y1151594D01*
G02X1407131Y1151452I-141J-142D01*
G01Y1131669D01*
X1407136D01*
Y1131106D01*
X1407131Y1131101D01*
Y1130815D01*
G02X1407072Y1130673I-200J0D01*
G01X1406847Y1130448D01*
G02X1406705Y1130389I-142J141D01*
G01X1387734D01*
Y1130344D01*
X1387249D01*
G02X1387107Y1130403I0J200D01*
G01X1387070Y1130440D01*
G02X1387011Y1130582I141J142D01*
G01Y1133332D01*
G02X1387070Y1133474I200J0D01*
G01X1387135Y1133539D01*
G03X1387194Y1133681I-141J142D01*
G01Y1150466D01*
G02X1387253Y1150608I200J0D01*
G01X1388459Y1151814D01*
G37*
G36*
G01X1781264Y957113D02*
G03X1781852I294J271D01*
G02X1784064I1106J-1019D01*
G03X1784652I294J271D01*
G02X1785758Y957598I1106J-1019D01*
G02X1787261Y956095I0J-1503D01*
G02X1786776Y954989I-1504J0D01*
G03Y954401I271J-294D01*
G02X1787261Y953295I-1019J-1106D01*
G02X1785758Y951792I-1503J0D01*
G02X1784652Y952277I0J1504D01*
G03X1784064I-294J-271D01*
G02X1781852I-1106J1019D01*
G03X1781264I-294J-271D01*
G02X1780158Y951792I-1106J1019D01*
G02X1778655Y953295I0J1503D01*
G02X1779140Y954401I1504J0D01*
G03Y954989I-271J294D01*
G02X1778655Y956095I1019J1106D01*
G02X1780158Y957598I1503J0D01*
G02X1781264Y957113I0J-1504D01*
G37*
G36*
G01X1640562Y707253D02*
Y706799D01*
G02X1640159Y705874I-1262J0D01*
G03X1640153Y705869I125J-156D01*
G01X1639228Y704944D01*
G02X1638336Y704574I-893J892D01*
G01X1636091D01*
G03X1635906Y704450I0J-200D01*
G01Y704449D01*
G02X1635847Y704341I-466J185D01*
G03X1635809Y704224I162J-117D01*
G01Y704095D01*
G03X1635847Y703978I200J0D01*
G02X1635942Y703685I-406J-294D01*
G01Y702083D01*
G02X1635441Y701582I-501J0D01*
G01X1633041D01*
G02X1632874Y701610I-2J501D01*
G01X1632842Y701622D01*
X1632116D01*
G02X1631225Y701991I0J1261D01*
G01X1630708Y702508D01*
G02X1630338Y703400I892J893D01*
G01Y705100D01*
G02X1630708Y705992I1262J-1D01*
G01X1631408Y706692D01*
G02X1632300Y707062I893J-892D01*
G01X1632442D01*
X1632545Y707136D01*
X1632566Y707197D01*
G02X1633041Y707538I475J-160D01*
G01X1635441D01*
G02X1635906Y707224I0J-501D01*
G01Y707222D01*
X1635929Y707166D01*
X1636030Y707098D01*
X1637730D01*
G03X1637872Y707156I1J200D01*
G01X1638038Y707322D01*
Y707331D01*
X1637901Y707468D01*
G03X1637899Y707470I-142J-140D01*
G02X1637298Y708900I1401J1430D01*
G02X1637457Y709682I2003J0D01*
G03X1637440Y709871I-184J79D01*
G01X1637255Y710149D01*
G03X1637089Y710238I-166J-111D01*
G01X1635447D01*
G03X1635308Y710182I0J-200D01*
G02X1634690Y709932I-619J640D01*
G01X1633836D01*
G02X1633636Y710132I0J200D01*
G01Y710168D01*
X1632548D01*
G03X1632403Y710106I0J-200D01*
G02X1631027Y709516I-1376J1310D01*
G01X1628200D01*
G02Y713318I0J1901D01*
G01X1631027D01*
G02X1632403Y712728I0J-1900D01*
G03X1632548Y712666I145J138D01*
G01X1633436D01*
G03X1633636Y712866I0J200D01*
G01Y712902D01*
X1634689D01*
G02X1635125Y712788I0J-890D01*
G03X1635127Y712786I142J140D01*
G01X1635150Y712774D01*
X1635197Y712762D01*
X1638700D01*
G02X1639592Y712392I-1J-1262D01*
G01X1640192Y711792D01*
G02X1640562Y710900I-892J-893D01*
G01Y710546D01*
G03X1640629Y710397I200J0D01*
G02X1641302Y708900I-1328J-1497D01*
G01Y708899D01*
G02X1640629Y707402I-2002J0D01*
G03X1640562Y707253I133J-149D01*
G37*
G36*
G01X1631098Y789936D02*
Y790989D01*
G02X1631294Y791546I890J0D01*
G03X1631338Y791671I-156J125D01*
G01Y793642D01*
G03X1631236Y793816I-200J0D01*
G01X1630933Y793988D01*
G03X1630732Y793985I-98J-174D01*
G02X1629700Y793698I-1033J1715D01*
G02X1628270Y794299I0J2002D01*
G03X1628268Y794301I-142J-140D01*
G01X1628131Y794438D01*
X1628122D01*
X1626228Y792544D01*
G02X1625336Y792174I-893J892D01*
G01X1625239D01*
G02X1625147Y791941I-498J62D01*
G03X1625109Y791824I162J-117D01*
G01Y791695D01*
G03X1625147Y791578I200J0D01*
G02X1625242Y791285I-406J-294D01*
G01Y789683D01*
G02X1624741Y789182I-501J0D01*
G01X1622341D01*
G02X1622174Y789210I-2J501D01*
G01X1622142Y789222D01*
X1621416D01*
G02X1620525Y789591I0J1261D01*
G01X1619908Y790208D01*
G02X1619538Y791100I892J893D01*
G01Y792900D01*
G02X1619908Y793792I1262J-1D01*
G01X1620444Y794328D01*
G02X1621336Y794698I893J-892D01*
G01X1621691D01*
G03X1621876Y794822I0J200D01*
G01Y794823D01*
G02X1622341Y795138I465J-186D01*
G01X1624741D01*
G02X1624985Y795074I-1J-502D01*
G01X1625044Y795041D01*
X1625176Y795060D01*
X1626669Y796553D01*
G03X1626674Y796559I-151J131D01*
G02X1627599Y796962I925J-859D01*
G01X1628053D01*
G03X1628202Y797029I0J200D01*
G02X1629700Y797702I1497J-1329D01*
G02X1631198Y797029I1J-2002D01*
G03X1631347Y796962I149J133D01*
G01X1631800D01*
G02X1632692Y796592I-1J-1262D01*
G01X1633492Y795792D01*
G02X1633862Y794900I-892J-893D01*
G01Y791627D01*
G03X1633900Y791510I200J0D01*
G02X1634068Y790990I-722J-520D01*
G01Y790136D01*
G02X1633868Y789936I-200J0D01*
G01X1633832D01*
Y788848D01*
G03X1633894Y788703I200J0D01*
G02X1634484Y787327I-1310J-1376D01*
G02X1632583Y785426I-1901J0D01*
G01X1629927D01*
G02Y789228I0J1901D01*
G01X1631134D01*
G03X1631334Y789428I0J200D01*
G01Y789736D01*
G03X1631134Y789936I-200J0D01*
G01X1631098D01*
G37*
G36*
G01X1628856Y716628D02*
G02X1628355Y716128I-501J1D01*
G01X1625955D01*
G02X1625490Y716442I0J501D01*
G01Y716444D01*
X1625467Y716500D01*
X1625366Y716568D01*
X1622147D01*
G03X1621998Y716501I0J-200D01*
G02X1620500Y715828I-1497J1329D01*
G02X1619002Y716501I-1J2002D01*
G03X1618853Y716568I-149J-133D01*
G01X1615367D01*
G03X1615242Y716525I-1J-200D01*
G02X1614690Y716332I-553J697D01*
G01X1613836D01*
G02X1613636Y716532I0J200D01*
G01Y716568D01*
X1611768D01*
G03X1611568Y716368I0J-200D01*
G01Y716332D01*
X1610515D01*
G02X1609625Y717228I0J890D01*
G01X1609626D01*
Y718406D01*
X1609625D01*
G02X1609740Y718849I890J5D01*
G01X1609752Y718871D01*
X1609766Y718921D01*
Y721555D01*
G03X1609738Y721658I-200J1D01*
G02X1609525Y722427I1289J771D01*
G02X1612529I1502J0D01*
G02X1612316Y721658I-1502J2D01*
G03X1612288Y721555I172J-102D01*
G01Y719266D01*
G03X1612488Y719066I200J0D01*
G01X1613436D01*
G03X1613636Y719266I0J200D01*
G01Y719302D01*
X1614691D01*
G02X1615215Y719131I-1J-890D01*
G03X1615333Y719092I119J161D01*
G01X1618853D01*
G03X1619002Y719159I0J200D01*
G02X1620421Y719830I1497J-1330D01*
G03X1620555Y719889I-8J200D01*
G01X1620639Y719973D01*
G03X1620698Y720115I-141J142D01*
G01Y721135D01*
G03X1620639Y721277I-200J0D01*
G01X1620225Y721691D01*
G03X1620133Y721744I-142J-141D01*
G01X1620132D01*
G02X1618998Y723200I368J1456D01*
G02X1620500Y724702I1502J0D01*
G02X1621956Y723569I0J-1502D01*
G01Y723567D01*
G03X1622009Y723475I194J50D01*
G01X1623381Y722103D01*
G03X1623523Y722044I142J141D01*
G01X1625756D01*
X1625788Y722056D01*
G02X1625955Y722084I165J-473D01*
G01X1628355D01*
G02X1628856Y721583I0J-501D01*
G01Y719981D01*
G02X1628761Y719688I-501J1D01*
G03X1628723Y719571I162J-117D01*
G01Y719442D01*
G03X1628761Y719325I200J0D01*
G02X1628856Y719032I-406J-294D01*
G01Y716628D01*
G37*
G36*
G01X1635942Y719983D02*
G02X1635441Y719482I-501J0D01*
G01X1633041D01*
G02X1632874Y719510I-2J501D01*
G01X1632842Y719522D01*
X1632016D01*
G02X1631125Y719891I0J1261D01*
G01X1630408Y720608D01*
G02X1630038Y721500I892J893D01*
G01Y723200D01*
G02X1630408Y724092I1262J-1D01*
G01X1631008Y724692D01*
G02X1631900Y725062I893J-892D01*
G01X1632476D01*
X1632571Y725120D01*
X1632597Y725169D01*
G02X1633041Y725438I444J-232D01*
G01X1635441D01*
G02X1635906Y725124I0J-501D01*
G01Y725122D01*
X1635929Y725066D01*
X1636030Y724998D01*
X1636565D01*
G02X1637457Y724628I-1J-1262D01*
G01X1637565Y724520D01*
G03X1637706Y724462I141J142D01*
G01X1638453D01*
G03X1638602Y724529I0J200D01*
G02X1640100Y725202I1497J-1329D01*
G01X1640114D01*
X1640257Y725343D01*
G03X1640316Y725485I-141J142D01*
G01Y726668D01*
G03X1640116Y726868I-200J0D01*
G01X1639908D01*
X1639832Y726835D01*
X1639804Y726805D01*
G02X1638429Y726216I-1376J1312D01*
G01X1635283D01*
G02Y730018I0J1901D01*
G01X1638427D01*
G02X1639803Y729428I0J-1900D01*
G03X1639948Y729366I145J138D01*
G01X1640836D01*
G03X1641036Y729566I0J200D01*
G01Y729602D01*
X1642089D01*
G02X1642979Y728706I0J-890D01*
G01X1642978D01*
Y727528D01*
X1642979D01*
G02X1642864Y727085I-890J-5D01*
G01X1642852Y727063D01*
X1642838Y727013D01*
Y724576D01*
G02X1642469Y723685I-1261J0D01*
G01X1642131Y723347D01*
X1642101Y723272D01*
X1642102Y723232D01*
Y723200D01*
G02X1640100Y721198I-2002J0D01*
G01X1640099D01*
G02X1638602Y721871I0J2002D01*
G03X1638453Y721938I-149J-133D01*
G01X1637101D01*
G02X1636209Y722308I1J1262D01*
G01X1636190Y722327D01*
G03X1635908I-141J-142D01*
G01X1635889Y722308D01*
X1635875Y722285D01*
G02X1635847Y722241I-437J247D01*
G03X1635809Y722124I162J-117D01*
G01Y721995D01*
G03X1635847Y721878I200J0D01*
G02X1635942Y721585I-406J-294D01*
G01Y719983D01*
G37*
G36*
G01X1629156Y731228D02*
G02X1628655Y730728I-501J1D01*
G01X1626255D01*
G02X1625790Y731042I0J501D01*
G01Y731044D01*
X1625767Y731100D01*
X1625666Y731168D01*
X1622847D01*
G03X1622698Y731101I0J-200D01*
G02X1621200Y730428I-1497J1329D01*
G02X1619702Y731101I-1J2002D01*
G03X1619553Y731168I-149J-133D01*
G01X1615667D01*
G03X1615542Y731125I-1J-200D01*
G02X1614990Y730932I-553J697D01*
G01X1614136D01*
G02X1613936Y731132I0J200D01*
G01Y731168D01*
X1612068D01*
G03X1611868Y730968I0J-200D01*
G01Y730932D01*
X1610815D01*
G02X1609925Y731828I0J890D01*
G01X1609926D01*
Y733006D01*
X1609925D01*
G02X1610040Y733449I890J5D01*
G01X1610052Y733471D01*
X1610066Y733521D01*
Y735101D01*
G03X1610038Y735204I-200J1D01*
G02X1609825Y735973I1289J771D01*
G02X1612829I1502J0D01*
G02X1612616Y735204I-1502J2D01*
G03X1612588Y735101I172J-102D01*
G01Y733866D01*
G03X1612788Y733666I200J0D01*
G01X1613736D01*
G03X1613936Y733866I0J200D01*
G01Y733902D01*
X1614991D01*
G02X1615515Y733731I-1J-890D01*
G03X1615633Y733692I119J161D01*
G01X1619553D01*
G03X1619702Y733759I0J200D01*
G02X1621200Y734432I1497J-1329D01*
G01X1621216D01*
G03X1621402Y734555I1J200D01*
G01X1621544Y734896D01*
G03X1621501Y735115I-184J78D01*
G01X1619825Y736791D01*
G03X1619733Y736844I-142J-141D01*
G01X1619732D01*
G02X1618598Y738300I368J1456D01*
G02X1620100Y739802I1502J0D01*
G02X1621556Y738669I0J-1502D01*
G01Y738667D01*
G03X1621609Y738575I194J50D01*
G01X1623481Y736703D01*
G03X1623623Y736644I142J141D01*
G01X1626056D01*
X1626088Y736656D01*
G02X1626255Y736684I165J-473D01*
G01X1628655D01*
G02X1629156Y736183I0J-501D01*
G01Y734581D01*
G02X1629061Y734288I-501J1D01*
G03X1629023Y734171I162J-117D01*
G01Y734042D01*
G03X1629061Y733925I200J0D01*
G02X1629156Y733632I-406J-294D01*
G01Y731228D01*
G37*
G36*
G01X1636242Y752783D02*
G02X1635741Y752282I-501J0D01*
G01X1633341D01*
G02X1633174Y752310I-2J501D01*
G01X1633142Y752322D01*
X1632416D01*
G02X1631525Y752691I0J1261D01*
G01X1630908Y753308D01*
G02X1630538Y754200I892J893D01*
G01Y755800D01*
G02X1630908Y756692I1262J-1D01*
G01X1631608Y757392D01*
G02X1632500Y757762I893J-892D01*
G01X1632742D01*
X1632845Y757836D01*
X1632866Y757897D01*
G02X1633154Y758201I475J-161D01*
G01X1633155D01*
G03X1633280Y758387I-75J185D01*
G01Y760111D01*
G03X1633213Y760261I-200J1D01*
G02X1632596Y761286I1328J1498D01*
G01X1632580Y761353D01*
X1632472Y761438D01*
X1631027D01*
G03X1630910Y761400I0J-200D01*
G02X1630390Y761232I-520J722D01*
G01X1629536D01*
G02X1629336Y761432I0J200D01*
G01Y761468D01*
X1628248D01*
G03X1628103Y761406I0J-200D01*
G02X1626727Y760816I-1376J1310D01*
G01X1626688D01*
G03X1626546Y760757I0J-200D01*
G01X1625345Y759555D01*
G02X1624000Y758998I-1345J1345D01*
G02X1622098Y760900I0J1902D01*
G02X1622655Y762245I1902J0D01*
G01X1624472Y764062D01*
G02X1625814Y764618I1344J-1346D01*
G01X1626727D01*
G02X1628103Y764028I0J-1900D01*
G03X1628248Y763966I145J138D01*
G01X1629136D01*
G03X1629336Y764166I0J200D01*
G01Y764202D01*
X1630389D01*
G02X1630946Y764006I0J-890D01*
G03X1631071Y763962I125J156D01*
G01X1633600D01*
G02X1634250Y763782I0J-1262D01*
G03X1634370Y763754I103J171D01*
G02X1634540Y763761I167J-1995D01*
G01X1634541D01*
G02X1636543Y761759I0J-2002D01*
G02X1635869Y760261I-2002J0D01*
G03X1635802Y760111I133J-149D01*
G01Y758387D01*
G03X1635927Y758201I200J-1D01*
G01X1635928D01*
G02X1636242Y757736I-187J-465D01*
G01Y755334D01*
G02X1636147Y755041I-501J1D01*
G03X1636109Y754924I162J-117D01*
G01Y754795D01*
G03X1636147Y754678I200J0D01*
G02X1636242Y754385I-406J-294D01*
G01Y752783D01*
G37*
G36*
G01X1635568Y777236D02*
X1635532D01*
G03X1635332Y777036I0J-200D01*
G01Y776148D01*
G03X1635394Y776003I200J0D01*
G02X1635984Y774627I-1310J-1376D01*
G02X1634083Y772726I-1901J0D01*
G01X1630327D01*
G02Y776528I0J1901D01*
G01X1632634D01*
G03X1632834Y776728I0J200D01*
G01Y777036D01*
G03X1632634Y777236I-200J0D01*
G01X1632598D01*
Y778289D01*
G02X1632876Y778935I890J0D01*
G03X1632938Y779080I-138J145D01*
G01Y780394D01*
G03X1632879Y780536I-200J0D01*
G01X1632436Y780979D01*
G03X1632294Y781038I-142J-141D01*
G01X1631147D01*
G03X1630998Y780971I0J-200D01*
G02X1629501Y780298I-1497J1329D01*
G01X1629500D01*
G02X1628718Y780457I0J2003D01*
G01X1628661Y780481D01*
X1628542Y780458D01*
X1627928Y779844D01*
G02X1627036Y779474I-893J892D01*
G01X1625591D01*
G03X1625406Y779350I0J-200D01*
G01Y779349D01*
G02X1625347Y779241I-466J185D01*
G03X1625309Y779124I162J-117D01*
G01Y778995D01*
G03X1625347Y778878I200J0D01*
G02X1625442Y778585I-406J-294D01*
G01Y776983D01*
G02X1624941Y776482I-501J0D01*
G01X1622541D01*
G02X1622343Y776522I-2J501D01*
G01X1622305Y776538D01*
X1621600D01*
G02X1620708Y776908I1J1262D01*
G01X1620208Y777408D01*
G02X1619838Y778300I892J893D01*
G01Y780200D01*
G02X1620208Y781092I1262J-1D01*
G01X1620744Y781628D01*
G02X1621636Y781998I893J-892D01*
G01X1621891D01*
G03X1622076Y782122I0J200D01*
G01Y782123D01*
G02X1622541Y782438I465J-186D01*
G01X1624941D01*
G02X1625406Y782124I0J-501D01*
G01Y782122D01*
X1625429Y782066D01*
X1625530Y781998D01*
X1626430D01*
G03X1626572Y782057I0J200D01*
G01X1627707Y783191D01*
X1627721Y783219D01*
G02X1629500Y784302I1779J-920D01*
G01X1629501D01*
G02X1630998Y783629I0J-2002D01*
G03X1631147Y783562I149J133D01*
G01X1632900D01*
G02X1633792Y783192I-1J-1262D01*
G01X1635092Y781892D01*
G02X1635462Y781000I-892J-893D01*
G01Y778758D01*
G03X1635481Y778674I200J1D01*
G01Y778673D01*
G02X1635568Y778289I-803J-384D01*
G01Y777236D01*
G37*
G36*
G01X1652351Y992416D02*
G02X1651442Y993796I593J1380D01*
G02X1654446I1502J0D01*
G02X1653908Y992644I-1502J0D01*
G03X1654007Y991970I257J-307D01*
G02X1654916Y990590I-593J-1380D01*
G02X1651912I-1502J0D01*
G02X1652450Y991742I1502J0D01*
G03X1652351Y992416I-257J307D01*
G37*
G36*
G01X1760531Y991010D02*
G02X1760201Y990973I-331J1465D01*
G02X1761703Y992475I0J1502D01*
G01Y992474D01*
G02X1761676Y992191I-1502J1D01*
G03X1762156Y991725I393J-76D01*
G02X1762486Y991762I331J-1465D01*
G02X1760984Y990260I0J-1502D01*
G01Y990261D01*
G02X1761011Y990544I1502J-1D01*
G03X1760531Y991010I-393J76D01*
G37*
G36*
G01X1756089Y541450D02*
G02Y544454I0J1502D01*
G02X1757193Y543971I0J-1503D01*
G01X1757222Y543939D01*
X1757302Y543905D01*
X1757647Y543915D01*
G03X1757796Y543989I-6J200D01*
G02X1758957Y544538I1161J-953D01*
G02Y541534I0J-1502D01*
G02X1757853Y542017I0J1503D01*
G01X1757824Y542049D01*
X1757744Y542083D01*
X1757399Y542073D01*
G03X1757250Y541999I6J-200D01*
G02X1756089Y541450I-1161J953D01*
G37*
G36*
G01X1777244Y834940D02*
X1777296Y834904D01*
X1777320D01*
Y834885D01*
X1777389Y834825D01*
G02X1778072Y833319I-1319J-1506D01*
G01Y828772D01*
G03X1778272Y828572I200J0D01*
G01X1779404D01*
G02X1780760Y828042I-1J-2002D01*
G01X1780819Y827987D01*
X1780979Y827990D01*
X1781515Y828526D01*
G02X1785427I1956J-1957D01*
G01X1787948Y826005D01*
G03X1788090Y825946I142J141D01*
G01X1792066D01*
G03X1792197Y825994I1J200D01*
G02X1792867Y826421I1806J-2095D01*
G03X1792985Y826604I-82J182D01*
G01Y827307D01*
G02X1793487Y827809I502J0D01*
G01X1799387D01*
G02X1799889Y827307I0J-502D01*
G01Y823048D01*
G02X1799814Y822784I-502J0D01*
G03X1799784Y822679I170J-105D01*
G01Y822558D01*
G03X1799814Y822453I200J0D01*
G02X1799888Y822189I-428J-262D01*
G01Y820489D01*
G02X1799814Y820225I-502J-2D01*
G03X1799784Y820120I170J-105D01*
G01Y819999D01*
G03X1799814Y819894I200J0D01*
G02X1799888Y819630I-428J-262D01*
G01Y817928D01*
G02X1799387Y817428I-501J1D01*
G01X1797621D01*
G03X1797499Y817387I-1J-200D01*
G02X1796437Y817028I-1062J1391D01*
G01X1791056D01*
G02X1789818Y817542I1J1751D01*
G01X1789803Y817557D01*
G02X1789290Y818794I1237J1238D01*
G01Y818796D01*
G02X1789293Y818908I1751J9D01*
G01X1789296Y818949D01*
X1789268Y819027D01*
X1789040Y819271D01*
G03X1788894Y819334I-146J-137D01*
G01X1788104D01*
G03X1787962Y819275I0J-200D01*
G01X1785427Y816740D01*
G02X1781515I-1956J1957D01*
G01X1778980Y819275D01*
G03X1778838Y819334I-142J-141D01*
G01X1766528D01*
G03X1766386Y819275I0J-200D01*
G01X1766038Y818927D01*
G02X1764082Y818116I-1957J1956D01*
G02X1762613Y818539I1J2767D01*
G03X1762401I-106J-170D01*
G02X1760932Y818116I-1470J2344D01*
G02X1758976Y818927I1J2767D01*
G01X1758778Y819125D01*
G03X1758492Y819121I-141J-142D01*
G02X1757402Y818653I-1090J1035D01*
G02X1756951Y818722I-1J1501D01*
G03X1756757Y818680I-60J-191D01*
G02X1754906Y817970I-1851J2058D01*
G02X1752140Y820737I1J2767D01*
G01Y820935D01*
G02X1752639Y822518I2766J-2D01*
G03Y822748I-164J115D01*
G02X1752140Y824333I2267J1585D01*
G02X1754906Y827100I2766J1D01*
G02X1756605Y826516I-1J-2767D01*
G03X1756807Y826490I123J158D01*
G02X1757402Y826613I595J-1380D01*
G02X1758492Y826145I0J-1503D01*
G03X1758778Y826141I145J138D01*
G01X1758976Y826339D01*
G02X1760932Y827150I1957J-1956D01*
G02X1762401Y826727I-1J-2767D01*
G03X1762613I106J170D01*
G02X1764082Y827150I1470J-2344D01*
G02X1766038Y826339I-1J-2767D01*
G01X1766372Y826005D01*
G03X1766514Y825946I142J141D01*
G01X1773599D01*
G03X1773748Y826012I1J200D01*
G01X1773947Y826231D01*
G03X1773998Y826384I-148J134D01*
G02X1773990Y826570I1993J179D01*
G02X1774062Y827105I2001J3D01*
G01X1774070Y827131D01*
Y833319D01*
G02X1774753Y834825I2002J0D01*
G01X1774822Y834885D01*
Y834904D01*
X1774846D01*
X1774898Y834940D01*
G03X1774900Y834942I-140J142D01*
G02X1777242I1171J-1624D01*
G03X1777244Y834940I142J140D01*
G37*
G54D283*
X205941Y668934D03*
X248090Y691114D03*
X244267Y696911D03*
X254634Y698241D03*
X111993Y710102D03*
X380963Y731000D03*
X391470Y732865D03*
X235790Y754332D03*
X489406Y797558D03*
X459245Y807152D03*
X248506Y812042D03*
X256303Y812254D03*
X362042Y814772D03*
X241204Y814841D03*
X365691Y815127D03*
X237591Y815266D03*
X371507Y815303D03*
X274096Y820725D03*
X473654Y821234D03*
X255289Y824340D03*
X479448Y828594D03*
X274697Y830951D03*
X252305Y831018D03*
X358207Y836462D03*
X472399Y839566D03*
X463404Y846870D03*
X479700Y847600D03*
X275123Y847874D03*
X477574Y860815D03*
X465492Y861970D03*
X460498Y870334D03*
X471726Y883705D03*
X471110Y921577D03*
X368067Y925136D03*
X474540Y927341D03*
X471068Y930235D03*
X368626Y931346D03*
X471876Y937236D03*
X491616Y938771D03*
X494315Y941212D03*
X281980Y953926D03*
X439434Y1322369D03*
X391284Y1307238D03*
X386415Y1321645D03*
X425582Y1291743D03*
X440896Y1311366D03*
X440906Y1289198D03*
X430527D03*
X434424Y1286274D03*
X437991Y1286544D03*
X451304Y1297045D03*
Y1293045D03*
X423762Y1305298D03*
X411174Y1282776D03*
X423741Y1300115D03*
X423721Y1310523D03*
X397695Y1287071D03*
X391691Y1326715D03*
X924956Y994321D03*
X916932Y994405D03*
X909166Y994188D03*
X912690Y994350D03*
X878976Y994020D03*
X1385052Y1303139D03*
X1389052D03*
X1051550Y823146D03*
X1657042Y773604D03*
X1656112Y768669D03*
X1750879Y541940D03*
X1753860Y997271D03*
X1748677Y993986D03*
X1745824Y987058D03*
X1749314Y987904D03*
X1751854Y991297D03*
X1758881Y995633D03*
X1773810Y990821D03*
X1774476Y995049D03*
G54D281*
X359376Y290592D03*
X257993Y307994D03*
X164496Y309405D03*
X170215Y311671D03*
X230842Y313888D03*
X234986Y336161D03*
X236264Y342494D03*
X233258Y359186D03*
X126131Y359511D03*
X125753Y365856D03*
X98255Y374510D03*
X100120Y377898D03*
X100066Y381976D03*
X498727Y1128759D03*
X432838Y1128821D03*
X429348Y1129092D03*
X495236Y1129094D03*
X988389Y1302558D03*
X1307167Y1245696D03*
X1347300Y1128332D03*
X1343725Y1128738D03*
X1413177Y1128894D03*
X1409425Y1129238D03*
X1531947Y1046212D03*
X1532067Y1041832D03*
X1521939Y1040818D03*
X1522099Y1035521D03*
X1524953Y1051037D03*
X1531961Y1050849D03*
G54D286*
X1795900Y852600D03*
G54D287*
X1817323Y1567323D03*
G54D284*
X116731Y1066535D03*
Y1263386D03*
X352952Y1066535D03*
Y1263386D03*
X573818Y1066535D03*
Y1263386D03*
X810038Y1066535D03*
Y1263386D03*
X1030905Y1066535D03*
Y1263386D03*
X1267125Y1066535D03*
Y1263386D03*
X1487991Y1066535D03*
Y1263386D03*
X1724212Y1066535D03*
Y1263386D03*
G54D285*
X770472Y1490945D03*
X820079Y388583D03*
X1020866D03*
X1070472Y1490945D03*
G54D282*
X184851Y334492D03*
%LPD*%
G75*
G36*
G01X425895Y1131897D02*
X425695Y1131697D01*
X408695D01*
X408529Y1131862D01*
Y1134057D01*
Y1148791D01*
Y1149594D01*
X409092Y1150157D01*
X409895D01*
X414122D01*
X415263D01*
X425312D01*
X425895Y1149574D01*
Y1131897D01*
G37*
G36*
G01X411825Y1319658D02*
X414511D01*
G02X414652Y1319599I-1J-200D01*
G01X415733Y1318518D01*
G02X415792Y1318377I-141J-142D01*
G01Y1292499D01*
G02X415733Y1292357I-200J0D01*
G01X413864Y1290487D01*
G02X413702Y1290430I-141J142D01*
G01X413699D01*
G03X413526Y1290440I-173J-1491D01*
G03X412563Y1290090I1J-1502D01*
G01X412536Y1290068D01*
X412441Y1290033D01*
G02X412371Y1290020I-71J187D01*
G01X401848D01*
G02X401706Y1290079I0J200D01*
G01X400451Y1291335D01*
G02X400392Y1291476I141J142D01*
G01Y1293686D01*
G02X400418Y1293785I200J0D01*
G01X400476Y1293888D01*
X400508Y1293922D01*
X400530Y1293935D01*
G03Y1296461I-814J1263D01*
G01X400508Y1296474D01*
X400476Y1296508D01*
X400418Y1296611D01*
G02X400392Y1296710I174J99D01*
G01Y1305369D01*
G02X400459Y1305518I200J0D01*
G01X400715Y1305746D01*
X400795Y1305771D01*
X400838Y1305766D01*
G03X401011Y1305756I173J1491D01*
G03Y1308760I0J1502D01*
G03X400838Y1308750I0J-1501D01*
G01X400795Y1308745D01*
X400715Y1308770D01*
X400459Y1308998D01*
G02X400392Y1309147I133J149D01*
G01Y1316085D01*
G02X400451Y1316227I200J0D01*
G01X401955Y1317731D01*
G02X402097Y1317790I142J-141D01*
G01X405420D01*
G02X405561Y1317731I-1J-200D01*
G01X405867Y1317425D01*
G02X405926Y1317284I-141J-142D01*
G01Y1313714D01*
G03X405985Y1313572I200J0D01*
G01X406184Y1313373D01*
G03X406326Y1313314I142J141D01*
G01X410142D01*
G03X410284Y1313373I0J200D01*
G01X410562Y1313651D01*
X410563Y1313652D01*
G03X410575Y1313664I-843J855D01*
G01X410576Y1313665D01*
X410755Y1313844D01*
X410756Y1313845D01*
G03X410768Y1313857I-843J855D01*
G01X410769Y1313858D01*
X411047Y1314136D01*
G03X411106Y1314278I-141J142D01*
G01Y1318939D01*
G02X411165Y1319081I200J0D01*
G01X411683Y1319599D01*
G02X411825Y1319658I142J-141D01*
G37*
G36*
G01X458023Y1131897D02*
X457823Y1131697D01*
X440823D01*
X440657Y1131862D01*
Y1134057D01*
Y1148791D01*
Y1149594D01*
X441220Y1150157D01*
X442023D01*
X446250D01*
X447391D01*
X457440D01*
X458023Y1149574D01*
Y1131897D01*
G37*
G36*
G01X491482D02*
X491282Y1131697D01*
X474282D01*
X474116Y1131862D01*
Y1134057D01*
Y1148791D01*
Y1149594D01*
X474679Y1150157D01*
X475482D01*
X479709D01*
X480850D01*
X490899D01*
X491482Y1149574D01*
Y1131897D01*
G37*
G36*
G01X523610D02*
X523410Y1131697D01*
X506410D01*
X506244Y1131862D01*
Y1134057D01*
Y1148791D01*
Y1149594D01*
X506807Y1150157D01*
X507610D01*
X511837D01*
X512978D01*
X523027D01*
X523610Y1149574D01*
Y1131897D01*
G37*
G36*
G01X988890Y1302558D02*
G03I-501J0D01*
G37*
G36*
G01X1340069Y1131897D02*
X1339869Y1131697D01*
X1322869D01*
X1322703Y1131862D01*
Y1134057D01*
Y1148791D01*
Y1149594D01*
X1323266Y1150157D01*
X1324069D01*
X1328296D01*
X1329437D01*
X1339486D01*
X1340069Y1149574D01*
Y1131897D01*
G37*
G36*
G01X1372197D02*
X1371997Y1131697D01*
X1354997D01*
X1354831Y1131862D01*
Y1134057D01*
Y1148791D01*
Y1149594D01*
X1355394Y1150157D01*
X1356197D01*
X1360424D01*
X1361565D01*
X1371614D01*
X1372197Y1149574D01*
Y1131897D01*
G37*
G36*
G01X1405656D02*
X1405456Y1131697D01*
X1388456D01*
X1388290Y1131862D01*
Y1134057D01*
Y1148791D01*
Y1149594D01*
X1388853Y1150157D01*
X1389656D01*
X1393883D01*
X1395024D01*
X1405073D01*
X1405656Y1149574D01*
Y1131897D01*
G37*
G36*
G01X1437784D02*
X1437584Y1131697D01*
X1420584D01*
X1420418Y1131862D01*
Y1134057D01*
Y1148791D01*
Y1149594D01*
X1420981Y1150157D01*
X1421784D01*
X1426011D01*
X1427152D01*
X1437201D01*
X1437784Y1149574D01*
Y1131897D01*
G37*
%LPC*%
G75*
G54D283*
X413374Y1305298D03*
X413395Y1310481D03*
X413354Y1300197D03*
X407767Y1292198D03*
%LPD*%
G75*
G54D100*
X91838Y680527D03*
G54D200*
X836701Y758161D03*
Y760720D03*
Y763280D03*
Y765839D03*
Y776161D03*
Y778720D03*
Y781280D03*
Y783839D03*
Y794161D03*
Y796720D03*
Y799280D03*
Y801839D03*
Y812161D03*
Y814720D03*
Y817280D03*
Y819839D03*
X854299Y765839D03*
Y763280D03*
Y760720D03*
Y758161D03*
Y781280D03*
Y778720D03*
Y776161D03*
Y783839D03*
Y799280D03*
Y796720D03*
Y794161D03*
Y801839D03*
Y814720D03*
Y812161D03*
Y819839D03*
Y817280D03*
G54D101*
X90658Y1003349D03*
X94398D03*
X547745D03*
X551485D03*
X1004831D03*
X1008571D03*
X1259368Y854487D03*
X1263108D03*
X1259368Y864487D03*
X1263108D03*
X1259368Y859487D03*
X1263108D03*
X1259368Y874487D03*
X1263108D03*
X1259368Y879487D03*
X1263108D03*
X1259368Y869487D03*
X1263108D03*
X1259368Y884487D03*
X1263108D03*
X1259368Y889487D03*
X1263108D03*
X1273264Y895646D03*
X1277004D03*
X1461918Y1003349D03*
X1465658D03*
X1775991Y826570D03*
X1783471D03*
Y818696D03*
G54D110*
X109882Y1458622D03*
Y1463741D03*
Y1473977D03*
Y1479095D03*
Y1489331D03*
Y1494449D03*
Y1504685D03*
Y1509804D03*
Y1560985D03*
Y1566103D03*
Y1576339D03*
Y1581457D03*
Y1591693D03*
Y1596811D03*
Y1607048D03*
Y1612166D03*
X127205Y1458622D03*
Y1463741D03*
X118543Y1452717D03*
Y1462953D03*
X127205Y1473977D03*
Y1479095D03*
X118543Y1468071D03*
Y1478308D03*
X127205Y1489331D03*
Y1494449D03*
X118543Y1483426D03*
Y1493662D03*
Y1498780D03*
X127205Y1504685D03*
Y1509804D03*
X118543Y1509016D03*
Y1514134D03*
X127205Y1560985D03*
Y1566103D03*
Y1576339D03*
X118543Y1565315D03*
Y1570434D03*
X127205Y1581457D03*
Y1591693D03*
X118543Y1580670D03*
Y1585788D03*
Y1596024D03*
X127205Y1596811D03*
Y1607048D03*
Y1612166D03*
X118543Y1601142D03*
Y1611378D03*
X127205Y1622402D03*
X118543Y1616496D03*
X144528Y1458622D03*
Y1463741D03*
X135866Y1452717D03*
Y1462953D03*
X144528Y1473977D03*
Y1479095D03*
X135866Y1468071D03*
Y1478308D03*
X144528Y1489331D03*
Y1494449D03*
X135866Y1483426D03*
Y1493662D03*
Y1498780D03*
X144528Y1504685D03*
Y1509804D03*
X135866Y1509016D03*
Y1514134D03*
X144528Y1560985D03*
Y1566103D03*
Y1576339D03*
X135866Y1565315D03*
Y1570434D03*
X144528Y1581457D03*
Y1591693D03*
X135866Y1580670D03*
Y1585788D03*
Y1596024D03*
X144528Y1596811D03*
Y1607048D03*
Y1612166D03*
X135866Y1601142D03*
Y1611378D03*
X144528Y1622402D03*
X135866Y1616496D03*
X161850Y1458622D03*
Y1463741D03*
X153189Y1452717D03*
Y1462953D03*
X161850Y1473977D03*
Y1479095D03*
X153189Y1468071D03*
Y1478308D03*
X161850Y1489331D03*
Y1494449D03*
X153189Y1483426D03*
Y1493662D03*
Y1498780D03*
X161850Y1504685D03*
Y1509804D03*
X153189Y1509016D03*
Y1514134D03*
X161850Y1560985D03*
Y1566103D03*
Y1576339D03*
X153189Y1565315D03*
Y1570434D03*
X161850Y1581457D03*
Y1591693D03*
X153189Y1580670D03*
Y1585788D03*
Y1596024D03*
X161850Y1596811D03*
Y1607048D03*
Y1612166D03*
X153189Y1601142D03*
Y1611378D03*
X161850Y1622402D03*
X153189Y1616496D03*
X179173Y1458622D03*
Y1463741D03*
X170512Y1452717D03*
Y1462953D03*
X179173Y1473977D03*
Y1479095D03*
X170512Y1468071D03*
Y1478308D03*
X179173Y1489331D03*
Y1494449D03*
X170512Y1483426D03*
Y1493662D03*
Y1498780D03*
X179173Y1504685D03*
Y1509804D03*
X170512Y1509016D03*
Y1514134D03*
X179173Y1560985D03*
Y1566103D03*
Y1576339D03*
X170512Y1565315D03*
Y1570434D03*
X179173Y1581457D03*
Y1591693D03*
X170512Y1580670D03*
Y1585788D03*
Y1596024D03*
X179173Y1596811D03*
Y1607048D03*
Y1612166D03*
X170512Y1601142D03*
Y1611378D03*
X179173Y1622402D03*
X170512Y1616496D03*
X187835Y1452717D03*
Y1462953D03*
Y1468071D03*
Y1478308D03*
Y1483426D03*
Y1493662D03*
Y1498780D03*
Y1509016D03*
Y1514134D03*
Y1565315D03*
Y1570434D03*
Y1580670D03*
Y1585788D03*
Y1596024D03*
Y1601142D03*
Y1611378D03*
Y1616496D03*
X291771Y1452717D03*
X283110Y1458622D03*
X291771Y1462953D03*
X283110Y1463741D03*
X291771Y1468071D03*
X283110Y1473977D03*
X291771Y1478308D03*
X283110Y1479095D03*
X291771Y1483426D03*
X283110Y1489331D03*
X291771Y1493662D03*
X283110Y1494449D03*
X291771Y1498780D03*
X283110Y1504685D03*
X291771Y1509016D03*
X283110Y1509804D03*
X291771Y1514134D03*
X283110Y1560985D03*
X291771Y1565315D03*
X283110Y1566103D03*
X291771Y1570434D03*
X283110Y1576339D03*
X291771Y1580670D03*
X283110Y1581457D03*
X291771Y1585788D03*
X283110Y1591693D03*
X291771Y1596024D03*
X283110Y1596811D03*
X291771Y1601142D03*
X283110Y1607048D03*
X291771Y1611378D03*
X283110Y1612166D03*
X291771Y1616496D03*
X309094Y1452717D03*
X300433Y1458622D03*
X309094Y1462953D03*
X300433Y1463741D03*
X309094Y1468071D03*
X300433Y1473977D03*
X309094Y1478308D03*
X300433Y1479095D03*
X309094Y1483426D03*
X300433Y1489331D03*
X309094Y1493662D03*
X300433Y1494449D03*
X309094Y1498780D03*
X300433Y1504685D03*
X309094Y1509016D03*
X300433Y1509804D03*
X309094Y1514134D03*
X300433Y1560985D03*
X309094Y1565315D03*
X300433Y1566103D03*
X309094Y1570434D03*
X300433Y1576339D03*
X309094Y1580670D03*
X300433Y1581457D03*
X309094Y1585788D03*
X300433Y1591693D03*
X309094Y1596024D03*
X300433Y1596811D03*
X309094Y1601142D03*
X300433Y1607048D03*
X309094Y1611378D03*
X300433Y1612166D03*
X309094Y1616496D03*
X300433Y1622402D03*
X326417Y1452717D03*
X317756Y1458622D03*
X326417Y1462953D03*
X317756Y1463741D03*
X326417Y1468071D03*
X317756Y1473977D03*
X326417Y1478308D03*
X317756Y1479095D03*
X326417Y1483426D03*
X317756Y1489331D03*
X326417Y1493662D03*
X317756Y1494449D03*
X326417Y1498780D03*
X317756Y1504685D03*
X326417Y1509016D03*
X317756Y1509804D03*
X326417Y1514134D03*
X317756Y1560985D03*
X326417Y1565315D03*
X317756Y1566103D03*
X326417Y1570434D03*
X317756Y1576339D03*
X326417Y1580670D03*
X317756Y1581457D03*
X326417Y1585788D03*
X317756Y1591693D03*
X326417Y1596024D03*
X317756Y1596811D03*
X326417Y1601142D03*
X317756Y1607048D03*
X326417Y1611378D03*
X317756Y1612166D03*
X326417Y1616496D03*
X317756Y1622402D03*
X343740Y1452717D03*
X335078Y1458622D03*
X343740Y1462953D03*
X335078Y1463741D03*
X343740Y1468071D03*
X335078Y1473977D03*
X343740Y1478308D03*
X335078Y1479095D03*
X343740Y1483426D03*
X335078Y1489331D03*
X343740Y1493662D03*
X335078Y1494449D03*
X343740Y1498780D03*
X335078Y1504685D03*
X343740Y1509016D03*
X335078Y1509804D03*
X343740Y1514134D03*
X335078Y1560985D03*
X343740Y1565315D03*
X335078Y1566103D03*
X343740Y1570434D03*
X335078Y1576339D03*
X343740Y1580670D03*
X335078Y1581457D03*
X343740Y1585788D03*
X335078Y1591693D03*
X343740Y1596024D03*
X335078Y1596811D03*
X343740Y1601142D03*
X335078Y1607048D03*
X343740Y1611378D03*
X335078Y1612166D03*
X343740Y1616496D03*
X335078Y1622402D03*
X361063Y1452717D03*
X352401Y1458622D03*
Y1463741D03*
X361063Y1462953D03*
Y1468071D03*
X352401Y1473977D03*
Y1479095D03*
X361063Y1478308D03*
Y1483426D03*
X352401Y1489331D03*
Y1494449D03*
X361063Y1493662D03*
Y1498780D03*
X352401Y1504685D03*
Y1509804D03*
X361063Y1509016D03*
Y1514134D03*
X352401Y1560985D03*
Y1566103D03*
X361063Y1565315D03*
Y1570434D03*
X352401Y1576339D03*
Y1581457D03*
X361063Y1580670D03*
Y1585788D03*
X352401Y1591693D03*
X361063Y1596024D03*
X352401Y1596811D03*
X361063Y1601142D03*
X352401Y1607048D03*
Y1612166D03*
X361063Y1611378D03*
Y1616496D03*
X352401Y1622402D03*
X456339Y1458622D03*
Y1463741D03*
Y1473977D03*
Y1479095D03*
Y1489331D03*
Y1494449D03*
Y1504685D03*
Y1509804D03*
Y1560985D03*
Y1566103D03*
Y1576339D03*
Y1581457D03*
Y1591693D03*
Y1596811D03*
Y1607048D03*
Y1612166D03*
X473662Y1458622D03*
Y1463741D03*
X465000Y1452717D03*
Y1462953D03*
X473662Y1473977D03*
Y1479095D03*
X465000Y1468071D03*
Y1478308D03*
X473662Y1489331D03*
Y1494449D03*
X465000Y1483426D03*
Y1493662D03*
Y1498780D03*
X473662Y1504685D03*
Y1509804D03*
X465000Y1509016D03*
Y1514134D03*
X473662Y1560985D03*
Y1566103D03*
Y1576339D03*
X465000Y1565315D03*
Y1570434D03*
X473662Y1581457D03*
Y1591693D03*
X465000Y1580670D03*
Y1585788D03*
Y1596024D03*
X473662Y1596811D03*
Y1607048D03*
Y1612166D03*
X465000Y1601142D03*
Y1611378D03*
X473662Y1622402D03*
X465000Y1616496D03*
X490985Y1458622D03*
Y1463741D03*
X482323Y1452717D03*
Y1462953D03*
X490985Y1473977D03*
Y1479095D03*
X482323Y1468071D03*
Y1478308D03*
X490985Y1489331D03*
Y1494449D03*
X482323Y1483426D03*
Y1493662D03*
Y1498780D03*
X490985Y1504685D03*
Y1509804D03*
X482323Y1509016D03*
Y1514134D03*
X490985Y1560985D03*
Y1566103D03*
Y1576339D03*
X482323Y1565315D03*
Y1570434D03*
X490985Y1581457D03*
Y1591693D03*
X482323Y1580670D03*
Y1585788D03*
Y1596024D03*
X490985Y1596811D03*
Y1607048D03*
Y1612166D03*
X482323Y1601142D03*
Y1611378D03*
X490985Y1622402D03*
X482323Y1616496D03*
X499646Y1452717D03*
Y1462953D03*
Y1468071D03*
Y1478308D03*
Y1483426D03*
Y1493662D03*
Y1498780D03*
Y1509016D03*
Y1514134D03*
Y1565315D03*
Y1570434D03*
Y1580670D03*
Y1585788D03*
Y1596024D03*
Y1601142D03*
Y1611378D03*
Y1616496D03*
X516969Y1452717D03*
X508307Y1458622D03*
X516969Y1462953D03*
X508307Y1463741D03*
X516969Y1468071D03*
X508307Y1473977D03*
X516969Y1478308D03*
X508307Y1479095D03*
X516969Y1483426D03*
X508307Y1489331D03*
X516969Y1493662D03*
X508307Y1494449D03*
X516969Y1498780D03*
X508307Y1504685D03*
X516969Y1509016D03*
X508307Y1509804D03*
X516969Y1514134D03*
X508307Y1560985D03*
X516969Y1565315D03*
X508307Y1566103D03*
X516969Y1570434D03*
X508307Y1576339D03*
X516969Y1580670D03*
X508307Y1581457D03*
X516969Y1585788D03*
X508307Y1591693D03*
X516969Y1596024D03*
X508307Y1596811D03*
X516969Y1601142D03*
X508307Y1607048D03*
X516969Y1611378D03*
X508307Y1612166D03*
X516969Y1616496D03*
X508307Y1622402D03*
X534292Y1452717D03*
X525630Y1458622D03*
Y1463741D03*
X534292Y1462953D03*
Y1468071D03*
X525630Y1473977D03*
Y1479095D03*
X534292Y1478308D03*
Y1483426D03*
X525630Y1489331D03*
Y1494449D03*
X534292Y1493662D03*
Y1498780D03*
X525630Y1504685D03*
Y1509804D03*
X534292Y1509016D03*
Y1514134D03*
X525630Y1560985D03*
Y1566103D03*
X534292Y1565315D03*
Y1570434D03*
X525630Y1576339D03*
Y1581457D03*
X534292Y1580670D03*
Y1585788D03*
X525630Y1591693D03*
X534292Y1596024D03*
X525630Y1596811D03*
X534292Y1601142D03*
X525630Y1607048D03*
Y1612166D03*
X534292Y1611378D03*
Y1616496D03*
X525630Y1622402D03*
X629567Y1458622D03*
Y1463741D03*
Y1473977D03*
Y1479095D03*
Y1489331D03*
Y1494449D03*
Y1504685D03*
Y1509804D03*
Y1560985D03*
Y1566103D03*
Y1576339D03*
Y1581457D03*
Y1591693D03*
Y1596811D03*
Y1607048D03*
Y1612166D03*
X646890Y1458622D03*
Y1463741D03*
X638228Y1452717D03*
Y1462953D03*
X646890Y1473977D03*
Y1479095D03*
X638228Y1468071D03*
Y1478308D03*
X646890Y1489331D03*
Y1494449D03*
X638228Y1483426D03*
Y1493662D03*
Y1498780D03*
X646890Y1504685D03*
Y1509804D03*
X638228Y1509016D03*
Y1514134D03*
X646890Y1560985D03*
Y1566103D03*
Y1576339D03*
X638228Y1565315D03*
Y1570434D03*
X646890Y1581457D03*
Y1591693D03*
X638228Y1580670D03*
Y1585788D03*
Y1596024D03*
X646890Y1596811D03*
Y1607048D03*
Y1612166D03*
X638228Y1601142D03*
Y1611378D03*
X646890Y1622402D03*
X638228Y1616496D03*
X664213Y1458622D03*
Y1463741D03*
X655551Y1452717D03*
Y1462953D03*
X664213Y1473977D03*
Y1479095D03*
X655551Y1468071D03*
Y1478308D03*
X664213Y1489331D03*
Y1494449D03*
X655551Y1483426D03*
Y1493662D03*
Y1498780D03*
X664213Y1504685D03*
Y1509804D03*
X655551Y1509016D03*
Y1514134D03*
X664213Y1560985D03*
Y1566103D03*
Y1576339D03*
X655551Y1565315D03*
Y1570434D03*
X664213Y1581457D03*
Y1591693D03*
X655551Y1580670D03*
Y1585788D03*
Y1596024D03*
X664213Y1596811D03*
Y1607048D03*
Y1612166D03*
X655551Y1601142D03*
Y1611378D03*
X664213Y1622402D03*
X655551Y1616496D03*
X681535Y1458622D03*
Y1463741D03*
X672874Y1452717D03*
Y1462953D03*
X681535Y1473977D03*
Y1479095D03*
X672874Y1468071D03*
Y1478308D03*
X681535Y1489331D03*
Y1494449D03*
X672874Y1483426D03*
Y1493662D03*
Y1498780D03*
X681535Y1504685D03*
Y1509804D03*
X672874Y1509016D03*
Y1514134D03*
X681535Y1560985D03*
Y1566103D03*
Y1576339D03*
X672874Y1565315D03*
Y1570434D03*
X681535Y1581457D03*
Y1591693D03*
X672874Y1580670D03*
Y1585788D03*
Y1596024D03*
X681535Y1596811D03*
Y1607048D03*
Y1612166D03*
X672874Y1601142D03*
Y1611378D03*
X681535Y1622402D03*
X672874Y1616496D03*
X698858Y1458622D03*
Y1463741D03*
X690197Y1452717D03*
Y1462953D03*
X698858Y1473977D03*
Y1479095D03*
X690197Y1468071D03*
Y1478308D03*
X698858Y1489331D03*
Y1494449D03*
X690197Y1483426D03*
Y1493662D03*
Y1498780D03*
X698858Y1504685D03*
Y1509804D03*
X690197Y1509016D03*
Y1514134D03*
X698858Y1560985D03*
Y1566103D03*
Y1576339D03*
X690197Y1565315D03*
Y1570434D03*
X698858Y1581457D03*
Y1591693D03*
X690197Y1580670D03*
Y1585788D03*
Y1596024D03*
X698858Y1596811D03*
Y1607048D03*
Y1612166D03*
X690197Y1601142D03*
Y1611378D03*
X698858Y1622402D03*
X690197Y1616496D03*
X707520Y1452717D03*
Y1462953D03*
Y1468071D03*
Y1478308D03*
Y1483426D03*
Y1493662D03*
Y1498780D03*
Y1509016D03*
Y1514134D03*
Y1565315D03*
Y1570434D03*
Y1580670D03*
Y1585788D03*
Y1596024D03*
Y1601142D03*
Y1611378D03*
Y1616496D03*
X1140511Y1452717D03*
X1131850Y1458622D03*
X1140511Y1462953D03*
X1131850Y1463741D03*
X1140511Y1468071D03*
X1131850Y1473977D03*
X1140511Y1478308D03*
X1131850Y1479095D03*
X1140511Y1483426D03*
X1131850Y1489331D03*
X1140511Y1493662D03*
X1131850Y1494449D03*
X1140511Y1498780D03*
X1131850Y1504685D03*
X1140511Y1509016D03*
X1131850Y1509804D03*
X1140511Y1514134D03*
X1131850Y1560985D03*
X1140511Y1565315D03*
X1131850Y1566103D03*
X1140511Y1570434D03*
X1131850Y1576339D03*
X1140511Y1580670D03*
X1131850Y1581457D03*
X1140511Y1585788D03*
X1131850Y1591693D03*
X1140511Y1596024D03*
X1131850Y1596811D03*
X1140511Y1601142D03*
X1131850Y1607048D03*
X1140511Y1611378D03*
X1131850Y1612166D03*
X1140511Y1616496D03*
X1149173Y1458622D03*
Y1463741D03*
Y1473977D03*
Y1479095D03*
Y1489331D03*
Y1494449D03*
Y1504685D03*
Y1509804D03*
Y1560985D03*
Y1566103D03*
Y1576339D03*
Y1581457D03*
Y1591693D03*
Y1596811D03*
Y1607048D03*
Y1612166D03*
Y1622402D03*
X1166496Y1458622D03*
Y1463741D03*
X1157834Y1452717D03*
Y1462953D03*
X1166496Y1473977D03*
Y1479095D03*
X1157834Y1468071D03*
Y1478308D03*
X1166496Y1489331D03*
Y1494449D03*
X1157834Y1483426D03*
Y1493662D03*
Y1498780D03*
X1166496Y1504685D03*
Y1509804D03*
X1157834Y1509016D03*
Y1514134D03*
X1166496Y1560985D03*
Y1566103D03*
Y1576339D03*
X1157834Y1565315D03*
Y1570434D03*
X1166496Y1581457D03*
Y1591693D03*
X1157834Y1580670D03*
Y1585788D03*
Y1596024D03*
X1166496Y1596811D03*
Y1607048D03*
Y1612166D03*
X1157834Y1601142D03*
Y1611378D03*
X1166496Y1622402D03*
X1157834Y1616496D03*
X1183818Y1458622D03*
Y1463741D03*
X1175157Y1452717D03*
Y1462953D03*
X1183818Y1473977D03*
Y1479095D03*
X1175157Y1468071D03*
Y1478308D03*
X1183818Y1489331D03*
Y1494449D03*
X1175157Y1483426D03*
Y1493662D03*
Y1498780D03*
X1183818Y1504685D03*
Y1509804D03*
X1175157Y1509016D03*
Y1514134D03*
X1183818Y1560985D03*
Y1566103D03*
Y1576339D03*
X1175157Y1565315D03*
Y1570434D03*
X1183818Y1581457D03*
Y1591693D03*
X1175157Y1580670D03*
Y1585788D03*
Y1596024D03*
X1183818Y1596811D03*
Y1607048D03*
Y1612166D03*
X1175157Y1601142D03*
Y1611378D03*
X1183818Y1622402D03*
X1175157Y1616496D03*
X1201141Y1458622D03*
Y1463741D03*
X1192480Y1452717D03*
Y1462953D03*
X1201141Y1473977D03*
Y1479095D03*
X1192480Y1468071D03*
Y1478308D03*
X1201141Y1489331D03*
Y1494449D03*
X1192480Y1483426D03*
Y1493662D03*
Y1498780D03*
X1201141Y1504685D03*
Y1509804D03*
X1192480Y1509016D03*
Y1514134D03*
X1201141Y1560985D03*
Y1566103D03*
Y1576339D03*
X1192480Y1565315D03*
Y1570434D03*
X1201141Y1581457D03*
Y1591693D03*
X1192480Y1580670D03*
Y1585788D03*
Y1596024D03*
X1201141Y1596811D03*
Y1607048D03*
Y1612166D03*
X1192480Y1601142D03*
Y1611378D03*
X1201141Y1622402D03*
X1192480Y1616496D03*
X1209803Y1452717D03*
Y1462953D03*
Y1468071D03*
Y1478308D03*
Y1483426D03*
Y1493662D03*
Y1498780D03*
Y1509016D03*
Y1514134D03*
Y1565315D03*
Y1570434D03*
Y1580670D03*
Y1585788D03*
Y1596024D03*
Y1601142D03*
Y1611378D03*
Y1616496D03*
X1313740Y1452717D03*
X1305079Y1458622D03*
X1313740Y1462953D03*
X1305079Y1463741D03*
X1313740Y1468071D03*
X1305079Y1473977D03*
X1313740Y1478308D03*
X1305079Y1479095D03*
X1313740Y1483426D03*
X1305079Y1489331D03*
X1313740Y1493662D03*
X1305079Y1494449D03*
X1313740Y1498780D03*
X1305079Y1504685D03*
X1313740Y1509016D03*
X1305079Y1509804D03*
X1313740Y1514134D03*
X1305079Y1560985D03*
X1313740Y1565315D03*
X1305079Y1566103D03*
X1313740Y1570434D03*
X1305079Y1576339D03*
X1313740Y1580670D03*
X1305079Y1581457D03*
X1313740Y1585788D03*
X1305079Y1591693D03*
X1313740Y1596024D03*
X1305079Y1596811D03*
X1313740Y1601142D03*
X1305079Y1607048D03*
X1313740Y1611378D03*
X1305079Y1612166D03*
X1313740Y1616496D03*
X1331063Y1452717D03*
X1322402Y1458622D03*
X1331063Y1462953D03*
X1322402Y1463741D03*
X1331063Y1468071D03*
X1322402Y1473977D03*
X1331063Y1478308D03*
X1322402Y1479095D03*
X1331063Y1483426D03*
X1322402Y1489331D03*
X1331063Y1493662D03*
X1322402Y1494449D03*
X1331063Y1498780D03*
X1322402Y1504685D03*
X1331063Y1509016D03*
X1322402Y1509804D03*
X1331063Y1514134D03*
X1322402Y1560985D03*
X1331063Y1565315D03*
X1322402Y1566103D03*
X1331063Y1570434D03*
X1322402Y1576339D03*
X1331063Y1580670D03*
X1322402Y1581457D03*
X1331063Y1585788D03*
X1322402Y1591693D03*
X1331063Y1596024D03*
X1322402Y1596811D03*
X1331063Y1601142D03*
X1322402Y1607048D03*
X1331063Y1611378D03*
X1322402Y1612166D03*
X1331063Y1616496D03*
X1322402Y1622402D03*
X1348386Y1452717D03*
X1339725Y1458622D03*
X1348386Y1462953D03*
X1339725Y1463741D03*
X1348386Y1468071D03*
X1339725Y1473977D03*
X1348386Y1478308D03*
X1339725Y1479095D03*
X1348386Y1483426D03*
X1339725Y1489331D03*
X1348386Y1493662D03*
X1339725Y1494449D03*
X1348386Y1498780D03*
X1339725Y1504685D03*
X1348386Y1509016D03*
X1339725Y1509804D03*
X1348386Y1514134D03*
X1339725Y1560985D03*
X1348386Y1565315D03*
X1339725Y1566103D03*
X1348386Y1570434D03*
X1339725Y1576339D03*
X1348386Y1580670D03*
X1339725Y1581457D03*
X1348386Y1585788D03*
X1339725Y1591693D03*
X1348386Y1596024D03*
X1339725Y1596811D03*
X1348386Y1601142D03*
X1339725Y1607048D03*
X1348386Y1611378D03*
X1339725Y1612166D03*
X1348386Y1616496D03*
X1339725Y1622402D03*
X1365709Y1452717D03*
X1357047Y1458622D03*
X1365709Y1462953D03*
X1357047Y1463741D03*
X1365709Y1468071D03*
X1357047Y1473977D03*
X1365709Y1478308D03*
X1357047Y1479095D03*
X1365709Y1483426D03*
X1357047Y1489331D03*
X1365709Y1493662D03*
X1357047Y1494449D03*
X1365709Y1498780D03*
X1357047Y1504685D03*
X1365709Y1509016D03*
X1357047Y1509804D03*
X1365709Y1514134D03*
X1357047Y1560985D03*
X1365709Y1565315D03*
X1357047Y1566103D03*
X1365709Y1570434D03*
X1357047Y1576339D03*
X1365709Y1580670D03*
X1357047Y1581457D03*
X1365709Y1585788D03*
X1357047Y1591693D03*
X1365709Y1596024D03*
X1357047Y1596811D03*
X1365709Y1601142D03*
X1357047Y1607048D03*
X1365709Y1611378D03*
X1357047Y1612166D03*
X1365709Y1616496D03*
X1357047Y1622402D03*
X1383032Y1452717D03*
X1374370Y1458622D03*
Y1463741D03*
X1383032Y1462953D03*
Y1468071D03*
X1374370Y1473977D03*
Y1479095D03*
X1383032Y1478308D03*
Y1483426D03*
X1374370Y1489331D03*
Y1494449D03*
X1383032Y1493662D03*
Y1498780D03*
X1374370Y1504685D03*
Y1509804D03*
X1383032Y1509016D03*
Y1514134D03*
X1374370Y1560985D03*
Y1566103D03*
X1383032Y1565315D03*
Y1570434D03*
X1374370Y1576339D03*
Y1581457D03*
X1383032Y1580670D03*
Y1585788D03*
X1374370Y1591693D03*
X1383032Y1596024D03*
X1374370Y1596811D03*
X1383032Y1601142D03*
X1374370Y1607048D03*
Y1612166D03*
X1383032Y1611378D03*
Y1616496D03*
X1374370Y1622402D03*
X1478307Y1458622D03*
Y1463741D03*
Y1473977D03*
Y1479095D03*
Y1489331D03*
Y1494449D03*
Y1504685D03*
Y1509804D03*
Y1560985D03*
Y1566103D03*
Y1576339D03*
Y1581457D03*
Y1591693D03*
Y1596811D03*
Y1607048D03*
Y1612166D03*
X1495630Y1458622D03*
Y1463741D03*
X1486968Y1452717D03*
Y1462953D03*
X1495630Y1473977D03*
Y1479095D03*
X1486968Y1468071D03*
Y1478308D03*
X1495630Y1489331D03*
Y1494449D03*
X1486968Y1483426D03*
Y1493662D03*
Y1498780D03*
X1495630Y1504685D03*
Y1509804D03*
X1486968Y1509016D03*
Y1514134D03*
X1495630Y1560985D03*
Y1566103D03*
Y1576339D03*
X1486968Y1565315D03*
Y1570434D03*
X1495630Y1581457D03*
Y1591693D03*
X1486968Y1580670D03*
Y1585788D03*
Y1596024D03*
X1495630Y1596811D03*
Y1607048D03*
Y1612166D03*
X1486968Y1601142D03*
Y1611378D03*
X1495630Y1622402D03*
X1486968Y1616496D03*
X1512953Y1458622D03*
Y1463741D03*
X1504291Y1452717D03*
Y1462953D03*
X1512953Y1473977D03*
Y1479095D03*
X1504291Y1468071D03*
Y1478308D03*
X1512953Y1489331D03*
Y1494449D03*
X1504291Y1483426D03*
Y1493662D03*
Y1498780D03*
X1512953Y1504685D03*
Y1509804D03*
X1504291Y1509016D03*
Y1514134D03*
X1512953Y1560985D03*
Y1566103D03*
Y1576339D03*
X1504291Y1565315D03*
Y1570434D03*
X1512953Y1581457D03*
Y1591693D03*
X1504291Y1580670D03*
Y1585788D03*
Y1596024D03*
X1512953Y1596811D03*
Y1607048D03*
Y1612166D03*
X1504291Y1601142D03*
Y1611378D03*
X1512953Y1622402D03*
X1504291Y1616496D03*
X1530275Y1458622D03*
Y1463741D03*
X1521614Y1452717D03*
Y1462953D03*
X1530275Y1473977D03*
Y1479095D03*
X1521614Y1468071D03*
Y1478308D03*
X1530275Y1489331D03*
Y1494449D03*
X1521614Y1483426D03*
Y1493662D03*
Y1498780D03*
X1530275Y1504685D03*
Y1509804D03*
X1521614Y1509016D03*
Y1514134D03*
X1530275Y1560985D03*
Y1566103D03*
Y1576339D03*
X1521614Y1565315D03*
Y1570434D03*
X1530275Y1581457D03*
Y1591693D03*
X1521614Y1580670D03*
Y1585788D03*
Y1596024D03*
X1530275Y1596811D03*
Y1607048D03*
Y1612166D03*
X1521614Y1601142D03*
Y1611378D03*
X1530275Y1622402D03*
X1521614Y1616496D03*
X1538937Y1452717D03*
Y1462953D03*
Y1468071D03*
Y1478308D03*
Y1483426D03*
Y1493662D03*
Y1498780D03*
Y1509016D03*
Y1514134D03*
Y1565315D03*
Y1570434D03*
Y1580670D03*
Y1585788D03*
Y1596024D03*
Y1601142D03*
Y1611378D03*
Y1616496D03*
X1556260Y1452717D03*
X1547598Y1458622D03*
Y1463741D03*
X1556260Y1462953D03*
Y1468071D03*
X1547598Y1473977D03*
Y1479095D03*
X1556260Y1478308D03*
Y1483426D03*
X1547598Y1489331D03*
Y1494449D03*
X1556260Y1493662D03*
Y1498780D03*
X1547598Y1504685D03*
Y1509804D03*
X1556260Y1509016D03*
Y1514134D03*
X1547598Y1560985D03*
Y1566103D03*
X1556260Y1565315D03*
Y1570434D03*
X1547598Y1576339D03*
Y1581457D03*
X1556260Y1580670D03*
Y1585788D03*
X1547598Y1591693D03*
X1556260Y1596024D03*
X1547598Y1596811D03*
X1556260Y1601142D03*
X1547598Y1607048D03*
Y1612166D03*
X1556260Y1611378D03*
Y1616496D03*
X1547598Y1622402D03*
X1660196Y1452717D03*
X1651535Y1458622D03*
X1660196Y1462953D03*
X1651535Y1463741D03*
X1660196Y1468071D03*
X1651535Y1473977D03*
X1660196Y1478308D03*
X1651535Y1479095D03*
X1660196Y1483426D03*
X1651535Y1489331D03*
X1660196Y1493662D03*
X1651535Y1494449D03*
X1660196Y1498780D03*
X1651535Y1504685D03*
X1660196Y1509016D03*
X1651535Y1509804D03*
X1660196Y1514134D03*
X1651535Y1560985D03*
X1660196Y1565315D03*
X1651535Y1566103D03*
X1660196Y1570434D03*
X1651535Y1576339D03*
X1660196Y1580670D03*
X1651535Y1581457D03*
X1660196Y1585788D03*
X1651535Y1591693D03*
X1660196Y1596024D03*
X1651535Y1596811D03*
X1660196Y1601142D03*
X1651535Y1607048D03*
X1660196Y1611378D03*
X1651535Y1612166D03*
X1660196Y1616496D03*
X1668858Y1458622D03*
Y1463741D03*
Y1473977D03*
Y1479095D03*
Y1489331D03*
Y1494449D03*
Y1504685D03*
Y1509804D03*
Y1560985D03*
Y1566103D03*
Y1576339D03*
Y1581457D03*
Y1591693D03*
Y1596811D03*
Y1607048D03*
Y1612166D03*
Y1622402D03*
X1686181Y1458622D03*
Y1463741D03*
X1677519Y1452717D03*
Y1462953D03*
X1686181Y1473977D03*
Y1479095D03*
X1677519Y1468071D03*
Y1478308D03*
X1686181Y1489331D03*
Y1494449D03*
X1677519Y1483426D03*
Y1493662D03*
Y1498780D03*
X1686181Y1504685D03*
Y1509804D03*
X1677519Y1509016D03*
Y1514134D03*
X1686181Y1560985D03*
Y1566103D03*
Y1576339D03*
X1677519Y1565315D03*
Y1570434D03*
X1686181Y1581457D03*
Y1591693D03*
X1677519Y1580670D03*
Y1585788D03*
Y1596024D03*
X1686181Y1596811D03*
Y1607048D03*
Y1612166D03*
X1677519Y1601142D03*
Y1611378D03*
X1686181Y1622402D03*
X1677519Y1616496D03*
X1703503Y1458622D03*
Y1463741D03*
X1694842Y1452717D03*
Y1462953D03*
X1703503Y1473977D03*
Y1479095D03*
X1694842Y1468071D03*
Y1478308D03*
X1703503Y1489331D03*
Y1494449D03*
X1694842Y1483426D03*
Y1493662D03*
Y1498780D03*
X1703503Y1504685D03*
Y1509804D03*
X1694842Y1509016D03*
Y1514134D03*
X1703503Y1560985D03*
Y1566103D03*
Y1576339D03*
X1694842Y1565315D03*
Y1570434D03*
X1703503Y1581457D03*
Y1591693D03*
X1694842Y1580670D03*
Y1585788D03*
Y1596024D03*
X1703503Y1596811D03*
Y1607048D03*
Y1612166D03*
X1694842Y1601142D03*
Y1611378D03*
X1703503Y1622402D03*
X1694842Y1616496D03*
X1720826Y1458622D03*
Y1463741D03*
X1712165Y1452717D03*
Y1462953D03*
X1720826Y1473977D03*
Y1479095D03*
X1712165Y1468071D03*
Y1478308D03*
X1720826Y1489331D03*
Y1494449D03*
X1712165Y1483426D03*
Y1493662D03*
Y1498780D03*
X1720826Y1504685D03*
Y1509804D03*
X1712165Y1509016D03*
Y1514134D03*
X1720826Y1560985D03*
Y1566103D03*
Y1576339D03*
X1712165Y1565315D03*
Y1570434D03*
X1720826Y1581457D03*
Y1591693D03*
X1712165Y1580670D03*
Y1585788D03*
Y1596024D03*
X1720826Y1596811D03*
Y1607048D03*
Y1612166D03*
X1712165Y1601142D03*
Y1611378D03*
X1720826Y1622402D03*
X1712165Y1616496D03*
X1729488Y1452717D03*
Y1462953D03*
Y1468071D03*
Y1478308D03*
Y1483426D03*
Y1493662D03*
Y1498780D03*
Y1509016D03*
Y1514134D03*
Y1565315D03*
Y1570434D03*
Y1580670D03*
Y1585788D03*
Y1596024D03*
Y1601142D03*
Y1611378D03*
Y1616496D03*
G54D201*
X849441Y1367717D03*
G54D102*
X103958Y1021783D03*
Y1014303D03*
X561045Y1021783D03*
Y1014303D03*
X1018131Y1021783D03*
Y1014303D03*
X1475218Y1021783D03*
Y1014303D03*
G54D120*
X311947Y342319D03*
X303285D03*
Y344878D03*
X311947Y347437D03*
X303285D03*
X652595Y653161D03*
X643933D03*
X652595Y658279D03*
X643933D03*
Y655720D03*
X760371Y342319D03*
Y344878D03*
Y347437D03*
X769033Y342319D03*
Y347437D03*
X1101020Y653161D03*
Y658279D03*
Y655720D03*
X1109682Y653161D03*
Y658279D03*
X1217458Y342319D03*
Y344878D03*
Y347437D03*
X1226120Y342319D03*
Y347437D03*
X1558107Y653161D03*
Y658279D03*
Y655720D03*
X1566769Y653161D03*
Y658279D03*
X1674545Y342319D03*
Y344878D03*
Y347437D03*
X1683207Y342319D03*
Y347437D03*
G54D210*
X894082Y566990D03*
X892114D03*
X890145D03*
X896051D03*
X890145Y591596D03*
X894082D03*
X896051D03*
X892114D03*
X901956Y566990D03*
X898020D03*
X909831D03*
X899988D03*
X905894D03*
X903925D03*
X907862D03*
X899988Y591596D03*
X903925D03*
X905894D03*
X907862D03*
X898020D03*
X909831D03*
X901956D03*
X1024318Y319612D03*
X1020382D03*
X1014476D03*
X1022350D03*
X1016444D03*
X1018413D03*
X1026287D03*
X1012507D03*
Y344218D03*
X1018413D03*
X1022350D03*
X1026287D03*
X1020382D03*
X1016444D03*
X1014476D03*
X1024318D03*
X1032193Y319612D03*
X1028256D03*
X1030224D03*
X1028256Y344218D03*
X1032193D03*
X1030224D03*
G54D111*
X109882Y1622402D03*
X283110D03*
X456339D03*
X629567D03*
X1131850D03*
X1305079D03*
X1478307D03*
X1651535D03*
G54D220*
X911630Y533706D03*
Y540006D03*
X919976D03*
Y533706D03*
G54D103*
X116731Y1066535D03*
Y1263386D03*
X352952Y1066535D03*
Y1263386D03*
X573818Y1066535D03*
Y1263386D03*
X810038Y1066535D03*
Y1263386D03*
X1030905Y1066535D03*
Y1263386D03*
X1267125Y1066535D03*
Y1263386D03*
X1487991Y1066535D03*
Y1263386D03*
X1724212Y1066535D03*
Y1263386D03*
G54D112*
X181269Y384429D03*
Y386791D03*
Y382067D03*
Y391516D03*
Y389154D03*
Y398602D03*
Y405689D03*
Y393878D03*
Y400965D03*
Y408051D03*
Y396240D03*
Y403327D03*
Y412776D03*
Y419862D03*
Y415138D03*
Y422224D03*
Y410413D03*
Y417500D03*
Y424587D03*
Y434036D03*
Y441122D03*
Y426949D03*
Y436398D03*
Y429311D03*
Y431673D03*
Y438760D03*
Y443484D03*
Y445847D03*
Y465177D03*
Y469902D03*
Y472264D03*
Y467539D03*
Y474626D03*
Y476988D03*
Y484075D03*
Y479350D03*
Y486437D03*
Y481713D03*
Y488799D03*
Y491162D03*
Y493524D03*
Y495886D03*
Y514036D03*
Y521122D03*
Y516398D03*
Y523484D03*
Y511673D03*
Y518760D03*
Y528209D03*
Y535295D03*
Y530571D03*
Y537658D03*
Y525847D03*
Y532933D03*
Y542382D03*
Y544744D03*
Y554193D03*
Y540020D03*
Y547106D03*
Y549469D03*
Y551831D03*
Y556555D03*
Y558917D03*
Y561280D03*
Y563642D03*
Y566004D03*
Y568366D03*
Y570728D03*
Y573091D03*
Y575453D03*
Y597480D03*
Y599843D03*
Y604567D03*
Y592756D03*
Y595118D03*
Y602205D03*
Y609291D03*
Y606929D03*
Y618740D03*
Y614016D03*
Y616378D03*
Y611654D03*
Y623465D03*
Y621102D03*
X199380Y384429D03*
Y386791D03*
Y382067D03*
Y391516D03*
Y389154D03*
Y398602D03*
Y405689D03*
Y393878D03*
Y400965D03*
Y408051D03*
Y396240D03*
Y403327D03*
Y412776D03*
Y419862D03*
Y415138D03*
Y422224D03*
Y410413D03*
Y417500D03*
Y424587D03*
Y434036D03*
Y441122D03*
Y426949D03*
Y436398D03*
Y429311D03*
Y431673D03*
Y438760D03*
Y443484D03*
Y445847D03*
Y465177D03*
Y469902D03*
Y472264D03*
Y467539D03*
Y474626D03*
Y476988D03*
Y484075D03*
Y479350D03*
Y486437D03*
Y481713D03*
Y488799D03*
Y491162D03*
Y493524D03*
Y495886D03*
Y514036D03*
Y521122D03*
Y516398D03*
Y523484D03*
Y511673D03*
Y518760D03*
Y528209D03*
Y535295D03*
Y530571D03*
Y537658D03*
Y525847D03*
Y532933D03*
Y542382D03*
Y544744D03*
Y549469D03*
Y554193D03*
Y551831D03*
Y540020D03*
Y547106D03*
Y556555D03*
Y558917D03*
Y561280D03*
Y563642D03*
Y566004D03*
Y568366D03*
Y570728D03*
Y573091D03*
Y575453D03*
Y597480D03*
Y599843D03*
Y604567D03*
Y592756D03*
Y595118D03*
Y602205D03*
Y618740D03*
Y611654D03*
Y609291D03*
Y606929D03*
Y614016D03*
Y616378D03*
Y621102D03*
Y623465D03*
X270305Y386772D03*
Y391496D03*
Y389134D03*
Y384410D03*
Y382047D03*
Y393858D03*
Y408032D03*
Y405669D03*
Y396221D03*
Y398583D03*
Y400945D03*
Y403307D03*
Y412756D03*
Y410394D03*
Y441870D03*
Y439508D03*
Y437146D03*
Y434784D03*
Y432421D03*
Y430059D03*
Y448957D03*
Y446595D03*
Y444232D03*
Y456043D03*
Y451319D03*
Y453681D03*
Y458406D03*
Y463130D03*
Y460768D03*
Y470217D03*
Y467854D03*
Y472579D03*
Y465492D03*
Y484390D03*
Y477303D03*
Y489114D03*
Y482028D03*
Y474941D03*
Y486752D03*
Y479665D03*
Y491476D03*
Y493839D03*
Y521437D03*
Y514350D03*
Y519075D03*
Y511988D03*
Y516713D03*
Y509626D03*
Y535610D03*
Y528524D03*
Y533248D03*
Y526162D03*
Y537973D03*
Y530886D03*
Y523799D03*
Y540335D03*
Y571476D03*
Y564390D03*
Y569114D03*
Y562028D03*
Y566752D03*
Y559665D03*
Y585650D03*
Y578563D03*
Y583288D03*
Y576201D03*
Y588012D03*
Y580925D03*
Y573839D03*
Y599823D03*
Y592736D03*
Y604547D03*
Y597461D03*
Y590374D03*
Y602185D03*
Y595099D03*
Y618721D03*
Y613996D03*
Y606910D03*
Y611634D03*
Y616358D03*
Y609272D03*
Y621083D03*
Y623445D03*
X288416Y382047D03*
Y384410D03*
Y386772D03*
Y391496D03*
Y389134D03*
Y396221D03*
Y408032D03*
Y405669D03*
Y398583D03*
Y400945D03*
Y403307D03*
Y393858D03*
Y412756D03*
Y410394D03*
Y441870D03*
Y439508D03*
Y437146D03*
Y434784D03*
Y432421D03*
Y430059D03*
Y451319D03*
Y458406D03*
Y448957D03*
Y446595D03*
Y444232D03*
Y456043D03*
Y453681D03*
Y463130D03*
Y460768D03*
Y470217D03*
Y467854D03*
Y472579D03*
Y465492D03*
Y484390D03*
Y477303D03*
Y489114D03*
Y482028D03*
Y474941D03*
Y486752D03*
Y479665D03*
Y491476D03*
Y493839D03*
Y521437D03*
Y514350D03*
Y519075D03*
Y511988D03*
Y516713D03*
Y509626D03*
Y535610D03*
Y528524D03*
Y533248D03*
Y526162D03*
Y537973D03*
Y530886D03*
Y523799D03*
Y540335D03*
Y571476D03*
Y564390D03*
Y569114D03*
Y562028D03*
Y566752D03*
Y559665D03*
Y585650D03*
Y578563D03*
Y583288D03*
Y576201D03*
Y588012D03*
Y580925D03*
Y573839D03*
Y599823D03*
Y592736D03*
Y604547D03*
Y597461D03*
Y590374D03*
Y602185D03*
Y595099D03*
Y618721D03*
Y613996D03*
Y606910D03*
Y611634D03*
Y616358D03*
Y609272D03*
Y621083D03*
Y623445D03*
X638355Y384429D03*
Y386791D03*
Y382067D03*
Y391516D03*
Y389154D03*
Y398602D03*
Y405689D03*
Y393878D03*
Y400965D03*
Y408051D03*
Y396240D03*
Y403327D03*
Y412776D03*
Y419862D03*
Y415138D03*
Y422224D03*
Y410413D03*
Y417500D03*
Y424587D03*
Y434036D03*
Y441122D03*
Y426949D03*
Y436398D03*
Y429311D03*
Y431673D03*
Y438760D03*
Y443484D03*
Y445847D03*
Y465177D03*
Y469902D03*
Y472264D03*
Y467539D03*
Y474626D03*
Y476988D03*
Y484075D03*
Y479350D03*
Y486437D03*
Y481713D03*
Y488799D03*
Y491162D03*
Y493524D03*
Y495886D03*
Y514036D03*
Y521122D03*
Y516398D03*
Y523484D03*
Y511673D03*
Y518760D03*
Y528209D03*
Y535295D03*
Y530571D03*
Y537658D03*
Y525847D03*
Y532933D03*
Y542382D03*
Y544744D03*
Y554193D03*
Y540020D03*
Y547106D03*
Y549469D03*
Y551831D03*
Y556555D03*
Y558917D03*
Y561280D03*
Y563642D03*
Y566004D03*
Y568366D03*
Y570728D03*
Y573091D03*
Y575453D03*
Y597480D03*
Y599843D03*
Y604567D03*
Y592756D03*
Y595118D03*
Y602205D03*
Y609291D03*
Y606929D03*
Y618740D03*
Y614016D03*
Y616378D03*
Y611654D03*
Y623465D03*
Y621102D03*
X656466Y384429D03*
Y386791D03*
Y382067D03*
Y391516D03*
Y389154D03*
Y398602D03*
Y405689D03*
Y393878D03*
Y400965D03*
Y408051D03*
Y396240D03*
Y403327D03*
Y412776D03*
Y419862D03*
Y415138D03*
Y422224D03*
Y410413D03*
Y417500D03*
Y424587D03*
Y434036D03*
Y441122D03*
Y426949D03*
Y436398D03*
Y429311D03*
Y431673D03*
Y438760D03*
Y443484D03*
Y445847D03*
Y465177D03*
Y469902D03*
Y472264D03*
Y467539D03*
Y474626D03*
Y476988D03*
Y484075D03*
Y479350D03*
Y486437D03*
Y481713D03*
Y488799D03*
Y491162D03*
Y493524D03*
Y495886D03*
Y514036D03*
Y521122D03*
Y516398D03*
Y523484D03*
Y511673D03*
Y518760D03*
Y528209D03*
Y535295D03*
Y530571D03*
Y537658D03*
Y525847D03*
Y532933D03*
Y542382D03*
Y544744D03*
Y549469D03*
Y554193D03*
Y551831D03*
Y540020D03*
Y547106D03*
Y556555D03*
Y558917D03*
Y561280D03*
Y563642D03*
Y566004D03*
Y568366D03*
Y570728D03*
Y573091D03*
Y575453D03*
Y597480D03*
Y599843D03*
Y604567D03*
Y592756D03*
Y595118D03*
Y602205D03*
Y618740D03*
Y611654D03*
Y609291D03*
Y606929D03*
Y614016D03*
Y616378D03*
Y621102D03*
Y623465D03*
X727391Y386772D03*
Y391496D03*
Y389134D03*
Y384410D03*
Y382047D03*
Y393858D03*
Y408032D03*
Y405669D03*
Y396221D03*
Y398583D03*
Y400945D03*
Y403307D03*
Y412756D03*
Y410394D03*
Y441870D03*
Y439508D03*
Y437146D03*
Y434784D03*
Y432421D03*
Y430059D03*
Y448957D03*
Y446595D03*
Y444232D03*
Y456043D03*
Y451319D03*
Y453681D03*
Y458406D03*
Y463130D03*
Y460768D03*
Y470217D03*
Y467854D03*
Y472579D03*
Y465492D03*
Y484390D03*
Y477303D03*
Y489114D03*
Y482028D03*
Y474941D03*
Y486752D03*
Y479665D03*
Y491476D03*
Y493839D03*
Y521437D03*
Y514350D03*
Y519075D03*
Y511988D03*
Y516713D03*
Y509626D03*
Y535610D03*
Y528524D03*
Y533248D03*
Y526162D03*
Y537973D03*
Y530886D03*
Y523799D03*
Y540335D03*
Y571476D03*
Y564390D03*
Y569114D03*
Y562028D03*
Y566752D03*
Y559665D03*
Y585650D03*
Y578563D03*
Y583288D03*
Y576201D03*
Y588012D03*
Y580925D03*
Y573839D03*
Y599823D03*
Y592736D03*
Y604547D03*
Y597461D03*
Y590374D03*
Y602185D03*
Y595099D03*
Y618721D03*
Y613996D03*
Y606910D03*
Y611634D03*
Y616358D03*
Y609272D03*
Y621083D03*
Y623445D03*
X745502Y382047D03*
Y384410D03*
Y386772D03*
Y391496D03*
Y389134D03*
Y396221D03*
Y408032D03*
Y405669D03*
Y398583D03*
Y400945D03*
Y403307D03*
Y393858D03*
Y412756D03*
Y410394D03*
Y441870D03*
Y439508D03*
Y437146D03*
Y434784D03*
Y432421D03*
Y430059D03*
Y451319D03*
Y458406D03*
Y448957D03*
Y446595D03*
Y444232D03*
Y456043D03*
Y453681D03*
Y463130D03*
Y460768D03*
Y470217D03*
Y467854D03*
Y472579D03*
Y465492D03*
Y484390D03*
Y477303D03*
Y489114D03*
Y482028D03*
Y474941D03*
Y486752D03*
Y479665D03*
Y491476D03*
Y493839D03*
Y521437D03*
Y514350D03*
Y519075D03*
Y511988D03*
Y516713D03*
Y509626D03*
Y535610D03*
Y528524D03*
Y533248D03*
Y526162D03*
Y537973D03*
Y530886D03*
Y523799D03*
Y540335D03*
Y571476D03*
Y564390D03*
Y569114D03*
Y562028D03*
Y566752D03*
Y559665D03*
Y585650D03*
Y578563D03*
Y583288D03*
Y576201D03*
Y588012D03*
Y580925D03*
Y573839D03*
Y599823D03*
Y592736D03*
Y604547D03*
Y597461D03*
Y590374D03*
Y602185D03*
Y595099D03*
Y618721D03*
Y613996D03*
Y606910D03*
Y611634D03*
Y616358D03*
Y609272D03*
Y621083D03*
Y623445D03*
X1095442Y384429D03*
Y386791D03*
Y382067D03*
Y391516D03*
Y389154D03*
Y398602D03*
Y405689D03*
Y393878D03*
Y400965D03*
Y408051D03*
Y396240D03*
Y403327D03*
Y412776D03*
Y419862D03*
Y415138D03*
Y422224D03*
Y410413D03*
Y417500D03*
Y424587D03*
Y434036D03*
Y441122D03*
Y426949D03*
Y436398D03*
Y429311D03*
Y431673D03*
Y438760D03*
Y443484D03*
Y445847D03*
Y465177D03*
Y469902D03*
Y472264D03*
Y467539D03*
Y474626D03*
Y476988D03*
Y484075D03*
Y479350D03*
Y486437D03*
Y481713D03*
Y488799D03*
Y491162D03*
Y493524D03*
Y495886D03*
Y514036D03*
Y521122D03*
Y516398D03*
Y523484D03*
Y511673D03*
Y518760D03*
Y528209D03*
Y535295D03*
Y530571D03*
Y537658D03*
Y525847D03*
Y532933D03*
Y542382D03*
Y544744D03*
Y554193D03*
Y540020D03*
Y547106D03*
Y549469D03*
Y551831D03*
Y556555D03*
Y558917D03*
Y561280D03*
Y563642D03*
Y566004D03*
Y568366D03*
Y570728D03*
Y573091D03*
Y575453D03*
Y597480D03*
Y599843D03*
Y604567D03*
Y592756D03*
Y595118D03*
Y602205D03*
Y609291D03*
Y606929D03*
Y618740D03*
Y614016D03*
Y616378D03*
Y611654D03*
Y623465D03*
Y621102D03*
X1113553Y384429D03*
Y386791D03*
Y382067D03*
Y391516D03*
Y389154D03*
Y398602D03*
Y405689D03*
Y393878D03*
Y400965D03*
Y408051D03*
Y396240D03*
Y403327D03*
Y412776D03*
Y419862D03*
Y415138D03*
Y422224D03*
Y410413D03*
Y417500D03*
Y424587D03*
Y434036D03*
Y441122D03*
Y426949D03*
Y436398D03*
Y429311D03*
Y431673D03*
Y438760D03*
Y443484D03*
Y445847D03*
Y465177D03*
Y469902D03*
Y472264D03*
Y467539D03*
Y474626D03*
Y476988D03*
Y484075D03*
Y479350D03*
Y486437D03*
Y481713D03*
Y488799D03*
Y491162D03*
Y493524D03*
Y495886D03*
Y514036D03*
Y521122D03*
Y516398D03*
Y523484D03*
Y511673D03*
Y518760D03*
Y528209D03*
Y535295D03*
Y530571D03*
Y537658D03*
Y525847D03*
Y532933D03*
Y542382D03*
Y544744D03*
Y549469D03*
Y554193D03*
Y551831D03*
Y540020D03*
Y547106D03*
Y556555D03*
Y558917D03*
Y561280D03*
Y563642D03*
Y566004D03*
Y568366D03*
Y570728D03*
Y573091D03*
Y575453D03*
Y597480D03*
Y599843D03*
Y604567D03*
Y592756D03*
Y595118D03*
Y602205D03*
Y618740D03*
Y611654D03*
Y609291D03*
Y606929D03*
Y614016D03*
Y616378D03*
Y621102D03*
Y623465D03*
X1184478Y386772D03*
Y391496D03*
Y389134D03*
Y384410D03*
Y382047D03*
Y393858D03*
Y408032D03*
Y405669D03*
Y396221D03*
Y398583D03*
Y400945D03*
Y403307D03*
Y412756D03*
Y410394D03*
Y441870D03*
Y439508D03*
Y437146D03*
Y434784D03*
Y432421D03*
Y430059D03*
Y448957D03*
Y446595D03*
Y444232D03*
Y456043D03*
Y451319D03*
Y453681D03*
Y458406D03*
Y463130D03*
Y460768D03*
Y470217D03*
Y467854D03*
Y472579D03*
Y465492D03*
Y484390D03*
Y477303D03*
Y489114D03*
Y482028D03*
Y474941D03*
Y486752D03*
Y479665D03*
Y491476D03*
Y493839D03*
Y521437D03*
Y514350D03*
Y519075D03*
Y511988D03*
Y516713D03*
Y509626D03*
Y535610D03*
Y528524D03*
Y533248D03*
Y526162D03*
Y537973D03*
Y530886D03*
Y523799D03*
Y540335D03*
Y571476D03*
Y564390D03*
Y569114D03*
Y562028D03*
Y566752D03*
Y559665D03*
Y585650D03*
Y578563D03*
Y583288D03*
Y576201D03*
Y588012D03*
Y580925D03*
Y573839D03*
Y599823D03*
Y592736D03*
Y604547D03*
Y597461D03*
Y590374D03*
Y602185D03*
Y595099D03*
Y618721D03*
Y613996D03*
Y606910D03*
Y611634D03*
Y616358D03*
Y609272D03*
Y621083D03*
Y623445D03*
X1202589Y382047D03*
Y384410D03*
Y386772D03*
Y391496D03*
Y389134D03*
Y396221D03*
Y408032D03*
Y405669D03*
Y398583D03*
Y400945D03*
Y403307D03*
Y393858D03*
Y412756D03*
Y410394D03*
Y441870D03*
Y439508D03*
Y437146D03*
Y434784D03*
Y432421D03*
Y430059D03*
Y451319D03*
Y458406D03*
Y448957D03*
Y446595D03*
Y444232D03*
Y456043D03*
Y453681D03*
Y463130D03*
Y460768D03*
Y470217D03*
Y467854D03*
Y472579D03*
Y465492D03*
Y484390D03*
Y477303D03*
Y489114D03*
Y482028D03*
Y474941D03*
Y486752D03*
Y479665D03*
Y491476D03*
Y493839D03*
Y521437D03*
Y514350D03*
Y519075D03*
Y511988D03*
Y516713D03*
Y509626D03*
Y535610D03*
Y528524D03*
Y533248D03*
Y526162D03*
Y537973D03*
Y530886D03*
Y523799D03*
Y540335D03*
Y571476D03*
Y564390D03*
Y569114D03*
Y562028D03*
Y566752D03*
Y559665D03*
Y585650D03*
Y578563D03*
Y583288D03*
Y576201D03*
Y588012D03*
Y580925D03*
Y573839D03*
Y599823D03*
Y592736D03*
Y604547D03*
Y597461D03*
Y590374D03*
Y602185D03*
Y595099D03*
Y618721D03*
Y613996D03*
Y606910D03*
Y611634D03*
Y616358D03*
Y609272D03*
Y621083D03*
Y623445D03*
X1552529Y384429D03*
Y386791D03*
Y382067D03*
Y391516D03*
Y389154D03*
Y398602D03*
Y405689D03*
Y393878D03*
Y400965D03*
Y408051D03*
Y396240D03*
Y403327D03*
Y412776D03*
Y419862D03*
Y415138D03*
Y422224D03*
Y410413D03*
Y417500D03*
Y424587D03*
Y434036D03*
Y441122D03*
Y426949D03*
Y436398D03*
Y429311D03*
Y431673D03*
Y438760D03*
Y443484D03*
Y445847D03*
Y465177D03*
Y469902D03*
Y472264D03*
Y467539D03*
Y474626D03*
Y476988D03*
Y484075D03*
Y479350D03*
Y486437D03*
Y481713D03*
Y488799D03*
Y491162D03*
Y493524D03*
Y495886D03*
Y514036D03*
Y521122D03*
Y516398D03*
Y523484D03*
Y511673D03*
Y518760D03*
Y528209D03*
Y535295D03*
Y530571D03*
Y537658D03*
Y525847D03*
Y532933D03*
Y542382D03*
Y544744D03*
Y554193D03*
Y540020D03*
Y547106D03*
Y549469D03*
Y551831D03*
Y556555D03*
Y558917D03*
Y561280D03*
Y563642D03*
Y566004D03*
Y568366D03*
Y570728D03*
Y573091D03*
Y575453D03*
Y597480D03*
Y599843D03*
Y604567D03*
Y592756D03*
Y595118D03*
Y602205D03*
Y609291D03*
Y606929D03*
Y618740D03*
Y614016D03*
Y616378D03*
Y611654D03*
Y623465D03*
Y621102D03*
X1570640Y384429D03*
Y386791D03*
Y382067D03*
Y391516D03*
Y389154D03*
Y398602D03*
Y405689D03*
Y393878D03*
Y400965D03*
Y408051D03*
Y396240D03*
Y403327D03*
Y412776D03*
Y419862D03*
Y415138D03*
Y422224D03*
Y410413D03*
Y417500D03*
Y424587D03*
Y434036D03*
Y441122D03*
Y426949D03*
Y436398D03*
Y429311D03*
Y431673D03*
Y438760D03*
Y443484D03*
Y445847D03*
Y465177D03*
Y469902D03*
Y472264D03*
Y467539D03*
Y474626D03*
Y476988D03*
Y484075D03*
Y479350D03*
Y486437D03*
Y481713D03*
Y488799D03*
Y491162D03*
Y493524D03*
Y495886D03*
Y514036D03*
Y521122D03*
Y516398D03*
Y523484D03*
Y511673D03*
Y518760D03*
Y528209D03*
Y535295D03*
Y530571D03*
Y537658D03*
Y525847D03*
Y532933D03*
Y542382D03*
Y544744D03*
Y549469D03*
Y554193D03*
Y551831D03*
Y540020D03*
Y547106D03*
Y556555D03*
Y558917D03*
Y561280D03*
Y563642D03*
Y566004D03*
Y568366D03*
Y570728D03*
Y573091D03*
Y575453D03*
Y597480D03*
Y599843D03*
Y604567D03*
Y592756D03*
Y595118D03*
Y602205D03*
Y618740D03*
Y611654D03*
Y609291D03*
Y606929D03*
Y614016D03*
Y616378D03*
Y621102D03*
Y623465D03*
X1641565Y386772D03*
Y391496D03*
Y389134D03*
Y384410D03*
Y382047D03*
Y393858D03*
Y408032D03*
Y405669D03*
Y396221D03*
Y398583D03*
Y400945D03*
Y403307D03*
Y412756D03*
Y410394D03*
Y441870D03*
Y439508D03*
Y437146D03*
Y434784D03*
Y432421D03*
Y430059D03*
Y448957D03*
Y446595D03*
Y444232D03*
Y456043D03*
Y451319D03*
Y453681D03*
Y458406D03*
Y463130D03*
Y460768D03*
Y470217D03*
Y467854D03*
Y472579D03*
Y465492D03*
Y484390D03*
Y477303D03*
Y489114D03*
Y482028D03*
Y474941D03*
Y486752D03*
Y479665D03*
Y491476D03*
Y493839D03*
Y521437D03*
Y514350D03*
Y519075D03*
Y511988D03*
Y516713D03*
Y509626D03*
Y535610D03*
Y528524D03*
Y533248D03*
Y526162D03*
Y537973D03*
Y530886D03*
Y523799D03*
Y540335D03*
Y571476D03*
Y564390D03*
Y569114D03*
Y562028D03*
Y566752D03*
Y559665D03*
Y585650D03*
Y578563D03*
Y583288D03*
Y576201D03*
Y588012D03*
Y580925D03*
Y573839D03*
Y599823D03*
Y592736D03*
Y604547D03*
Y597461D03*
Y590374D03*
Y602185D03*
Y595099D03*
Y618721D03*
Y613996D03*
Y606910D03*
Y611634D03*
Y616358D03*
Y609272D03*
Y621083D03*
Y623445D03*
X1659676Y382047D03*
Y384410D03*
Y386772D03*
Y391496D03*
Y389134D03*
Y396221D03*
Y408032D03*
Y405669D03*
Y398583D03*
Y400945D03*
Y403307D03*
Y393858D03*
Y412756D03*
Y410394D03*
Y441870D03*
Y439508D03*
Y437146D03*
Y434784D03*
Y432421D03*
Y430059D03*
Y451319D03*
Y458406D03*
Y448957D03*
Y446595D03*
Y444232D03*
Y456043D03*
Y453681D03*
Y463130D03*
Y460768D03*
Y470217D03*
Y467854D03*
Y472579D03*
Y465492D03*
Y484390D03*
Y477303D03*
Y489114D03*
Y482028D03*
Y474941D03*
Y486752D03*
Y479665D03*
Y491476D03*
Y493839D03*
Y521437D03*
Y514350D03*
Y519075D03*
Y511988D03*
Y516713D03*
Y509626D03*
Y535610D03*
Y528524D03*
Y533248D03*
Y526162D03*
Y537973D03*
Y530886D03*
Y523799D03*
Y540335D03*
Y571476D03*
Y564390D03*
Y569114D03*
Y562028D03*
Y566752D03*
Y559665D03*
Y585650D03*
Y578563D03*
Y583288D03*
Y576201D03*
Y588012D03*
Y580925D03*
Y573839D03*
Y599823D03*
Y592736D03*
Y604547D03*
Y597461D03*
Y590374D03*
Y602185D03*
Y595099D03*
Y618721D03*
Y613996D03*
Y606910D03*
Y611634D03*
Y616358D03*
Y609272D03*
Y621083D03*
Y623445D03*
G54D121*
X343826Y1153242D03*
X341266D03*
X338707D03*
Y1167808D03*
X341266D03*
X343826D03*
X346385Y1153242D03*
Y1167808D03*
X798353Y1153242D03*
X795794D03*
Y1167808D03*
X798353D03*
X803472Y1153242D03*
X800913D03*
Y1167808D03*
X803472D03*
X874909Y761332D03*
X872350D03*
X880028D03*
X877469D03*
Y775898D03*
X874909D03*
X872350D03*
X880028D03*
X1091168Y1606949D03*
Y1621515D03*
X1093727Y1606949D03*
X1098846D03*
X1096287D03*
Y1621515D03*
X1093727D03*
X1098846D03*
X1252880Y1153242D03*
Y1167808D03*
X1260558Y1153242D03*
X1257999D03*
X1255439D03*
Y1167808D03*
X1257999D03*
X1260558D03*
X1717645Y1153242D03*
X1715086D03*
X1712526D03*
X1709967D03*
Y1167808D03*
X1712526D03*
X1715086D03*
X1717645D03*
G54D202*
X843012Y1592787D03*
Y1602787D03*
Y1612787D03*
Y1622787D03*
X853012Y1592787D03*
Y1602787D03*
Y1612787D03*
Y1622787D03*
X878012Y1592787D03*
Y1602787D03*
Y1612787D03*
Y1622787D03*
X888012Y1592787D03*
Y1602787D03*
Y1612787D03*
Y1622787D03*
X913012Y1592787D03*
Y1602787D03*
Y1612787D03*
Y1622787D03*
X923012Y1592787D03*
Y1602787D03*
Y1612787D03*
Y1622787D03*
X948012Y1592787D03*
Y1602787D03*
Y1612787D03*
Y1622787D03*
X958012Y1592787D03*
Y1602787D03*
Y1612787D03*
Y1622787D03*
X983012Y1592787D03*
X993012D03*
X983012Y1602787D03*
Y1612787D03*
X993012Y1602787D03*
Y1612787D03*
X983012Y1622787D03*
X993012D03*
X1018012Y1592787D03*
X1028012D03*
X1018012Y1602787D03*
Y1612787D03*
X1028012Y1602787D03*
Y1612787D03*
X1018012Y1622787D03*
G54D130*
X389627Y877960D03*
G54D10*
G01X8786Y85503D02*
Y88425D01*
G01X18298Y99741D02*
Y102141D01*
G01X6298Y99741D02*
Y100798D01*
X8000Y102500D01*
G01X20079Y1433831D02*
Y1429347D01*
G01X12599Y1433831D02*
Y1438143D01*
G01X16339Y1441705D02*
X12561Y1445483D01*
Y1449735D01*
G01X16339Y1441705D02*
X16342Y1441702D01*
X27222D01*
G01X19454Y1464612D02*
X22284D01*
G01X16301Y1457609D02*
Y1464609D01*
X16304Y1464612D01*
G01D02*
Y1468196D01*
G01X27222Y1441702D02*
X29880D01*
G01X76033Y821918D02*
X74349D01*
G01X76033D02*
X82362Y828247D01*
Y851064D01*
X87641Y856343D01*
X110915D01*
X117145Y862573D01*
Y947893D01*
X90563Y974475D01*
Y996129D01*
G01X163191Y1065313D02*
X168707Y1059797D01*
Y1038179D01*
X164955Y1034427D01*
Y876985D01*
X136056Y848086D01*
X86367D01*
G01X166188Y1066551D02*
X183833D01*
X195955Y1054429D01*
Y1033712D01*
G01X197073Y68581D02*
X199473D01*
G01X199486Y80581D02*
X197073D01*
G01X299435Y68581D02*
X301835D01*
G01X301848Y80581D02*
X299435D01*
G01X408680Y37530D02*
Y39943D01*
G01X396680D02*
Y37543D01*
G01X551798Y68581D02*
X554198D01*
G01X554211Y80581D02*
X551798D01*
G01X654160Y68581D02*
X656560D01*
G01X656573Y80581D02*
X654160D01*
G01X739358Y1617010D02*
X735878D01*
G01X756522Y68581D02*
X758922D01*
G01X758935Y80581D02*
X756522D01*
G01X858884Y68581D02*
X861284D01*
G01X861297Y80581D02*
X858884D01*
G01X934928Y954377D02*
X969807D01*
X975402Y948782D01*
G01Y929255D02*
X957229Y911082D01*
G01X927631Y798271D02*
X923872D01*
G01X952695Y1444139D02*
X949110D01*
G01X975268Y1444392D02*
X978934D01*
G01X1008884Y68581D02*
X1011284D01*
G01X1011297Y80581D02*
X1008884D01*
G01X998334Y1444392D02*
X1002194D01*
G01X1026283Y820194D02*
X1030635Y824546D01*
G01X1026283Y828898D02*
X1030635Y824546D01*
G01X1011782Y1013972D02*
Y1016591D01*
G01X1021366Y1444492D02*
X1025615D01*
G01X1030635Y824546D02*
X1034987Y828898D01*
G01X1030635Y824546D02*
X1034987Y820194D01*
G01X1048403Y1444608D02*
X1044252D01*
G01X1111246Y68581D02*
X1113646D01*
G01X1113659Y80581D02*
X1111246D01*
G01X1213608Y68581D02*
X1216008D01*
G01X1216021Y80581D02*
X1213608D01*
G01X1310853Y39943D02*
Y37543D01*
G01X1322853Y37530D02*
Y39943D01*
G01X1430174Y976075D02*
X1434267D01*
X1438454Y971888D01*
X1449817D01*
X1451316Y970389D01*
Y961865D01*
X1449423Y959972D01*
X1441320D01*
X1439031Y957683D01*
G01X1465971Y68581D02*
X1468371D01*
G01X1468384Y80581D02*
X1465971D01*
G01X1568333Y68581D02*
X1570733D01*
G01X1570746Y80581D02*
X1568333D01*
G01X1670695Y68581D02*
X1673095D01*
G01X1673108Y80581D02*
X1670695D01*
G01X1773057Y68581D02*
X1775457D01*
G01X1775470Y80581D02*
X1773057D01*
G01X1776071Y833319D02*
Y826650D01*
X1775991Y826570D01*
G01D02*
X1779404D01*
X3704Y5374D03*
X3017Y24773D03*
Y44773D03*
Y64773D03*
Y84773D03*
Y104773D03*
Y124773D03*
Y144773D03*
Y164773D03*
Y184773D03*
Y204773D03*
Y224773D03*
Y244773D03*
Y264773D03*
Y284773D03*
Y304773D03*
X3221Y324773D03*
X3035Y978036D03*
Y998036D03*
Y1018036D03*
Y1038036D03*
Y1058036D03*
Y1078036D03*
Y1098036D03*
Y1118036D03*
Y1138036D03*
Y1158036D03*
Y1178036D03*
Y1198036D03*
Y1238036D03*
Y1258036D03*
Y1278036D03*
Y1298036D03*
Y1318036D03*
Y1338036D03*
Y1358036D03*
Y1378036D03*
Y1398036D03*
Y1418036D03*
Y1438036D03*
Y1458036D03*
Y1478036D03*
Y1498036D03*
Y1538036D03*
Y1558036D03*
Y1578036D03*
X3017Y1639466D03*
X15972Y3000D03*
X20408Y51296D03*
Y55296D03*
X14751Y62381D03*
X7271Y70981D03*
X11011Y79720D03*
X12601Y92110D03*
X8786Y88425D03*
X14264Y94236D03*
X10292D03*
X12786Y87903D03*
X18000Y90000D03*
X9364Y107501D03*
X16728Y107910D03*
X12652Y116894D03*
X18298Y102141D03*
X8000Y102500D03*
X10131Y115473D03*
X15143Y115581D03*
X14996Y133034D03*
X11442Y132719D03*
X19855Y133000D03*
X9057Y138939D03*
X19184Y144728D03*
X15184D03*
X9082Y135789D03*
X19855Y141362D03*
X11999Y141415D03*
X15948Y141267D03*
X13615Y153263D03*
X10966Y155873D03*
Y152873D03*
Y162073D03*
Y159073D03*
X16909Y153263D03*
X12247Y166341D03*
X17313Y166937D03*
X21909Y153263D03*
X22335Y166721D03*
X12709Y175777D03*
X16709Y175943D03*
X15139Y198883D03*
X15520Y195176D03*
X18320D03*
X13020D03*
X10520D03*
X15139Y201683D03*
X12880Y203393D03*
X10380D03*
X19068Y206838D03*
X16568D03*
X19572Y219470D03*
Y221970D03*
X10259Y218085D03*
X13059D03*
X19638Y226320D03*
X16859Y216385D03*
X19572Y216970D03*
X22599Y228646D03*
X18564Y238589D03*
X9745Y245784D03*
X18206Y244571D03*
X15586Y249108D03*
X13715Y259381D03*
X8970Y254871D03*
X18206Y264571D03*
X19075Y278429D03*
X7036Y268371D03*
Y272371D03*
X8335Y280663D03*
X14807Y282181D03*
X15586Y269108D03*
X15499Y288542D03*
X10971Y333342D03*
X17964Y349298D03*
Y369298D03*
Y389298D03*
Y409298D03*
Y429298D03*
Y449298D03*
Y469298D03*
Y489298D03*
Y509298D03*
Y529298D03*
Y549298D03*
Y569298D03*
Y589298D03*
Y609298D03*
Y629298D03*
Y649298D03*
Y669298D03*
Y689298D03*
Y709298D03*
Y729298D03*
Y749298D03*
Y769298D03*
Y789298D03*
Y809298D03*
Y829298D03*
Y849298D03*
Y869298D03*
Y889298D03*
Y909298D03*
Y929298D03*
X9554Y961954D03*
X17964Y949298D03*
X17033Y1006819D03*
X14357Y1009906D03*
X20216Y1009748D03*
X14197Y1014205D03*
Y1017759D03*
X20197Y1014205D03*
Y1017759D03*
X6161Y1075991D03*
X6108Y1070611D03*
Y1065318D03*
X6059Y1091964D03*
X6055Y1086546D03*
X6053Y1081305D03*
X14252Y1121333D03*
X11552D03*
X16752D03*
X8952D03*
X14152Y1111633D03*
X11452D03*
X8852D03*
X16652D03*
X14252Y1130333D03*
X16752D03*
X14306Y1138705D03*
X16806D03*
X20079Y1429347D03*
X12599Y1438143D03*
X16304Y1468196D03*
X13606Y1476707D03*
X6690Y1496782D03*
X19365Y1494298D03*
X15889Y1494254D03*
X10089D03*
X6489Y1501334D03*
X19745Y1508846D03*
X8042Y1522199D03*
X12327Y1519202D03*
X7983Y1529035D03*
Y1525635D03*
X19735Y1530499D03*
X19859Y1520657D03*
X7922Y1532494D03*
X11995Y1535134D03*
X6951Y1538547D03*
X18879Y1534334D03*
X6567Y1554215D03*
X14375Y1553121D03*
X18409Y1554202D03*
X10367Y1553080D03*
X12000Y1644980D03*
X26956Y4469D03*
X28317Y24773D03*
Y44773D03*
X24316Y67527D03*
Y63527D03*
Y59527D03*
X35638Y53597D03*
X32350Y67562D03*
X28442Y55340D03*
X32350Y59562D03*
Y63562D03*
X26588Y97667D03*
X35442D03*
X35048Y103411D03*
X33288Y109410D03*
Y116497D03*
X30788D03*
X25988D03*
X22439Y106495D03*
X35688Y111255D03*
Y114655D03*
X22439Y102495D03*
X35207Y106561D03*
X30788Y123584D03*
X33288Y123583D03*
X25988Y123584D03*
X33288Y130670D03*
X30788D03*
X25988D03*
X28388Y121742D03*
X35688Y125428D03*
X28388Y132515D03*
Y118342D03*
X35688Y128828D03*
X30788Y137757D03*
X25988D03*
X23184Y144728D03*
X28388Y135915D03*
X29201Y151651D03*
X26201D03*
X22935Y162073D03*
Y159073D03*
X20709Y175777D03*
X26565Y177448D03*
X32507Y180517D03*
X30567Y195176D03*
X28067D03*
X25567D03*
X33067D03*
X29585Y199248D03*
X32585D03*
X34520Y213539D03*
X29921Y206806D03*
X32585Y202048D03*
X25648Y210509D03*
X28148D03*
X29585Y201748D03*
X27421Y206806D03*
X27340Y230556D03*
X36185Y230117D03*
X31595Y227824D03*
X36201Y238714D03*
X21530Y236121D03*
X27966Y238689D03*
X28740Y247292D03*
X32201Y238714D03*
X23844Y239299D03*
X21556Y232971D03*
X31682Y246874D03*
X33902Y244297D03*
X21449Y253198D03*
X26325Y262078D03*
X25549Y256394D03*
X28740Y267292D03*
X21386Y273198D03*
X31682Y266874D03*
X29116Y281129D03*
X37117Y279991D03*
X25549Y276394D03*
X23479Y295619D03*
X34845Y291756D03*
X26629Y295619D03*
X35650Y487982D03*
Y478982D03*
Y483982D03*
Y499982D03*
Y491982D03*
Y495982D03*
X25819Y531726D03*
Y536726D03*
X30177Y534211D03*
X34359Y541135D03*
X34732Y534909D03*
X25819Y527726D03*
Y552726D03*
Y540726D03*
Y548726D03*
X34425Y546553D03*
X34448Y552726D03*
X25819Y544726D03*
X32452Y581222D03*
X29652D03*
X35252D03*
Y591215D03*
X29652D03*
X32452D03*
X34254Y611091D03*
X30123Y611071D03*
X27686Y621311D03*
X36494Y616905D03*
X36306Y622285D03*
X29451Y633560D03*
X27686Y629311D03*
Y625311D03*
X36692Y633724D03*
X36575Y627713D03*
X36692Y641817D03*
X30369Y663048D03*
X27625Y663094D03*
X35293Y662952D03*
X25818Y682139D03*
X27854Y671553D03*
X30414Y671508D03*
X28818Y682139D03*
X35250Y671508D03*
X34565Y699082D03*
X26596Y874520D03*
X26844Y920354D03*
X24132Y958151D03*
X25371Y980696D03*
X36529Y1006321D03*
X30479Y1006509D03*
X24456Y1006401D03*
X32093Y1009748D03*
X26155Y1009985D03*
X29197Y1014205D03*
X32197Y1017759D03*
X26197D03*
X35197Y1014205D03*
X21196Y1065529D03*
Y1063029D03*
X36089Y1062601D03*
Y1065101D03*
X35925Y1075663D03*
X33425D03*
X28996Y1065529D03*
X23796D03*
X26396D03*
Y1063029D03*
X23796D03*
X28996D03*
X28606Y1082678D03*
X23406D03*
X26006D03*
Y1080178D03*
X23406D03*
X28606D03*
X20806Y1082678D03*
Y1080178D03*
X21321Y1098769D03*
X26521D03*
X29121D03*
X23921D03*
Y1101335D03*
X29121D03*
X26521D03*
X21321D03*
X32574Y1111633D03*
X29874D03*
X27274D03*
X24674D03*
Y1121333D03*
X27274D03*
X29874D03*
X32574D03*
X24674Y1130333D03*
X21974D03*
X21209Y1138705D03*
X23709D03*
X27934Y1204311D03*
X30934D03*
X31631Y1198651D03*
X30410Y1218497D03*
Y1220997D03*
X27934Y1215511D03*
X30934D03*
X34314Y1215403D03*
X27934Y1212711D03*
Y1209911D03*
Y1207111D03*
X30934Y1212711D03*
Y1209911D03*
Y1207111D03*
X30410Y1234797D03*
Y1232297D03*
Y1227897D03*
Y1225397D03*
Y1241697D03*
Y1239197D03*
X29860Y1438552D03*
X23603Y1449735D03*
X29880Y1441702D03*
X22284Y1464612D03*
X35825Y1464845D03*
X21544Y1479662D03*
X33536Y1467485D03*
X21544Y1489648D03*
X25674Y1486291D03*
X32195Y1511279D03*
X33189Y1501373D03*
X32079Y1525641D03*
Y1521641D03*
Y1517641D03*
X35237Y1532096D03*
X31237D03*
X35850Y1556096D03*
X22381Y1554152D03*
X26231Y1554167D03*
X32000Y1644980D03*
X46450Y82984D03*
Y77784D03*
Y75184D03*
Y80384D03*
X48364Y92473D03*
X46450Y85584D03*
X45988Y90512D03*
X51550Y90615D03*
X37988Y109410D03*
X46240D03*
X45988Y102323D03*
X46240Y116496D03*
X37988Y102323D03*
Y116496D03*
X46931Y130670D03*
X49236Y121658D03*
X37988Y130670D03*
Y123583D03*
X46932Y137756D03*
X52437D03*
X37988D03*
X45984Y163264D03*
X48476Y180812D03*
X37284Y285272D03*
X42690Y451466D03*
X48596Y458466D03*
X48643Y442919D03*
X48596Y451419D03*
X45643Y472905D03*
X41643Y473419D03*
X49643Y472905D03*
Y464419D03*
X41643Y464919D03*
X48390Y485128D03*
X51239Y485138D03*
X40009Y481467D03*
X43948Y492108D03*
X44563Y482165D03*
X39801Y504825D03*
X42301D03*
X44801D03*
X43804Y500202D03*
X45256Y495993D03*
X45293Y522569D03*
X39742Y517401D03*
X42242D03*
X44742D03*
X46993Y529169D03*
X41408Y531882D03*
X43908D03*
X45293Y525369D03*
X46408Y531882D03*
X38358Y531948D03*
X52869Y537958D03*
X39643Y555194D03*
X36843D03*
X49839Y546830D03*
X46643Y555194D03*
X52869Y540458D03*
X43843Y555194D03*
X39643Y563194D03*
X36843D03*
X39643Y571194D03*
X36843D03*
X46643D03*
X43843D03*
Y563194D03*
X46643D03*
X51000Y581222D03*
X45400D03*
X48200D03*
X51000Y591215D03*
X45400D03*
X48200D03*
X51172Y607762D03*
X48372D03*
X45572D03*
Y610562D03*
X48372D03*
X51172D03*
X40362Y610548D03*
X54192Y633473D03*
X42172Y633716D03*
X49192Y628078D03*
X47179Y633736D03*
X42192Y641817D03*
X37847Y662910D03*
X39549Y682108D03*
X36910D03*
X37804Y671508D03*
X40165Y699082D03*
X37365D03*
X51449Y822718D03*
X47949D03*
X49249Y837718D03*
X52349D03*
X46049D03*
X53549Y843118D03*
X49265Y886660D03*
X52922Y900295D03*
X52077Y905295D03*
X48429Y916430D03*
X47264Y919649D03*
X47916Y947622D03*
X48683Y1006510D03*
X42470Y1006738D03*
X50541Y1009589D03*
X44999Y1009510D03*
X38823Y1009273D03*
X47197Y1014205D03*
X41197D03*
X44197Y1017759D03*
X38197D03*
X48704Y1017982D03*
X43889Y1062601D03*
X38689D03*
X41289D03*
Y1065101D03*
X38689D03*
X43889D03*
X47314Y1072228D03*
X50366Y1086981D03*
Y1082388D03*
X38200Y1089721D03*
X44365Y1086404D03*
X41172Y1079064D03*
X38216Y1093757D03*
X46166D03*
X39659Y1105100D03*
X42259D03*
X44859D03*
X47559D03*
X48585Y1123867D03*
X47559Y1114800D03*
X44859D03*
X42259D03*
X39659D03*
X48547Y1133688D03*
X51047D03*
X44960Y1190619D03*
X49500Y1199066D03*
X49638Y1203884D03*
X55188Y1205179D03*
X51023Y1201416D03*
X51197Y1218206D03*
X48842Y1211109D03*
X53479Y1216256D03*
X39452Y1250932D03*
X43198Y1254055D03*
X45698D03*
X48198D03*
X45698Y1251555D03*
X43198D03*
X48198D03*
X47621Y1343672D03*
X39225Y1464845D03*
X40996Y1467703D03*
X44195Y1511279D03*
X48195D03*
X40195D03*
X48089Y1501387D03*
X39095Y1501361D03*
X48079Y1525641D03*
Y1529641D03*
Y1521641D03*
X39237Y1532096D03*
X52048Y1556062D03*
X47074Y1555923D03*
X40951Y1555932D03*
X52000Y1644980D03*
X55638Y53597D03*
X64785Y79993D03*
Y82593D03*
Y85193D03*
Y74793D03*
Y77393D03*
X64829Y92874D03*
X55871Y99961D03*
X55921Y95236D03*
X56098Y109410D03*
Y116496D03*
X55964Y103037D03*
X64098Y102323D03*
Y109410D03*
Y116496D03*
X66856Y104249D03*
Y107649D03*
X56098Y123583D03*
Y130670D03*
X64098Y123583D03*
Y130670D03*
Y137756D03*
X66478Y162368D03*
X63878D03*
X69261Y211695D03*
Y208695D03*
X65189Y210713D03*
Y213213D03*
Y208213D03*
X54733Y212978D03*
Y215478D03*
Y207978D03*
Y210478D03*
X65189Y228961D03*
Y231461D03*
Y223661D03*
Y226461D03*
X68896Y226141D03*
X54733Y231226D03*
Y228726D03*
Y223726D03*
Y226226D03*
X65189Y215713D03*
X69139Y236611D03*
X68841Y248891D03*
X57987Y258880D03*
X60562Y264180D03*
X58062D03*
X66956Y267526D03*
Y270026D03*
X58279Y293796D03*
X66293Y285690D03*
X68793D03*
X66293Y288190D03*
X68793D03*
X60779Y293796D03*
X65759Y437508D03*
X61759D03*
X57759D03*
X54936Y449352D03*
X59522Y448874D03*
X68619Y447269D03*
X68497Y450201D03*
X54167Y457339D03*
X56667D03*
X65737Y445603D03*
X57857Y446071D03*
X66224Y473045D03*
X58224D03*
X53643Y472905D03*
X56667Y459839D03*
X54167D03*
Y462339D03*
X56667D03*
X62224Y473045D03*
X67670Y464818D03*
X58224Y465004D03*
X63154Y462371D03*
X66371Y482134D03*
Y484634D03*
X55124Y478625D03*
X53739Y485138D03*
X56239D03*
X56824Y482425D03*
X55124Y475825D03*
X62700Y491214D03*
X59670Y500086D03*
X64550Y504699D03*
X62050D03*
X59550D03*
X66403Y495487D03*
X62700Y493714D03*
X66403Y492987D03*
X68236Y519458D03*
X61752Y516979D03*
X64252D03*
X59252D03*
X60233Y521804D03*
X68202Y522129D03*
X64495Y527449D03*
X60233Y524304D03*
X56540Y531378D03*
Y528878D03*
X61695Y527449D03*
X68202Y527129D03*
Y524629D03*
Y529629D03*
Y537877D03*
X56572Y539731D03*
X68202Y542877D03*
Y545377D03*
Y540377D03*
X61330Y544895D03*
X56572Y542231D03*
X64130Y541895D03*
Y544895D03*
X61630Y541895D03*
X68188Y548358D03*
X67622Y572842D03*
X64408Y572975D03*
Y582747D03*
X63859Y590801D03*
X67684Y597232D03*
X63684Y597130D03*
X67684Y605637D03*
X62789Y608311D03*
X61854Y617853D03*
Y620653D03*
X53972Y607762D03*
Y610562D03*
X59684Y605443D03*
X63684D03*
X66510Y628242D03*
X55318Y629362D03*
X53129Y627948D03*
X66530Y625013D03*
X58181Y627908D03*
X64692Y642184D03*
X55307Y688473D03*
X60849Y826818D03*
X64649D03*
X58949Y821018D03*
X56049Y827218D03*
X68649D03*
X64849Y840418D03*
X60249D03*
X69049Y847718D03*
X65549Y850718D03*
X68598Y859415D03*
X66342Y880067D03*
X67316Y865869D03*
X68778Y873821D03*
X63969Y869475D03*
X63930Y874694D03*
X64175Y897500D03*
X67461Y912983D03*
X63303Y912835D03*
X68100Y910122D03*
X71528Y913190D03*
X64632Y901500D03*
X59962Y910251D03*
X57178Y981386D03*
X53197Y1014205D03*
Y1017759D03*
X69263Y1053152D03*
X55699Y1072761D03*
X61588Y1074481D03*
X55049Y1082343D03*
X55004Y1086937D03*
X62109Y1087656D03*
Y1084656D03*
Y1079656D03*
Y1091656D03*
X58981Y1105100D03*
X56381D03*
X61581D03*
X64281D03*
X61681Y1114800D03*
X56481D03*
X59081D03*
X64381D03*
X57218Y1123867D03*
X55397Y1133688D03*
X57897D03*
X60269Y1198820D03*
X63094Y1207604D03*
X58250Y1220896D03*
X65940Y1209382D03*
X55596Y1210466D03*
X68245Y1212054D03*
X58250Y1227796D03*
Y1230296D03*
Y1237196D03*
Y1234696D03*
Y1223396D03*
X58443Y1272257D03*
X57185Y1480808D03*
X57144Y1491047D03*
X54843Y1501625D03*
X60227Y1514751D03*
X60277Y1528395D03*
X55862Y1541791D03*
X65478Y1541980D03*
X60303Y1534436D03*
X56114Y1556061D03*
X60747Y1555890D03*
X64747D03*
X68743Y1583498D03*
X60864Y1583484D03*
X58064D03*
X55264D03*
X69816Y1592527D03*
X60554Y1612002D03*
Y1615152D03*
X66291Y1633801D03*
X74432Y5374D03*
X73745Y24773D03*
Y44773D03*
X73381Y94017D03*
X69381D03*
X73110Y101701D03*
Y98551D03*
X77804Y95879D03*
X76005Y114623D03*
X73509Y110445D03*
X78501D03*
X73509Y115401D03*
X78501D03*
X83911Y117557D03*
X80660Y103783D03*
X76005Y111223D03*
X76660Y103783D03*
X73509Y129574D03*
Y124618D03*
X78501Y129574D03*
Y124618D03*
X83911Y122513D03*
Y131731D03*
X76005Y125396D03*
Y128796D03*
X83911Y136687D03*
X75194Y141247D03*
X71422Y147540D03*
X82661Y143740D03*
X80041Y148277D03*
X71422Y151540D03*
X73578Y165393D03*
Y162793D03*
Y170493D03*
Y167993D03*
X80502Y177616D03*
X81083Y172190D03*
X72575Y181426D03*
X75786Y181366D03*
X78581Y181009D03*
X83756Y168697D03*
X75072Y191941D03*
X81572Y184619D03*
X74939Y188727D03*
X84844Y191941D03*
X75400Y184012D03*
X72783Y184221D03*
X83552Y206760D03*
X72061Y208695D03*
X71761Y211695D03*
X76819Y213859D03*
Y211359D03*
X80522Y213132D03*
X73158Y229286D03*
X76851Y222212D03*
X71696Y226141D03*
X76851Y224712D03*
X80522Y215632D03*
X74139Y236611D03*
X71639D03*
X73158Y231786D03*
X71341Y248891D03*
X73841D03*
X76766Y256535D03*
X84766D03*
X80766Y256303D03*
X75438Y265701D03*
X85541Y266114D03*
X80525Y265896D03*
X72256Y267526D03*
X69756D03*
Y270026D03*
X72256D03*
X83014Y281982D03*
X77073Y281716D03*
X71593Y285690D03*
Y288190D03*
X75819Y290755D03*
X79819D03*
X83819D03*
X71130Y462152D03*
Y459652D03*
Y464652D03*
X73630Y459652D03*
Y462152D03*
Y464652D03*
X71826Y480705D03*
X74326D03*
X69816Y475946D03*
Y478446D03*
X78033Y478586D03*
Y481086D03*
Y476086D03*
Y483586D03*
Y491133D03*
X71461Y498151D03*
Y495151D03*
X73961D03*
X78033Y498633D03*
Y496133D03*
Y493633D03*
X73961Y498151D03*
X75736Y519458D03*
X73236D03*
X70736D03*
X71995Y532749D03*
X74795D03*
X78133Y553297D03*
Y555897D03*
X75688Y548358D03*
X73188D03*
X70688D03*
X78133Y558497D03*
Y566597D03*
Y563697D03*
Y561097D03*
X72128Y570686D03*
X74923Y570478D03*
X75777Y585507D03*
X71184D03*
X71730Y579475D03*
X75340Y576484D03*
X74983Y573689D03*
X72337Y573303D03*
X78733Y578405D03*
X84159Y578986D03*
X71228Y590145D03*
X75822Y590190D03*
X83684Y596729D03*
X72515Y596089D03*
X77734Y596782D03*
X75684Y605443D03*
X83684D03*
X81740Y619758D03*
Y616958D03*
Y614158D03*
X69670Y619513D03*
Y616713D03*
Y613913D03*
X79684Y605443D03*
X81740Y636250D03*
X69670Y633205D03*
Y636005D03*
X81740Y633450D03*
X69670Y638805D03*
X81740Y639050D03*
X78129Y656900D03*
X82648Y670679D03*
X73914Y660107D03*
X79043Y667391D03*
X84845Y659857D03*
X72314Y680207D03*
Y683407D03*
X82714Y674707D03*
X74414Y681907D03*
X84314Y686107D03*
X82562Y680037D03*
X78735Y683426D03*
X72149Y827318D03*
X74349Y824718D03*
Y821918D03*
X72549Y838818D03*
X74700Y842890D03*
X71928Y873683D03*
X84367Y878286D03*
X76528Y878533D03*
X74028Y889065D03*
X83079Y888515D03*
X72035Y898346D03*
X80339Y897943D03*
X76203Y897910D03*
X76991Y946134D03*
X80593Y946082D03*
X78167Y949261D03*
X76332Y953421D03*
X87632Y1007522D03*
X84679Y1018368D03*
X70059Y1071656D03*
X69373Y1063389D03*
X70059Y1075656D03*
X70302Y1067656D03*
X70059Y1079656D03*
X77734Y1095676D03*
X70947Y1201565D03*
Y1205835D03*
X71006Y1228684D03*
X71020Y1224323D03*
X87000Y1597855D03*
X76005Y1580680D03*
X82433Y1580590D03*
X74909Y1593009D03*
X71910Y1625009D03*
X78291Y1625743D03*
X83689Y1624736D03*
X74291Y1633801D03*
X82291D03*
X78291D03*
X70291D03*
X72000Y1644980D03*
X93334Y3000D03*
X88080Y103603D03*
X88903Y117557D03*
X86407Y132509D03*
Y118335D03*
X88903Y122513D03*
Y131731D03*
X86407Y121735D03*
X87002Y146461D03*
X88903Y136687D03*
X86407Y135909D03*
X91224Y141247D03*
X92337Y144172D03*
X95711Y143518D03*
X94811Y152373D03*
X85904Y152367D03*
X97961Y152562D03*
X103456Y157370D03*
X87604Y180572D03*
X92287Y180527D03*
X98826Y172665D03*
X98763Y178560D03*
X98653Y183834D03*
X96010Y192421D03*
X92242Y185121D03*
X87604Y185165D03*
X99639Y186629D03*
X98943Y200864D03*
X92898Y192490D03*
X98173Y190185D03*
X89353Y206767D03*
X86853D03*
X91853D03*
X98966Y207037D03*
X99032Y212455D03*
X89483Y221708D03*
X86983D03*
X86398Y224421D03*
X88098Y231021D03*
Y228221D03*
X96333Y221642D03*
X91983Y221708D03*
X103841Y228631D03*
X93649Y236189D03*
X91149D03*
X88649D03*
X91090Y248765D03*
X88590D03*
X93590D03*
X85796Y279208D03*
X89900Y281307D03*
X97747Y265897D03*
X100247D03*
X94087Y270695D03*
X91287D03*
X88787D03*
Y268195D03*
X91287D03*
X94087D03*
X94390Y293645D03*
Y290845D03*
Y288345D03*
X91890Y293645D03*
Y290845D03*
Y288345D03*
X95943Y377953D03*
X98255Y374510D03*
X100120Y377898D03*
X100066Y381976D03*
X90257Y445506D03*
X86788Y581659D03*
X87684Y605443D03*
X93456Y649838D03*
X89432Y668293D03*
X92134D03*
X95973Y655660D03*
X92897Y658359D03*
X95917Y658374D03*
X95539Y664443D03*
X85614Y674707D03*
X87714Y684607D03*
X86289Y822088D03*
X88875Y840940D03*
X86367Y848086D03*
X91581Y877859D03*
Y874859D03*
X90000Y871389D03*
X103770Y868206D03*
X87853Y899220D03*
X103692Y900295D03*
X91387Y905295D03*
X100058Y977651D03*
X99836Y980330D03*
X103836Y988813D03*
X100200Y988800D03*
X95836Y988813D03*
X91128Y1006487D03*
X99836Y997860D03*
X95836D03*
X85706Y998507D03*
X94398Y1006648D03*
X101025Y1009655D03*
X94586Y1023900D03*
X91765Y1018307D03*
X88007Y1013678D03*
X88479Y1023731D03*
X88287Y1026537D03*
X97609Y1018469D03*
X100594Y1035088D03*
X97247Y1030568D03*
X90450Y1033542D03*
X103124Y1165091D03*
X93496Y1547768D03*
X86291Y1633801D03*
X92000Y1644980D03*
X113334Y3000D03*
X119582Y102249D03*
X107364Y113394D03*
Y110394D03*
X111582Y102249D03*
X110013Y110784D03*
X115582Y102249D03*
X107364Y116594D03*
X118307Y110784D03*
X113307D03*
X110152Y130898D03*
X117607Y133298D03*
X107364Y119594D03*
X117886Y124663D03*
X112864Y124879D03*
X107798Y124283D03*
X111754Y134579D03*
X119230Y138838D03*
X106205Y161306D03*
X107540Y172665D03*
Y180665D03*
Y176665D03*
Y168665D03*
X117501Y198883D03*
X115382Y195176D03*
X112882D03*
X117882D03*
X107540Y196665D03*
Y192665D03*
X107653Y186778D03*
X117501Y201683D03*
X115242Y203393D03*
X112742D03*
X107572Y200864D03*
Y212864D03*
Y204864D03*
Y208864D03*
Y216864D03*
Y221864D03*
X112621Y218085D03*
X115421D03*
X103213Y219379D03*
X117948Y249108D03*
X109329Y252371D03*
Y248371D03*
X112474Y716315D03*
X111993Y710102D03*
X114397Y727974D03*
X120250Y758841D03*
X113505Y796856D03*
X109591Y796905D03*
X113601Y881266D03*
X107641Y865224D03*
X102355Y874267D03*
X102947Y877196D03*
X102320Y891043D03*
X110887Y884000D03*
X103972Y977609D03*
X103836Y980330D03*
X111836Y988813D03*
X119836D03*
X115836D03*
X107836D03*
X103836Y997860D03*
X111836D03*
X111275Y1008262D03*
X114770Y1009354D03*
X107836Y997860D03*
X115836D03*
X103825Y1009655D03*
X111275Y1011762D03*
X105971Y1025745D03*
X114770Y1016827D03*
X110409Y1024094D03*
X114770Y1029427D03*
X110970Y1030672D03*
X101970D03*
X104970D03*
X107970D03*
X108933Y1102091D03*
X112433D03*
X103124D03*
X102761Y1096233D03*
X108971Y1109564D03*
X112433Y1114691D03*
X103124D03*
X108933D03*
X103124Y1109564D03*
Y1122164D03*
X108971D03*
X108933Y1127291D03*
X112433D03*
X103124D03*
X112433Y1139891D03*
X103124Y1134764D03*
X108971D03*
X103124Y1152491D03*
X108933D03*
X112433D03*
X103124Y1147364D03*
X108971D03*
X108933Y1165091D03*
X112433D03*
X103124Y1172564D03*
X108971D03*
X103124Y1159964D03*
X108971D03*
X103184Y1177691D03*
X108933D03*
X112433D03*
X103861Y1182703D03*
X109415Y1202103D03*
X106586Y1204932D03*
X118533Y1207737D03*
X112048Y1214372D03*
X107803Y1218169D03*
X112795Y1223749D03*
X107669Y1456451D03*
Y1465913D03*
X116330Y1465513D03*
X107669Y1461182D03*
X116330Y1460782D03*
X107669Y1481267D03*
X116330Y1480867D03*
X107669Y1476536D03*
X116330Y1476136D03*
Y1470244D03*
X107669Y1471805D03*
X116330Y1491490D03*
Y1485598D03*
X107669Y1487159D03*
Y1496621D03*
X116330Y1496221D03*
X107669Y1491890D03*
X116330Y1506845D03*
Y1500952D03*
X107669Y1502514D03*
X116330Y1511576D03*
X107669Y1511976D03*
Y1507245D03*
X116330Y1516307D03*
X107669Y1563544D03*
X116330Y1563144D03*
X107669Y1558813D03*
Y1568275D03*
X116330Y1567875D03*
X107669Y1578898D03*
X116330Y1578498D03*
Y1572606D03*
X107669Y1574167D03*
Y1583629D03*
X116330Y1583229D03*
X107669Y1594253D03*
X116330Y1593853D03*
Y1587960D03*
X107669Y1589522D03*
Y1609607D03*
X116330Y1609207D03*
X107669Y1598984D03*
X116330Y1598584D03*
Y1603315D03*
X107669Y1604876D03*
X116330Y1613938D03*
Y1618669D03*
X107669Y1614338D03*
X112000Y1644980D03*
X129318Y4469D03*
X130679Y24773D03*
Y44773D03*
X128950Y97667D03*
X133200Y95111D03*
X128350Y116497D03*
X133150D03*
X124606Y106495D03*
X125599Y109172D03*
X122599D03*
X124606Y102495D03*
X119333Y116594D03*
X133150Y123584D03*
X128350D03*
X133150Y130670D03*
X128350D03*
X130750Y132515D03*
Y121742D03*
Y118342D03*
X119333Y119594D03*
X122867Y125107D03*
X128350Y137757D03*
X133150D03*
X126246Y141228D03*
X124340Y146012D03*
X130750Y135915D03*
X124340Y142862D03*
X131481Y143762D03*
X125381Y148717D03*
X129134Y150847D03*
X120682Y195176D03*
X131947Y199248D03*
X127929Y195176D03*
X130429D03*
X132929D03*
X134947Y199248D03*
X118930Y206838D03*
X121430D03*
X128010Y210509D03*
X130510D03*
X132283Y206806D03*
X129783D03*
X131947Y201748D03*
X122000Y226320D03*
X119221Y216385D03*
X121934Y216970D03*
Y219470D03*
Y221970D03*
X129702Y230556D03*
X133957Y227824D03*
X124961Y228646D03*
X131102Y247292D03*
X130328Y238689D03*
X123892Y236121D03*
X120926Y238589D03*
X128687Y242078D03*
X123918Y232971D03*
X134044Y246874D03*
X120568Y244571D03*
X123811Y253198D03*
X127911Y256394D03*
X126131Y359511D03*
X125125Y362403D03*
X125753Y365856D03*
X118122Y747565D03*
X119099Y755052D03*
X118467Y796785D03*
X122437Y860775D03*
X125698Y857515D03*
X122432Y857540D03*
X129666Y857514D03*
X133424Y857303D03*
X122887Y884000D03*
X127067Y891495D03*
X122887Y888000D03*
X123387Y892000D03*
X135836Y988813D03*
X131836D03*
X123836D03*
X127836D03*
X124079Y1009354D03*
X119836Y997860D03*
X131836D03*
X127836D03*
X123836D03*
X120579Y1009354D03*
Y1021954D03*
X124079D03*
X120617Y1029427D03*
Y1016827D03*
X133870Y1105091D03*
X133579Y1097469D03*
X124925Y1102091D03*
X130380Y1105091D03*
X124880D03*
X133870Y1117691D03*
X124925Y1114691D03*
Y1127291D03*
X124880Y1117691D03*
X130380D03*
X133870Y1130291D03*
X124925Y1139891D03*
X124880Y1130291D03*
X130380D03*
X133870Y1142891D03*
Y1155491D03*
X130434Y1144964D03*
X124474Y1142997D03*
X130380Y1155491D03*
X124880D03*
X124925Y1152491D03*
X133870Y1168091D03*
X124474Y1168197D03*
X130434Y1170164D03*
X124925Y1165091D03*
Y1177691D03*
X131000Y1180266D03*
X124765Y1180691D03*
X121211Y1215195D03*
X126937Y1209607D03*
X135757Y1221407D03*
X135448Y1229402D03*
Y1234921D03*
X126433Y1230407D03*
X129250Y1227650D03*
X124992Y1465913D03*
Y1456451D03*
Y1461182D03*
X133653Y1465513D03*
Y1460782D03*
X124992Y1471805D03*
Y1476536D03*
Y1481267D03*
X133653Y1476136D03*
Y1470244D03*
Y1480867D03*
Y1496221D03*
X124992Y1487159D03*
Y1491890D03*
Y1496621D03*
X133653Y1491490D03*
Y1485598D03*
Y1506845D03*
Y1500952D03*
Y1511576D03*
X124992Y1511976D03*
Y1507245D03*
Y1502514D03*
X133653Y1516307D03*
X124992Y1558813D03*
Y1563544D03*
X133653Y1563144D03*
Y1567875D03*
X124992Y1574167D03*
Y1578898D03*
X133653Y1578498D03*
Y1572606D03*
X124992Y1568275D03*
Y1589522D03*
Y1594253D03*
X133653Y1593853D03*
Y1587960D03*
X124992Y1583629D03*
X133653Y1583229D03*
X124992Y1609607D03*
Y1604876D03*
Y1598984D03*
X133653Y1609207D03*
Y1598584D03*
Y1603315D03*
X124992Y1614338D03*
X133653Y1613938D03*
Y1618669D03*
X132000Y1644980D03*
X138000Y53597D03*
X148812Y80384D03*
Y82984D03*
Y75184D03*
Y77784D03*
Y85584D03*
X137410Y103411D03*
X137804Y97667D03*
X148600Y90650D03*
X148350Y95236D03*
X135650Y109410D03*
X148602D03*
Y116496D03*
X148350Y102323D03*
X140350Y116496D03*
Y109410D03*
Y102323D03*
X135650Y116497D03*
X138050Y111255D03*
Y114655D03*
X137569Y106561D03*
X148774Y124576D03*
X149827Y130670D03*
X135650Y123583D03*
Y130670D03*
X140350D03*
Y123583D03*
X138050Y128828D03*
Y125428D03*
X149822Y137756D03*
X140350D03*
X135429Y195176D03*
X136882Y213539D03*
X134947Y202048D03*
X138547Y230117D03*
X138563Y238714D03*
X134563D03*
X138664Y241699D03*
X148061Y378600D03*
X146196Y390223D03*
X148692Y391001D03*
X148061Y382600D03*
X143186Y402291D03*
X138194Y397335D03*
X143186D03*
X146196Y395179D03*
Y404396D03*
Y409352D03*
X138194Y402291D03*
X148692Y394401D03*
Y405174D03*
X140690Y401513D03*
Y398113D03*
X148692Y408574D03*
X140786Y416465D03*
Y411509D03*
X135794Y416465D03*
Y411509D03*
X146196Y418569D03*
Y423525D03*
X140786Y425682D03*
X135794D03*
X138290Y412287D03*
X148692Y419347D03*
Y422747D03*
X138290Y415687D03*
Y426460D03*
X140786Y430638D03*
X135794D03*
X146196Y432743D03*
Y437699D03*
X140786Y439855D03*
X135794D03*
X148692Y433521D03*
X138290Y429860D03*
X148692Y436921D03*
X138290Y440633D03*
X148176Y458711D03*
X140786Y444811D03*
X135794D03*
X136604Y450750D03*
X138290Y444033D03*
X148940Y455921D03*
X145376Y458711D03*
X135794Y468609D03*
X140786D03*
X135794Y473565D03*
X140786D03*
X138290Y469387D03*
Y472787D03*
X147520Y463600D03*
X146196Y489895D03*
X135794Y487738D03*
X140786D03*
X146196Y480677D03*
Y475721D03*
X135794Y482782D03*
X140786D03*
X148692Y476499D03*
X138290Y483560D03*
X148692Y490673D03*
X138290Y486960D03*
X148692Y479899D03*
X146196Y494851D03*
X148692Y494073D03*
X135794Y512743D03*
X140786D03*
X135794Y517699D03*
X140786D03*
X146196Y519855D03*
X148692Y524033D03*
Y520633D03*
X138290Y516921D03*
Y513521D03*
X135794Y526916D03*
X140786Y531872D03*
X135794D03*
X146196Y524811D03*
Y538984D03*
Y534028D03*
X140786Y526916D03*
X140703Y536382D03*
X138290Y531094D03*
X148692Y538206D03*
Y534806D03*
X138290Y527694D03*
X142024Y552466D03*
X145670Y597580D03*
X147893Y599588D03*
X147155Y589556D03*
X147094Y592354D03*
X145609Y594668D03*
X147896Y596095D03*
X147925Y603600D03*
Y615600D03*
X147893Y607588D03*
X147925Y619600D03*
Y623600D03*
X149469Y634190D03*
X152658Y645389D03*
X136862Y857244D03*
X147836Y988813D03*
X139836D03*
X151836D03*
X143836D03*
X139836Y997860D03*
X147836D03*
X143836D03*
X135836D03*
X142026Y1012354D03*
X136571Y1009354D03*
X145516Y1024954D03*
Y1012354D03*
X136526D03*
X136571Y1021954D03*
X142026Y1024954D03*
X136526D03*
X144640Y1039439D03*
X150952Y1040115D03*
X148534Y1046476D03*
X146595Y1053457D03*
X134457Y1180654D03*
X136432Y1224472D03*
X142315Y1456451D03*
Y1461182D03*
Y1465913D03*
Y1471805D03*
Y1476536D03*
Y1481267D03*
Y1487159D03*
Y1491890D03*
Y1496621D03*
Y1507245D03*
Y1502514D03*
Y1511976D03*
Y1558813D03*
Y1563544D03*
Y1574167D03*
Y1578898D03*
Y1568275D03*
Y1589522D03*
Y1594253D03*
Y1583629D03*
Y1609607D03*
Y1604876D03*
Y1598984D03*
Y1614338D03*
X158000Y53597D03*
X151366Y92849D03*
X167191Y92874D03*
X153912Y90615D03*
X158283Y95236D03*
X158233Y99961D03*
X158460Y116496D03*
X158326Y103037D03*
X158460Y109410D03*
X166460Y116496D03*
Y109410D03*
Y102323D03*
X158460Y130670D03*
Y123583D03*
X166460D03*
Y130670D03*
X155051Y137756D03*
X166460D03*
X166240Y162368D03*
X157095Y210478D03*
Y207978D03*
Y215478D03*
Y212978D03*
Y228726D03*
Y231226D03*
X167551Y223661D03*
X157095Y226226D03*
Y223726D03*
X160424Y264180D03*
X162924D03*
X160349Y258880D03*
X163141Y293796D03*
X160641D03*
X166528Y312392D03*
X164496Y309405D03*
X151188Y390223D03*
Y395179D03*
Y404396D03*
Y409352D03*
Y423525D03*
Y418569D03*
Y432743D03*
Y437699D03*
X150703Y453682D03*
X151188Y489895D03*
Y480677D03*
Y475721D03*
Y494851D03*
Y519855D03*
Y538984D03*
Y534028D03*
Y524811D03*
X157375Y555234D03*
X157090Y562003D03*
X152386Y634946D03*
X159836Y988813D03*
X151836Y997860D03*
X159836D03*
X155836D03*
X164028Y1041468D03*
X160733Y1056594D03*
X153693Y1051037D03*
X160547Y1049283D03*
X160627Y1053561D03*
X160807Y1043955D03*
X155513Y1065148D03*
X166188Y1066551D03*
X163191Y1065313D03*
X159228Y1065613D03*
X165649Y1159350D03*
Y1151870D03*
X159637Y1461182D03*
X150976Y1465513D03*
Y1460782D03*
X159637Y1465913D03*
Y1456451D03*
X150976Y1476136D03*
Y1470244D03*
Y1480867D03*
X159637Y1471805D03*
Y1476536D03*
Y1481267D03*
Y1496621D03*
X150976Y1491490D03*
Y1485598D03*
Y1496221D03*
X159637Y1487159D03*
Y1491890D03*
X150976Y1500952D03*
Y1511576D03*
X159637Y1507245D03*
Y1502514D03*
Y1511976D03*
X150976Y1506845D03*
Y1516307D03*
X159637Y1558813D03*
Y1563544D03*
X150976Y1563144D03*
X159637Y1578898D03*
X150976Y1567875D03*
Y1578498D03*
Y1572606D03*
X159637Y1568275D03*
Y1574167D03*
X150976Y1583229D03*
Y1593853D03*
Y1587960D03*
X159637Y1583629D03*
Y1589522D03*
Y1594253D03*
X150976Y1609207D03*
Y1598584D03*
Y1603315D03*
X159637Y1609607D03*
Y1604876D03*
Y1598984D03*
X150976Y1613938D03*
Y1618669D03*
X159637Y1614338D03*
X152000Y1644980D03*
X176794Y5374D03*
X176107Y24773D03*
Y44773D03*
X167147Y77393D03*
Y74793D03*
Y85193D03*
Y82593D03*
Y79993D03*
X179743Y94017D03*
X175743D03*
X171743D03*
X175472Y101701D03*
Y98551D03*
X175871Y110445D03*
X180863Y115401D03*
Y110445D03*
X175871Y115401D03*
X178367Y111223D03*
Y114623D03*
X179022Y103783D03*
X169218Y107649D03*
Y104249D03*
X178367Y128796D03*
X180863Y129574D03*
Y124618D03*
X175871Y129574D03*
Y124618D03*
X178367Y125396D03*
X173784Y147540D03*
X177556Y141247D03*
X185023Y143740D03*
X182403Y148277D03*
X173784Y151540D03*
X175940Y162793D03*
Y165393D03*
X168840Y162368D03*
X175940Y167993D03*
Y170493D03*
X178148Y181366D03*
X180943Y181009D03*
X174937Y181426D03*
X182864Y177616D03*
X183445Y172190D03*
X177434Y191941D03*
X177301Y188727D03*
X175145Y184221D03*
X177762Y184012D03*
X171623Y211695D03*
X182884Y213132D03*
X179181Y211359D03*
Y213859D03*
X174123Y211695D03*
X167551Y208213D03*
Y213213D03*
Y210713D03*
X171623Y208695D03*
X174423D03*
X175520Y229286D03*
X179213Y224712D03*
Y222212D03*
X171258Y226141D03*
X167551Y231461D03*
Y228961D03*
Y226461D03*
X174058Y226141D03*
X167551Y215713D03*
X182884Y215632D03*
X174001Y236611D03*
X176501D03*
X175520Y231786D03*
X171501Y236611D03*
X176203Y248891D03*
X173703D03*
X171203D03*
X179128Y256535D03*
X177800Y265701D03*
X182887Y265896D03*
X174618Y267526D03*
Y270026D03*
X169318Y267526D03*
X172118D03*
Y270026D03*
X169318D03*
X179435Y281716D03*
X173955Y285690D03*
Y288190D03*
X171155Y285690D03*
X168655Y288190D03*
X171155D03*
X168655Y285690D03*
X182181Y290755D03*
X178181D03*
X170215Y311671D03*
X177369Y389154D03*
Y396240D03*
Y403327D03*
Y410413D03*
Y417500D03*
Y424587D03*
Y431673D03*
Y438760D03*
Y445847D03*
Y467539D03*
Y474626D03*
Y488799D03*
Y481713D03*
Y495886D03*
Y511673D03*
Y518760D03*
Y525847D03*
Y532933D03*
Y540020D03*
Y547106D03*
X175615Y550907D03*
X173115D03*
X175615Y553407D03*
X173115D03*
X174923Y545263D03*
Y541863D03*
X177385Y566929D03*
X171339Y572070D03*
X172686Y569928D03*
X175033Y570962D03*
X174776Y568475D03*
X177099Y569426D03*
X176650Y602197D03*
X177114Y595108D03*
X169389Y1155610D03*
X168299Y1465513D03*
Y1460782D03*
X176960Y1465914D03*
Y1456452D03*
Y1461183D03*
X168299Y1476136D03*
Y1470244D03*
Y1480867D03*
X176960Y1476537D03*
Y1471806D03*
Y1481268D03*
X168299Y1491490D03*
Y1485598D03*
Y1496221D03*
X176960Y1491891D03*
Y1487160D03*
Y1496622D03*
Y1507246D03*
Y1502515D03*
X168299Y1506845D03*
Y1500952D03*
Y1511576D03*
X176960Y1511977D03*
X168299Y1516307D03*
Y1563144D03*
X176960Y1563544D03*
Y1558813D03*
Y1568275D03*
X168299Y1578498D03*
Y1572606D03*
Y1567875D03*
Y1583229D03*
X176960Y1583629D03*
X168299Y1593853D03*
Y1587960D03*
X176960Y1594253D03*
Y1589522D03*
X168299Y1609207D03*
Y1598584D03*
Y1603315D03*
X176960Y1609607D03*
Y1598984D03*
Y1604876D03*
X168299Y1613938D03*
Y1618669D03*
X176960Y1614338D03*
X172000Y1644980D03*
X195697Y3000D03*
X188820Y80140D03*
Y84140D03*
Y76140D03*
X191568Y76587D03*
Y72615D03*
X183752Y94017D03*
X193007Y100625D03*
X186026Y97475D03*
X186273Y117557D03*
X191265D03*
X183022Y103783D03*
X194189Y103621D03*
X185957Y106186D03*
X197380Y112083D03*
X188769Y118335D03*
Y121735D03*
X186273Y131731D03*
Y122513D03*
X191265D03*
Y131731D03*
X188769Y132509D03*
Y135909D03*
X189364Y146461D03*
X186273Y136687D03*
X191265D03*
X193586Y141247D03*
X198073Y143518D03*
X197173Y152373D03*
X188266Y152367D03*
X194649Y180527D03*
X189966Y180572D03*
X201015Y183834D03*
X201125Y178560D03*
X186118Y168697D03*
X201188Y172665D03*
X198372Y192421D03*
X189966Y185165D03*
X194604Y185121D03*
X183934Y184619D03*
X187206Y191941D03*
X195260Y192490D03*
X200535Y190185D03*
X201305Y200864D03*
X185914Y206760D03*
X189215Y206767D03*
X191715D03*
X194215D03*
X201394Y212455D03*
X201328Y207037D03*
X194345Y221708D03*
X198695Y221642D03*
X190460Y228221D03*
Y231021D03*
X191845Y221708D03*
X188760Y224421D03*
X189345Y221708D03*
X191011Y236189D03*
X193511D03*
X196011D03*
X187128Y256535D03*
X190952Y248765D03*
X193452D03*
X195952D03*
X183128Y256303D03*
X187903Y266114D03*
X188158Y279208D03*
X192262Y281307D03*
X196449Y268195D03*
X193649D03*
X196449Y270695D03*
X193649D03*
X191149D03*
Y268195D03*
X185376Y281982D03*
X196752Y293645D03*
Y290845D03*
Y288345D03*
X194252Y293645D03*
Y290845D03*
Y288345D03*
X186181Y290755D03*
X191988Y389154D03*
X185169D03*
Y396240D03*
X186448Y404911D03*
X190518Y396240D03*
X194603Y422864D03*
X186589Y426299D03*
X185402Y412571D03*
X195295Y414823D03*
X194673Y429832D03*
X194278Y436447D03*
X186900Y445847D03*
X196313Y447953D03*
X185169Y467539D03*
X195480D03*
X185169Y474626D03*
X194222Y472772D03*
X194956Y487711D03*
X195069Y479104D03*
X185430Y480828D03*
X187380Y498834D03*
X195480Y495886D03*
X190829Y516841D03*
X194080Y510565D03*
X185169Y518760D03*
Y511673D03*
Y525847D03*
X185654Y552872D03*
X185776Y550123D03*
X185328Y545528D03*
X185099Y562443D03*
X186867Y560675D03*
X187408Y572334D03*
X185640Y574102D03*
X194063Y577716D03*
X191125Y602400D03*
Y598400D03*
Y594400D03*
Y606400D03*
Y614400D03*
Y610400D03*
X193723Y656942D03*
X185622Y1465513D03*
Y1460782D03*
Y1480868D03*
Y1476137D03*
Y1470244D03*
Y1485599D03*
X192000Y1644980D03*
X211262Y60922D03*
X206398Y55513D03*
X203248D03*
X199473Y68581D03*
X205848Y60513D03*
X208645Y60369D03*
X199486Y80581D03*
X214389Y86012D03*
X208463Y96472D03*
X203591Y91951D03*
X203616Y88801D03*
X214389Y94374D03*
X206533Y94351D03*
X210482Y94279D03*
X209530Y86046D03*
X205976Y85731D03*
X202195Y117261D03*
X209726Y113394D03*
Y110394D03*
X213944Y102249D03*
X212375Y110784D03*
X209726Y116594D03*
X201669Y103621D03*
X215669Y110784D03*
X211969Y133298D03*
X209726Y119594D03*
X210160Y124283D03*
X215226Y124879D03*
X214116Y134579D03*
X208567Y161306D03*
X200323Y152562D03*
X205818Y157370D03*
X209902Y172665D03*
Y180665D03*
Y176665D03*
Y168665D03*
X215244Y195176D03*
X202001Y186629D03*
X209902Y196665D03*
Y192665D03*
X210015Y186778D03*
X209934Y200864D03*
X215104Y203393D03*
X209934Y212864D03*
Y204864D03*
Y208864D03*
Y216864D03*
Y221864D03*
X214983Y218085D03*
X205575Y219379D03*
X206203Y228631D03*
X211691Y252371D03*
Y248371D03*
X200109Y265897D03*
X202609D03*
X215380Y389153D03*
X210580D03*
X203280Y389154D03*
X212980Y390995D03*
X204675Y382109D03*
X215380Y396240D03*
X208080Y403327D03*
X215380Y403326D03*
X210580D03*
X208080Y410413D03*
X210580D03*
X215380D03*
X203280Y396240D03*
Y403327D03*
Y410413D03*
X208080Y396240D03*
X210580D03*
X212980Y405168D03*
Y394395D03*
X205680Y401482D03*
Y398082D03*
X212980Y408568D03*
X208080Y417500D03*
X215380Y417499D03*
X210580D03*
X208080Y424586D03*
X210580D03*
X215380D03*
X203280Y417500D03*
Y424586D03*
X212980Y419341D03*
Y422741D03*
X205680Y415655D03*
Y412255D03*
Y426428D03*
X208080Y431673D03*
Y438760D03*
X210580D03*
X215380D03*
Y431673D03*
X210580D03*
X203280D03*
Y438760D03*
X205680Y440602D03*
Y429828D03*
X212980Y433515D03*
Y436915D03*
X203280Y445847D03*
X208080D03*
X205680Y444002D03*
X215380Y467539D03*
X210580D03*
X203280D03*
X208080Y474626D03*
X210580D03*
X215380D03*
X203280D03*
X212980Y469381D03*
Y472781D03*
X215380Y488799D03*
X203280D03*
X208080D03*
X210580D03*
X203280Y481713D03*
X210580Y481712D03*
X208080D03*
X215380D03*
X205680Y490641D03*
Y479868D03*
X212980Y483554D03*
X205680Y476468D03*
X212980Y486954D03*
X208080Y495886D03*
X203280D03*
X205680Y494041D03*
X215380Y518760D03*
X210580D03*
X208080D03*
X210580Y511673D03*
X215380D03*
X203280D03*
Y518760D03*
X205680Y524002D03*
X212980Y516915D03*
Y513515D03*
X205680Y520602D03*
X210580Y532933D03*
X208080D03*
Y540020D03*
Y525846D03*
X210580D03*
X215380D03*
Y532933D03*
X203280Y525847D03*
Y532933D03*
Y540020D03*
X205680Y534775D03*
X212980Y527688D03*
X205680Y538175D03*
X212980Y531088D03*
X203280Y547106D03*
Y554193D03*
X204674Y551683D03*
X212460Y560500D03*
X203740Y567914D03*
Y565414D03*
Y570414D03*
X204674Y558917D03*
Y561420D03*
X203740Y575414D03*
Y572914D03*
X200495Y577937D03*
X203280Y602205D03*
Y595118D03*
X208500Y595500D03*
X203500Y606929D03*
X208000Y604567D03*
X203460Y618400D03*
X203741Y612592D03*
X209158Y610072D03*
X209094Y616317D03*
X209429Y625300D03*
X208540Y621591D03*
X205941Y668934D03*
X201115Y695581D03*
X203046Y693716D03*
X213296Y1438215D03*
X213969Y1447453D03*
Y1461853D03*
Y1458453D03*
Y1450853D03*
X215697Y3000D03*
X231681Y4469D03*
X221944Y102249D03*
X231312Y97667D03*
X224961Y109172D03*
X226968Y106495D03*
X230712Y116497D03*
X217944Y102249D03*
X227961Y109172D03*
X221695Y116594D03*
X226968Y102495D03*
X220669Y110784D03*
X230712Y123584D03*
Y130670D03*
X219969Y133298D03*
X221695Y119594D03*
X225229Y125107D03*
X220248Y124663D03*
X228608Y141228D03*
X230712Y137757D03*
X226702Y146012D03*
Y142862D03*
X227743Y148717D03*
X221592Y138838D03*
X231496Y150847D03*
X220244Y195176D03*
X219863Y198883D03*
X217744Y195176D03*
X223044D03*
X230291D03*
X223792Y206838D03*
X219863Y201683D03*
X221292Y206838D03*
X217604Y203393D03*
X230372Y210509D03*
X224362Y226320D03*
X224296Y216970D03*
Y219470D03*
Y221970D03*
X221583Y216385D03*
X217783Y218085D03*
X232064Y230556D03*
X227323Y228646D03*
X226254Y236121D03*
X223288Y238589D03*
X231049Y242078D03*
X226280Y232971D03*
X220310Y249108D03*
X222930Y244571D03*
X226173Y253198D03*
X233417D03*
X228760Y316122D03*
X230842Y313888D03*
X233258Y359186D03*
X228267Y392718D03*
Y408718D03*
Y400718D03*
Y404718D03*
Y396718D03*
Y412718D03*
X221375Y455024D03*
X220349Y465622D03*
X225500Y530000D03*
X225000Y540500D03*
X223925Y543925D03*
X224500Y555000D03*
X224000Y547075D03*
X224200Y549800D03*
X223500Y568000D03*
X224104Y562800D03*
X224040Y558800D03*
X221693Y594982D03*
X222289Y590895D03*
X220333Y617930D03*
X222646Y607542D03*
X220255Y629749D03*
X217945Y1423924D03*
X217799Y1433684D03*
X217906Y1430452D03*
Y1427052D03*
X222253Y1438483D03*
X219525Y1440028D03*
X216125D03*
X227249Y1447453D03*
Y1450853D03*
Y1458453D03*
Y1461853D03*
X229260Y1469587D03*
X218171Y1474460D03*
X224780Y1478149D03*
X217985Y1483055D03*
X225765Y1471985D03*
X233313Y1476699D03*
X224176Y1492816D03*
X221899Y1488800D03*
X218021Y1494724D03*
X222843Y1498442D03*
X217614Y1489671D03*
X233180Y1486442D03*
X233166Y1491454D03*
X223235Y1506770D03*
X222908Y1502028D03*
X226957Y1510442D03*
X226135Y1502442D03*
X230758Y1505046D03*
X226971Y1514578D03*
X216342Y1515642D03*
X227552Y1530675D03*
X232622Y1531104D03*
X226971Y1522578D03*
X219981Y1530797D03*
X223322Y1518578D03*
X217519Y1537172D03*
X222119Y1539941D03*
X227882Y1540816D03*
X233753Y1539752D03*
X233042Y24773D03*
Y44773D03*
X240363Y53597D03*
X239772Y103411D03*
X240166Y97667D03*
X235562Y95111D03*
X242712Y116496D03*
Y109410D03*
Y102323D03*
X238012Y116497D03*
X235512D03*
X238012Y109410D03*
X240412Y114655D03*
Y111255D03*
X239931Y106561D03*
X238012Y123583D03*
Y130670D03*
X235512D03*
X242712D03*
Y123583D03*
X235512Y123584D03*
X233112Y132515D03*
Y121742D03*
X240412Y125428D03*
X233112Y118342D03*
X240412Y128828D03*
X235512Y137757D03*
X242712Y137756D03*
X233112Y135915D03*
X233843Y143762D03*
X232791Y195176D03*
X235291D03*
X237309Y199248D03*
X234309D03*
X237791Y195176D03*
X239244Y213539D03*
X237309Y202048D03*
X232872Y210509D03*
X234645Y206806D03*
X232145D03*
X234309Y201748D03*
X240909Y230117D03*
X236319Y227824D03*
X232690Y238689D03*
X240925Y238714D03*
X233464Y247292D03*
X236925Y238714D03*
X236406Y246874D03*
X238626Y244297D03*
X236349Y339428D03*
X234986Y336161D03*
X236264Y342494D03*
X245362Y546712D03*
Y542712D03*
X247333Y599506D03*
X247536Y602689D03*
X241967Y616063D03*
X247278Y618288D03*
X243278D03*
X243078Y636486D03*
X240249Y628328D03*
X241084Y638243D03*
X240194Y643113D03*
X246583Y665140D03*
X242102Y656321D03*
X250102D03*
X246102D03*
X241850Y678462D03*
X245000D03*
X244267Y696911D03*
X235790Y754332D03*
X241204Y814841D03*
X237591Y815266D03*
X248556Y824003D03*
X246311Y819000D03*
X247600Y848500D03*
X238400Y836900D03*
X232675Y1466801D03*
X234976Y1481676D03*
X240466Y1503857D03*
X243268Y1501903D03*
X243535Y1511473D03*
X245500Y1517033D03*
X237633Y1511909D03*
X244600Y1531700D03*
X240808Y1519942D03*
X235687Y1522578D03*
X237580Y1528604D03*
X245937Y1524237D03*
X237700Y1531600D03*
X239949Y1541327D03*
X244912Y1539389D03*
X260363Y53597D03*
X251174Y77784D03*
Y80384D03*
Y82984D03*
Y75184D03*
Y85584D03*
X253728Y92849D03*
X250962Y90650D03*
X256274Y90615D03*
X260595Y99961D03*
X260645Y95236D03*
X250712D03*
X260688Y103037D03*
X250964Y109410D03*
X250712Y102323D03*
X250964Y116496D03*
X260822D03*
Y109410D03*
X251136Y124576D03*
X260822Y130670D03*
Y123583D03*
X252189Y130670D03*
X257413Y137756D03*
X252184D03*
X259457Y210478D03*
Y207978D03*
Y215478D03*
Y212978D03*
Y228726D03*
Y231226D03*
Y226226D03*
Y223726D03*
X262786Y264180D03*
X262711Y258880D03*
X263003Y293796D03*
X257226Y312081D03*
X257993Y307994D03*
X265011Y403307D03*
X256475Y422088D03*
X255000Y427017D03*
X254692Y431029D03*
X253758Y435029D03*
X252695Y442956D03*
X254512Y438323D03*
X254678Y449873D03*
X261965Y458455D03*
X250336Y456386D03*
X254678Y445873D03*
X263301Y444232D03*
X262526Y451108D03*
X261605Y465492D03*
Y472579D03*
X259105D03*
X254305D03*
X249125Y465874D03*
X264005Y467337D03*
Y470737D03*
X256705Y474424D03*
X261605Y486752D03*
X254305D03*
X259105Y479666D03*
X261605D03*
X254305D03*
X259105Y486752D03*
X264005Y484910D03*
X256705Y488597D03*
X264005Y481510D03*
X256705Y477824D03*
X254305Y493839D03*
X259105D03*
X256705Y491997D03*
X261605Y516713D03*
X259105D03*
Y523800D03*
X261605D03*
X254305D03*
Y516713D03*
X261605Y509626D03*
X264005Y514871D03*
X256705Y518558D03*
X264005Y511471D03*
X256705Y521958D03*
X261605Y530886D03*
X259105D03*
Y537973D03*
X254305Y530886D03*
Y537973D03*
X256705Y532731D03*
Y536131D03*
X264005Y525644D03*
Y529044D03*
X254305Y566752D03*
X261605Y559665D03*
Y566752D03*
X259105D03*
X264005Y561510D03*
X256705Y571997D03*
Y568597D03*
X264005Y564910D03*
X261605Y588012D03*
X259105Y588013D03*
X254305Y573839D03*
X261605D03*
X259105D03*
X261605Y580926D03*
X259105D03*
X254305D03*
Y588013D03*
X256705Y586171D03*
X264005Y575684D03*
Y579084D03*
X256705Y582771D03*
X259105Y602186D03*
X254305D03*
Y595099D03*
X259105D03*
X261605D03*
Y602185D03*
X264005Y589857D03*
X256705Y600344D03*
X264005Y593257D03*
Y604030D03*
X256705Y596944D03*
X254305Y609272D03*
X259105D03*
X261605D03*
X259105Y616359D03*
X254305D03*
X256705Y611117D03*
Y614517D03*
X264005Y607430D03*
X252688Y636364D03*
X248984Y638125D03*
X258867Y680499D03*
X248690Y678519D03*
X248090Y691114D03*
X254634Y698241D03*
X248506Y812042D03*
X256303Y812254D03*
X251802Y824128D03*
X250700Y819900D03*
X254058Y819851D03*
X255289Y824340D03*
X252305Y831018D03*
X252100Y836800D03*
X250876Y1532782D03*
X248042Y1532900D03*
X255909Y1542043D03*
X250790Y1539759D03*
X279156Y5374D03*
X278469Y24773D03*
Y44773D03*
X269509Y77393D03*
Y74793D03*
Y85193D03*
Y82593D03*
Y79993D03*
X274105Y94017D03*
X278105D03*
X277834Y101701D03*
Y98551D03*
X269553Y92874D03*
X268822Y116496D03*
Y109410D03*
X278233Y115401D03*
Y110445D03*
X268822Y102323D03*
X271580Y107649D03*
Y104249D03*
X268822Y130670D03*
Y123583D03*
X278233Y129574D03*
Y124618D03*
X268822Y137756D03*
X276146Y147540D03*
X279918Y141247D03*
X276146Y151540D03*
X268602Y162368D03*
X271202D03*
X278302Y162793D03*
Y165393D03*
Y167993D03*
Y170493D03*
X277299Y181426D03*
X279796Y191941D03*
X279663Y188727D03*
X280124Y184012D03*
X277507Y184221D03*
X269913Y210713D03*
X273985Y208695D03*
X276785D03*
X273985Y211695D03*
X276485D03*
X269913Y208213D03*
Y213213D03*
Y228961D03*
Y226461D03*
X276420Y226141D03*
X269913Y223661D03*
X277882Y229286D03*
X273620Y226141D03*
X269913Y231461D03*
Y215713D03*
X276363Y236611D03*
X278863D03*
X277882Y231786D03*
X273863Y236611D03*
X276065Y248891D03*
X273565D03*
X278565D03*
X265286Y264180D03*
X280162Y265701D03*
X276980Y267526D03*
Y270026D03*
X271680Y267526D03*
X274480D03*
Y270026D03*
X271680D03*
X281797Y281716D03*
X276317Y288190D03*
X273517Y285690D03*
X271017Y288190D03*
X273517D03*
X271017Y285690D03*
X265503Y293796D03*
X276317Y285690D03*
X274425Y390500D03*
X277575Y395084D03*
X274425Y381500D03*
X265011Y410394D03*
X265945Y440098D03*
Y437598D03*
Y435098D03*
Y432598D03*
Y430098D03*
X278784Y435158D03*
X278529Y440489D03*
X274949Y442606D03*
X266405Y451319D03*
Y458406D03*
X278827Y444841D03*
X282230Y458572D03*
X265011Y453881D03*
X280220Y448493D03*
X274866Y446606D03*
X265011Y446595D03*
X274205Y466027D03*
X266405Y465492D03*
X266229Y462264D03*
X274347Y475262D03*
X266405Y472579D03*
X275873Y463479D03*
X276344Y467367D03*
X274347Y489435D03*
Y482666D03*
X266405Y479665D03*
Y486752D03*
Y493839D03*
X274163Y495088D03*
X266405Y523799D03*
Y516713D03*
Y509626D03*
X274205D03*
X274820Y522134D03*
X274898Y514608D03*
X266405Y530886D03*
Y537973D03*
X275463Y529136D03*
X275302Y535677D03*
X266405Y566752D03*
Y559665D03*
X274586Y565574D03*
X274205Y559665D03*
X266405Y580926D03*
Y588012D03*
Y573839D03*
X274233Y574338D03*
X266405Y602185D03*
Y595099D03*
Y609272D03*
Y616358D03*
X274332D03*
X274096Y820725D03*
X274697Y830951D03*
X275123Y847874D03*
X269700Y853100D03*
X275400Y864400D03*
X269700Y884600D03*
X278400Y890839D03*
X275400Y899400D03*
X269900Y914200D03*
X279261Y926339D03*
X278739Y936439D03*
X270100Y946500D03*
X272000Y1644980D03*
X294959Y11097D03*
X289797Y36735D03*
X290113Y23188D03*
X284666Y34068D03*
X289631Y28281D03*
X286129Y36971D03*
X291182Y84140D03*
Y80140D03*
Y76140D03*
X293930Y76587D03*
Y72615D03*
X282105Y94017D03*
X286114D03*
X295369Y100625D03*
X288388Y97475D03*
X280729Y111223D03*
X288635Y117557D03*
X283225Y115401D03*
Y110445D03*
X285384Y103783D03*
X296551Y103621D03*
X293627Y117557D03*
X280729Y114623D03*
X281384Y103783D03*
X288319Y106186D03*
X280729Y125396D03*
X291131Y121735D03*
X288635Y131731D03*
Y122513D03*
X283225Y129574D03*
Y124618D03*
X293627Y122513D03*
Y131731D03*
X280729Y128796D03*
X291131Y118335D03*
Y132509D03*
Y135909D03*
X291726Y146461D03*
X293627Y136687D03*
X288635D03*
X295948Y141247D03*
X287385Y143740D03*
X284765Y148277D03*
X290628Y152367D03*
X292328Y180572D03*
X285807Y172190D03*
X280510Y181366D03*
X283305Y181009D03*
X288480Y168697D03*
X285226Y177616D03*
X292328Y185165D03*
X286296Y184619D03*
X289568Y191941D03*
X297622Y192490D03*
X288276Y206760D03*
X291577Y206767D03*
X294077D03*
X296577D03*
X285246Y213132D03*
X281543Y211359D03*
Y213859D03*
X281575Y224712D03*
Y222212D03*
X296707Y221708D03*
X292822Y228221D03*
Y231021D03*
X294207Y221708D03*
X291122Y224421D03*
X291707Y221708D03*
X285246Y215632D03*
X293373Y236189D03*
X295873D03*
X281490Y256535D03*
X289490D03*
X293314Y248765D03*
X295814D03*
X285490Y256303D03*
X290265Y266114D03*
X285249Y265896D03*
X290520Y279208D03*
X294624Y281307D03*
X296011Y270695D03*
X293511D03*
Y268195D03*
X296011D03*
X287738Y281982D03*
X296614Y293645D03*
Y290845D03*
Y288345D03*
X284543Y290755D03*
X280543D03*
X288543D03*
X286940Y315039D03*
X297719Y339559D03*
X291396Y350223D03*
X284075Y381500D03*
X292520Y384410D03*
X292358Y393858D03*
X298000Y391496D03*
X295699Y382047D03*
X292500Y410394D03*
Y403307D03*
X296000Y403500D03*
X298000Y409000D03*
X294000Y398583D03*
X284295Y430760D03*
X284316Y433570D03*
X284132Y437072D03*
X284173Y439963D03*
X295253Y440869D03*
Y438269D03*
X292453D03*
Y440869D03*
Y435669D03*
Y430469D03*
Y433069D03*
X295253D03*
Y430469D03*
Y435669D03*
X284417Y443180D03*
X284437Y454744D03*
X284379Y452018D03*
X292316Y458406D03*
X293307Y451677D03*
X295807D03*
X293307Y454177D03*
X295807D03*
X284482Y460250D03*
X284516Y465492D03*
X282247Y470136D03*
X292316Y465492D03*
X284516Y472579D03*
X292316D03*
X295011Y460218D03*
Y463618D03*
X284516Y479665D03*
Y486752D03*
X292316Y479665D03*
Y486752D03*
Y493839D03*
X284516D03*
X292316Y523799D03*
Y516713D03*
Y509626D03*
X284516Y516713D03*
Y509626D03*
X292316Y537973D03*
Y530886D03*
X283377Y532756D03*
X283456Y525483D03*
X280976Y537973D03*
X284516Y559665D03*
Y566752D03*
X292316Y559665D03*
Y566752D03*
X284366Y579978D03*
X292316Y573839D03*
Y588012D03*
Y580925D03*
X284516Y573839D03*
X292316Y595099D03*
Y602185D03*
X284580Y608117D03*
X292316Y616358D03*
Y609272D03*
X281980Y953926D03*
X280897Y1465913D03*
X289558Y1465513D03*
X280897Y1461182D03*
X289558Y1460782D03*
X280897Y1456451D03*
X289558Y1480867D03*
X280897Y1476536D03*
X289558Y1476136D03*
Y1470244D03*
X280897Y1471805D03*
Y1481267D03*
Y1491890D03*
X289558Y1491490D03*
Y1485598D03*
X280897Y1487159D03*
Y1496621D03*
X289558Y1496221D03*
X280897Y1507245D03*
X289558Y1506845D03*
Y1500952D03*
X280897Y1502514D03*
X289558Y1511576D03*
X280897Y1511976D03*
X289558Y1516307D03*
X280897Y1563544D03*
X289558Y1563144D03*
X280897Y1558813D03*
Y1574167D03*
Y1568275D03*
X289558Y1567875D03*
X280897Y1578898D03*
X289558Y1578498D03*
Y1572606D03*
Y1593853D03*
Y1587960D03*
X280897Y1589522D03*
Y1583629D03*
X289558Y1583229D03*
X280897Y1594253D03*
Y1609607D03*
X289558Y1609207D03*
X280897Y1598984D03*
X289558Y1598584D03*
Y1603315D03*
X280897Y1604876D03*
Y1614338D03*
X289558Y1613938D03*
Y1618669D03*
X292000Y1644980D03*
X298059Y3000D03*
X309106Y37543D03*
X312256D03*
X308760Y55513D03*
X305610D03*
X301835Y68581D03*
X310817Y60393D03*
X307916Y60529D03*
X301848Y80581D03*
X310882Y96613D03*
X305953Y91951D03*
X305978Y88801D03*
X312844Y94279D03*
X308895Y94351D03*
X308338Y85731D03*
X311892Y86046D03*
X312088Y113394D03*
X304557Y117261D03*
X312088Y116594D03*
X299742Y112083D03*
X304031Y103621D03*
X312088Y119594D03*
X312522Y124283D03*
X300435Y143518D03*
X299535Y152373D03*
X310929Y161306D03*
X302685Y152562D03*
X308180Y157370D03*
X297011Y180527D03*
X312264Y172665D03*
Y180665D03*
Y176665D03*
Y168665D03*
X303377Y183834D03*
X303550Y172665D03*
X303487Y178560D03*
X299759Y190285D03*
X296966Y185121D03*
X304363Y186629D03*
X302897Y190185D03*
X312264Y196665D03*
Y192665D03*
X303667Y200864D03*
X312377Y186778D03*
X300814Y192859D03*
X312296Y212864D03*
Y200864D03*
Y204864D03*
Y208864D03*
X303756Y212455D03*
X303690Y207037D03*
X312296Y221864D03*
Y216864D03*
X301057Y221642D03*
X307937Y219379D03*
X308565Y228631D03*
X298373Y236189D03*
X298314Y248765D03*
X302471Y265897D03*
X304971D03*
X298811Y270695D03*
Y268195D03*
X299114Y290845D03*
Y288345D03*
Y293645D03*
X315079Y314890D03*
X302966Y324139D03*
X310013Y316731D03*
X312263Y324518D03*
X301943Y328867D03*
X306812Y342319D03*
X301943Y332017D03*
X308952Y356875D03*
X312316Y356747D03*
X299000Y377912D03*
X301158Y380307D03*
X309258Y389912D03*
Y393924D03*
Y385912D03*
X299000Y386500D03*
X301308Y395346D03*
X301393Y400039D03*
X309258Y409924D03*
Y405924D03*
Y401924D03*
X299088Y397912D03*
X306673Y418838D03*
X298507Y445908D03*
X302457Y445787D03*
X298220Y1465913D03*
Y1456451D03*
Y1461182D03*
X306881Y1465513D03*
Y1460782D03*
Y1470244D03*
Y1480867D03*
X298220Y1471805D03*
Y1476536D03*
Y1481267D03*
X306881Y1476136D03*
X298220Y1487159D03*
Y1491890D03*
Y1496621D03*
X306881Y1491490D03*
Y1485598D03*
Y1496221D03*
X298220Y1507245D03*
Y1502514D03*
X306881Y1506845D03*
Y1500952D03*
Y1511576D03*
X298220Y1511976D03*
X306881Y1516307D03*
X298220Y1558813D03*
Y1563544D03*
X306881Y1563144D03*
X298220Y1568275D03*
X306881Y1567875D03*
X298220Y1574167D03*
Y1578898D03*
X306881Y1578498D03*
Y1572606D03*
X298220Y1583629D03*
X306881Y1583229D03*
X298220Y1589522D03*
Y1594253D03*
X306881Y1593853D03*
Y1587960D03*
Y1598584D03*
Y1603315D03*
X298220Y1609607D03*
Y1604876D03*
Y1598984D03*
X306881Y1609207D03*
X298220Y1614338D03*
X306881Y1613938D03*
Y1618669D03*
X312000Y1644980D03*
X318059Y3000D03*
X322847Y19806D03*
X321840Y14408D03*
X322113Y26187D03*
X313624Y60922D03*
X316751Y86012D03*
X324306Y102249D03*
X316751Y94374D03*
X320306Y102249D03*
X327323Y109172D03*
X316306Y102249D03*
X314737Y110784D03*
X324057Y116594D03*
X318031Y110784D03*
X323031D03*
X314854Y130898D03*
X322331Y133298D03*
X324057Y119594D03*
X327591Y125107D03*
X322610Y124663D03*
X317588Y124879D03*
X329064Y146012D03*
X316478Y134579D03*
X329064Y142862D03*
X330105Y148717D03*
X323954Y138838D03*
X322225Y198883D03*
X322606Y195176D03*
X325406D03*
X320106D03*
X317606D03*
X323654Y206838D03*
X319966Y203393D03*
X322225Y201683D03*
X317466Y203393D03*
X326154Y206838D03*
X317345Y218085D03*
X320145D03*
X323945Y216385D03*
X326658Y216970D03*
Y219470D03*
X326724Y226320D03*
X326658Y221970D03*
X329685Y228646D03*
X325650Y238589D03*
X328616Y236121D03*
X328642Y232971D03*
X322672Y249108D03*
X325292Y244571D03*
X328535Y253198D03*
X314053Y252371D03*
Y248371D03*
X323882Y303839D03*
X327032Y303962D03*
X314855Y311740D03*
X319857Y321649D03*
X318508Y324322D03*
X315904Y336324D03*
X315944Y332584D03*
X320483Y353506D03*
X316067Y347937D03*
X321416Y348015D03*
X317333Y353470D03*
X318500Y356519D03*
X315310Y356712D03*
X321549Y445315D03*
Y448115D03*
X323489Y471484D03*
X318497Y466528D03*
X323489D03*
X318497Y471484D03*
X328899Y473640D03*
X320993Y467306D03*
Y470706D03*
X328899Y487813D03*
X323489Y480701D03*
X328899Y478596D03*
X318497Y480701D03*
Y485657D03*
X323489D03*
X320993Y481479D03*
Y484879D03*
X328899Y492769D03*
X323489Y515617D03*
X328899Y517774D03*
X318497Y510661D03*
X323489D03*
X318497Y515617D03*
X328899Y522730D03*
X320993Y514839D03*
Y511439D03*
X318497Y524835D03*
X328899Y536903D03*
Y531947D03*
X323489Y529791D03*
Y524835D03*
X318497Y529791D03*
X320993Y525613D03*
Y529013D03*
X318660Y539315D03*
X320785Y553287D03*
X327456Y550065D03*
X324291Y556775D03*
X328899Y572769D03*
X318497Y565657D03*
Y560701D03*
X328899Y567813D03*
X323489Y565657D03*
Y560701D03*
X320993Y564879D03*
Y561479D03*
X318497Y579830D03*
X323489Y574874D03*
X318497D03*
X323489Y579830D03*
X328899Y581987D03*
X323489Y589047D03*
X318497D03*
X328899Y586943D03*
X320993Y575652D03*
Y579052D03*
X318497Y594003D03*
X328899Y596160D03*
X323489Y594003D03*
Y603221D03*
X318497D03*
X328899Y601116D03*
X320993Y603999D03*
Y593225D03*
Y589825D03*
X328899Y610333D03*
X323489Y608177D03*
X318497D03*
X328899Y615289D03*
X320993Y607399D03*
X321119Y622912D03*
X315543Y1465913D03*
Y1456451D03*
Y1461182D03*
X324204Y1465513D03*
Y1460782D03*
Y1480867D03*
X315543Y1471805D03*
Y1476536D03*
Y1481267D03*
X324204Y1476136D03*
Y1470244D03*
X315543Y1487159D03*
Y1491890D03*
Y1496621D03*
X324204Y1491490D03*
Y1485598D03*
Y1496221D03*
Y1500952D03*
Y1511576D03*
X315543Y1507245D03*
Y1502514D03*
Y1511976D03*
X324204Y1506845D03*
Y1516307D03*
X315543Y1558813D03*
Y1563544D03*
X324204Y1563144D03*
X315543Y1574167D03*
Y1578898D03*
X324204Y1567875D03*
Y1578498D03*
Y1572606D03*
X315543Y1568275D03*
Y1583629D03*
Y1589522D03*
Y1594253D03*
X324204Y1583229D03*
Y1593853D03*
Y1587960D03*
X315543Y1609607D03*
Y1604876D03*
Y1598984D03*
X324204Y1609207D03*
Y1598584D03*
Y1603315D03*
X315543Y1614338D03*
X324204Y1613938D03*
Y1618669D03*
X334043Y4469D03*
X330905Y11806D03*
Y15806D03*
Y19806D03*
X335404Y24773D03*
X330905Y23806D03*
Y31806D03*
Y27806D03*
X335404Y44773D03*
X342725Y53597D03*
X333674Y97667D03*
X342134Y103411D03*
X342528Y97667D03*
X337924Y95111D03*
X329330Y106495D03*
X345074Y116496D03*
X337874Y116497D03*
X340374D03*
X345074Y109410D03*
Y102323D03*
X340374Y109410D03*
X333074Y116497D03*
X330323Y109172D03*
X342774Y111255D03*
Y114655D03*
X329330Y102495D03*
X342293Y106561D03*
X337874Y130670D03*
X345074D03*
Y123583D03*
X340374D03*
X337874Y123584D03*
X333074D03*
Y130670D03*
X340374D03*
X335474Y118342D03*
Y132515D03*
X342774Y125428D03*
X335474Y121742D03*
X342774Y128828D03*
X333074Y137757D03*
X337874D03*
X330970Y141228D03*
X345074Y137756D03*
X335474Y135915D03*
X336205Y143762D03*
X333858Y150847D03*
X335153Y195176D03*
X332653D03*
X336671Y199248D03*
X337653Y195176D03*
X340153D03*
X339671Y199248D03*
X341606Y213539D03*
X336671Y201748D03*
X334507Y206806D03*
X337007D03*
X335234Y210509D03*
X332734D03*
X339671Y202048D03*
X343271Y230117D03*
X338681Y227824D03*
X334426Y230556D03*
X335052Y238689D03*
X335826Y247292D03*
X343287Y238714D03*
X339287D03*
X333411Y242078D03*
X338768Y246874D03*
X340988Y244297D03*
X332635Y256394D03*
X347058Y399918D03*
X339072Y416888D03*
Y419488D03*
Y422088D03*
X345050Y458334D03*
Y454334D03*
X333891Y473640D03*
X331395Y474418D03*
X333891Y487813D03*
Y478596D03*
X331395Y488591D03*
Y477818D03*
X333891Y492769D03*
X331395Y491991D03*
X333891Y522730D03*
Y517774D03*
X331395Y518552D03*
Y521952D03*
X333891Y531947D03*
Y536903D03*
X331395Y536125D03*
Y532725D03*
X338358Y554861D03*
X337078Y551381D03*
X335399Y544718D03*
X333891Y572769D03*
Y567813D03*
X331395Y568591D03*
Y571991D03*
X333891Y586943D03*
Y581987D03*
X331395Y586165D03*
Y582765D03*
X333891Y596160D03*
Y601116D03*
X331395Y600338D03*
Y596938D03*
X333891Y610333D03*
Y615289D03*
X331395Y611111D03*
Y614511D03*
X337564Y1018294D03*
X333985Y1017945D03*
X341077Y1018056D03*
X339251Y1138130D03*
X336755Y1143489D03*
X340500Y1147500D03*
X335190Y1173065D03*
X341266Y1171956D03*
X337629Y1186071D03*
X330800Y1174500D03*
X343121Y1188412D03*
X342009Y1176100D03*
X339776Y1187962D03*
X335502Y1188222D03*
X336901Y1196407D03*
X339540Y1196894D03*
X341527Y1460782D03*
X332865Y1465913D03*
Y1456451D03*
Y1461182D03*
X341527Y1465513D03*
Y1476136D03*
Y1470244D03*
Y1480867D03*
X332865Y1471805D03*
Y1476536D03*
Y1481267D03*
X341527Y1491490D03*
Y1485598D03*
Y1496221D03*
X332865Y1487159D03*
Y1491890D03*
Y1496621D03*
Y1511976D03*
X341527Y1506845D03*
Y1500952D03*
Y1511576D03*
X332865Y1507245D03*
Y1502514D03*
X341527Y1516307D03*
X332865Y1558813D03*
Y1563544D03*
X341527Y1563144D03*
X332865Y1578898D03*
X341527Y1567875D03*
Y1578498D03*
Y1572606D03*
X332865Y1568275D03*
Y1574167D03*
Y1583629D03*
Y1589522D03*
Y1594253D03*
X341527Y1583229D03*
Y1593853D03*
Y1587960D03*
X332865Y1598984D03*
X341527Y1609207D03*
Y1598584D03*
Y1603315D03*
X332865Y1609607D03*
Y1604876D03*
X341527Y1613938D03*
Y1618669D03*
X332865Y1614338D03*
X332000Y1644980D03*
X353536Y82984D03*
Y80384D03*
Y77784D03*
Y75184D03*
X356090Y92849D03*
X353536Y85584D03*
X358636Y90615D03*
X353324Y90650D03*
X362957Y99961D03*
X353074Y95236D03*
Y102323D03*
X353326Y109410D03*
Y116496D03*
X353498Y124576D03*
X354551Y130670D03*
X359525Y137756D03*
X354546D03*
X359376Y290592D03*
X356423Y301288D03*
X348375Y322284D03*
X348351Y319372D03*
X348806Y315427D03*
X351132Y322202D03*
X348968Y333138D03*
X349120Y336100D03*
X348737Y375386D03*
X354486Y377173D03*
X351136Y372334D03*
X350486Y377173D03*
X358491D03*
X357173Y392183D03*
X347591Y391533D03*
X359486Y385123D03*
X349311Y385644D03*
X354486Y385123D03*
X357218Y396866D03*
X361234Y402867D03*
X357655Y405889D03*
Y408489D03*
X358248Y403300D03*
X353894Y406060D03*
X354155Y421489D03*
Y418889D03*
Y416289D03*
X350163Y412106D03*
X357655Y413689D03*
Y416289D03*
Y421489D03*
Y418889D03*
Y424089D03*
Y411089D03*
X358042Y442518D03*
Y439718D03*
Y432718D03*
X357655Y426689D03*
X358042Y435518D03*
X347450Y447486D03*
X358754Y450091D03*
X356241Y447001D03*
X359241D03*
X353320Y454214D03*
X353663Y449045D03*
X353367Y459330D03*
X358754Y462060D03*
X353670Y473571D03*
Y488618D03*
Y491118D03*
Y481071D03*
Y478571D03*
Y476071D03*
X360242Y477053D03*
X357742D03*
X353670Y493618D03*
X359278Y491870D03*
X356778D03*
X353670Y496118D03*
X358207Y836462D03*
X358096Y867459D03*
X358086Y884616D03*
X357962Y898800D03*
X358024Y912085D03*
X358085Y923327D03*
X355929Y1132042D03*
X351563Y1132410D03*
X346366Y1134729D03*
X361621D03*
X349748D03*
X357748D03*
X353748D03*
X352545Y1142666D03*
X349700Y1148000D03*
X360877Y1157404D03*
X354420Y1157544D03*
X357947Y1159455D03*
X352536Y1160168D03*
X352931Y1167768D03*
X357950D03*
X357057Y1179542D03*
X357796Y1188058D03*
X357083Y1185205D03*
X361792Y1187310D03*
X348432Y1187215D03*
X348125Y1180175D03*
X357297Y1192709D03*
X358368Y1201043D03*
X354398D03*
X350402D03*
X346387Y1199256D03*
X360523Y1192282D03*
X360659Y1209789D03*
X349276Y1217228D03*
X351940Y1219895D03*
X362332Y1230265D03*
X355215Y1223170D03*
X360273Y1228226D03*
X358062Y1226016D03*
X350188Y1491891D03*
Y1487160D03*
Y1496622D03*
Y1507246D03*
Y1502515D03*
Y1511977D03*
X358850Y1511576D03*
Y1506845D03*
Y1516307D03*
X350188Y1563544D03*
Y1558813D03*
Y1568275D03*
Y1578898D03*
Y1574167D03*
Y1583629D03*
Y1594253D03*
Y1589522D03*
Y1604876D03*
Y1609607D03*
Y1598984D03*
Y1614338D03*
X352000Y1644980D03*
X362725Y53597D03*
X371871Y85193D03*
Y82593D03*
Y79993D03*
Y77393D03*
Y74793D03*
X376467Y94017D03*
X371915Y92874D03*
X363007Y95236D03*
X363050Y103037D03*
X363184Y116496D03*
Y109410D03*
X371184Y116496D03*
Y109410D03*
Y102323D03*
X373942Y104249D03*
Y107649D03*
X363184Y130670D03*
Y123583D03*
X371184Y130670D03*
Y123583D03*
Y137756D03*
X370964Y162368D03*
X373564D03*
X372275Y208213D03*
X379147Y208695D03*
X376347D03*
Y211695D03*
X372275Y210713D03*
Y213213D03*
X361819Y207978D03*
Y212978D03*
Y215478D03*
Y210478D03*
X372275Y226461D03*
X375982Y226141D03*
X361819Y231226D03*
Y228726D03*
Y223726D03*
Y226226D03*
X372275Y228961D03*
Y231461D03*
Y223661D03*
X378782Y226141D03*
X372275Y215713D03*
X376225Y236611D03*
X375927Y248891D03*
X367648Y264180D03*
X365148D03*
X365073Y258880D03*
X374042Y270026D03*
X376842D03*
X374042Y267526D03*
X376842D03*
X365365Y293796D03*
X367865D03*
X373379Y288190D03*
X375879Y285690D03*
X373379D03*
X375879Y288190D03*
X368057Y354184D03*
X371417Y353820D03*
X365559Y354300D03*
X364933Y374232D03*
X373264Y370010D03*
X377237Y371060D03*
X373264Y379429D03*
X378875Y379088D03*
X366526Y377173D03*
X370486D03*
X361767Y392228D03*
X362486Y385123D03*
X366486D03*
X370160Y391569D03*
X376992Y395248D03*
X368587Y409016D03*
X364551Y409032D03*
X361811Y396866D03*
X368587Y401066D03*
X378927Y406739D03*
X367919Y439318D03*
X375919Y442118D03*
Y439318D03*
X367919Y442118D03*
X375919Y449118D03*
Y446318D03*
X364954Y450091D03*
X367919Y449118D03*
Y446318D03*
X376099Y458309D03*
Y454309D03*
X367564Y452740D03*
X361754Y450091D03*
X367564Y456034D03*
Y461034D03*
X376099Y462309D03*
X369282Y468088D03*
Y465288D03*
X366443Y472189D03*
X373546Y470001D03*
X376046D03*
X361754Y462060D03*
X365332Y490070D03*
Y487570D03*
X373971Y489036D03*
X371832Y485580D03*
X374332D03*
X376832D03*
X366420Y479986D03*
Y477486D03*
X363686Y478668D03*
Y476168D03*
X361887Y493758D03*
Y496258D03*
X376207Y492836D03*
Y495636D03*
X373504Y517954D03*
X376881Y518564D03*
X363015Y710365D03*
X365887Y710329D03*
X372400Y746300D03*
X372300Y750000D03*
X373500Y767300D03*
X376300D03*
X370415Y766108D03*
X377020Y782535D03*
X373101Y779608D03*
X376300Y779800D03*
X373703Y782555D03*
X365850Y773950D03*
X371436Y791188D03*
X368491Y815092D03*
X365691Y815127D03*
X371507Y815303D03*
X362042Y814772D03*
X368273Y928100D03*
X368067Y925136D03*
X375040Y932959D03*
X371424Y937185D03*
X367944Y946082D03*
X370214Y943812D03*
X368626Y931346D03*
X368964Y937738D03*
X372858Y935136D03*
X366761Y934550D03*
X370214Y959812D03*
X363893Y946863D03*
X379928Y949774D03*
X379245Y956643D03*
X378875Y961862D03*
X370214Y947812D03*
X370101Y953699D03*
X370214Y967812D03*
Y963812D03*
Y971812D03*
X378928Y967812D03*
X372501Y1123695D03*
X365748Y1134325D03*
X368657Y1146937D03*
Y1150087D03*
X366133Y1162817D03*
Y1170767D03*
X368661Y1182649D03*
X366429Y1185238D03*
X366222Y1180235D03*
X368917Y1195419D03*
X362402Y1201039D03*
X366402Y1200969D03*
X365029Y1214158D03*
X362735Y1211864D03*
X369839Y1218940D03*
X366521Y1208993D03*
X367816Y1310586D03*
Y1315542D03*
X370202Y1314764D03*
Y1311364D03*
X372000Y1644980D03*
X388059Y3000D03*
X381518Y5374D03*
X388487Y24069D03*
X380831Y24773D03*
X383612Y30618D03*
Y33768D03*
X388612Y31168D03*
X387948Y27288D03*
X380831Y44773D03*
X393544Y76140D03*
Y84140D03*
Y80140D03*
X384467Y94017D03*
X388476D03*
X380467D03*
X380196Y101701D03*
Y98551D03*
X390750Y97475D03*
X383091Y111223D03*
X390997Y117557D03*
X385587Y115401D03*
X380595D03*
X385587Y110445D03*
X380595D03*
X387746Y103783D03*
X383091Y114623D03*
X383746Y103783D03*
X390681Y106186D03*
X393493Y118335D03*
X383091Y125396D03*
Y128796D03*
X390997Y131731D03*
Y122513D03*
X385587Y129574D03*
X380595D03*
X385587Y124618D03*
X380595D03*
X393493Y132509D03*
Y121735D03*
Y135909D03*
X390997Y136687D03*
X380664Y165393D03*
Y162793D03*
Y167993D03*
Y170493D03*
X387588Y177616D03*
X382872Y181366D03*
X379661Y181426D03*
X385667Y181009D03*
X390842Y168697D03*
X388169Y172190D03*
X382158Y191941D03*
X388658Y184619D03*
X382025Y188727D03*
X391930Y191941D03*
X382486Y184012D03*
X379869Y184221D03*
X390638Y206760D03*
X393939Y206767D03*
X383905Y211359D03*
X387608Y213132D03*
X378847Y211695D03*
X383905Y213859D03*
X380244Y229286D03*
X383937Y222212D03*
Y224712D03*
X394069Y221708D03*
X393484Y224421D03*
X387608Y215632D03*
X381225Y236611D03*
X378725D03*
X380244Y231786D03*
X378427Y248891D03*
X380927D03*
X391852Y256535D03*
X383852D03*
X387852Y256303D03*
X387611Y265896D03*
X382524Y265701D03*
X392627Y266114D03*
X392882Y279208D03*
X379342Y270026D03*
Y267526D03*
X384159Y281716D03*
X390100Y281982D03*
X378679Y285690D03*
Y288190D03*
X386905Y290755D03*
X382905D03*
X390905D03*
X392387Y337599D03*
Y342555D03*
X389237Y371070D03*
X385237Y370976D03*
X391737Y377581D03*
X384173Y379028D03*
X381237Y371076D03*
X394237Y379591D03*
X391940Y383817D03*
Y388817D03*
Y386317D03*
X396373Y407104D03*
X392444Y401949D03*
X385864Y398278D03*
X383364D03*
X378927Y409539D03*
X381927D03*
Y407039D03*
X381591Y401981D03*
X384091D03*
X393893Y413611D03*
X393833Y423944D03*
X378210Y424067D03*
X380710D03*
X385710D03*
X383210D03*
X378445Y413611D03*
X380945D03*
X385945D03*
X383445D03*
X385584Y438293D03*
Y441093D03*
Y450041D03*
Y452841D03*
Y455641D03*
Y443893D03*
X393837Y466409D03*
X393646Y474382D03*
X385634Y472020D03*
X393662Y470382D03*
X385694Y477318D03*
X385293Y466409D03*
X393823Y487382D03*
X393652Y482382D03*
X393746Y478382D03*
X387141Y484882D03*
X385131Y487382D03*
X388593Y664232D03*
X386350Y693559D03*
X391478Y690675D03*
X391470Y732865D03*
X380963Y731000D03*
X381875Y740341D03*
X379800Y778000D03*
Y769200D03*
X380331Y782627D03*
X387692Y790056D03*
X393547D03*
X380607Y786932D03*
X392415Y792725D03*
X389015D03*
X387958Y813700D03*
X381631Y814147D03*
X384666Y814103D03*
X383391Y804000D03*
X386589Y864408D03*
X383462Y860535D03*
X386614Y868286D03*
X392584Y875845D03*
X382675Y870151D03*
X391614Y938651D03*
Y930676D03*
X384856Y947987D03*
X385512Y955356D03*
X390150Y955312D03*
Y959905D03*
X385467Y959950D03*
X378119Y953696D03*
X392910Y948536D03*
X393998Y971780D03*
X381377Y1003008D03*
X381045Y1009444D03*
X378790Y1001083D03*
X380280Y1006071D03*
X383710Y1007283D03*
X382465Y1012430D03*
X378410Y1131573D03*
X380261Y1129692D03*
X387587Y1296675D03*
X387644Y1302089D03*
X385091Y1297453D03*
Y1300853D03*
X391284Y1307238D03*
X386415Y1321645D03*
X391691Y1326715D03*
X389458Y1365466D03*
X392234Y1369579D03*
Y1364501D03*
X389188Y1369033D03*
X391757Y1383480D03*
X388600Y1395500D03*
X391852Y1389931D03*
X389985Y1405762D03*
X393951Y1447455D03*
X394000Y1508100D03*
X381900Y1544800D03*
X389700Y1536900D03*
X391740Y1545629D03*
Y1540529D03*
X382017Y1555700D03*
Y1547700D03*
Y1551700D03*
Y1559700D03*
X395296Y1561024D03*
X391740Y1550729D03*
Y1555829D03*
X392000Y1644980D03*
X408059Y3000D03*
X410789Y22627D03*
X408680Y37530D03*
X396680Y37543D03*
X400714Y45448D03*
X404686D03*
X397731Y100625D03*
X408493Y117577D03*
X395989Y117557D03*
X398913Y103621D03*
X402104Y112083D03*
X406393Y103621D03*
X395989Y131731D03*
Y122513D03*
Y136687D03*
X399373Y180527D03*
X394690Y180572D03*
X405912Y172665D03*
X405739Y183834D03*
X405849Y178560D03*
X403096Y192421D03*
X394690Y185165D03*
X399328Y185121D03*
X406725Y186629D03*
X399984Y192490D03*
X405259Y190185D03*
X406029Y200864D03*
X395942Y192300D03*
X398939Y206767D03*
X396439D03*
X406118Y212455D03*
X406052Y207037D03*
X395184Y228221D03*
X399069Y221708D03*
X396569D03*
X403419Y221642D03*
X395184Y231021D03*
X410299Y219379D03*
X410927Y228631D03*
X400735Y236189D03*
X398235D03*
X395735D03*
X400676Y248765D03*
X398176D03*
X395676D03*
X396986Y281307D03*
X407333Y265897D03*
X404833D03*
X401173Y268195D03*
Y270695D03*
X398373Y268195D03*
X395873D03*
Y270695D03*
X398373D03*
X398976Y293645D03*
X401476D03*
Y288345D03*
Y290845D03*
X398976Y288345D03*
Y290845D03*
X409484Y314921D03*
X405843Y315158D03*
X403343D03*
X398951Y333711D03*
X397374Y344439D03*
X394883Y341777D03*
Y338377D03*
X410086Y336795D03*
X409655Y331589D03*
X410688Y344736D03*
X400993Y331589D03*
Y335589D03*
X407493Y354142D03*
X400728Y353152D03*
X411007Y356743D03*
X394237Y370899D03*
X406421Y387151D03*
Y382151D03*
Y384651D03*
X398453Y387702D03*
X401253D03*
X394653Y389402D03*
X396373Y409904D03*
X409268Y408240D03*
X406843Y399161D03*
Y401661D03*
Y396661D03*
X394944Y398949D03*
X399518Y402642D03*
X402018D03*
X396633Y423944D03*
X409386Y420393D03*
X396693Y413611D03*
X399193D03*
X401693D03*
X401633Y423944D03*
X399133D03*
X395577Y438293D03*
Y441093D03*
Y455641D03*
Y450041D03*
Y452841D03*
Y443893D03*
X397315Y471560D03*
X405801Y475560D03*
X405301Y467560D03*
X397315Y479560D03*
Y475560D03*
X405603Y668060D03*
X408103D03*
X403103D03*
X400603D03*
Y678060D03*
X405603D03*
X408103D03*
X403103D03*
X409284Y741316D03*
X406200Y741300D03*
X400900Y755400D03*
X400914Y762675D03*
X408300Y755487D03*
X400900Y770100D03*
X407965Y770196D03*
X408400Y795200D03*
Y792200D03*
X406600Y789000D03*
X397223Y796792D03*
X400023D03*
X397900Y789000D03*
X407000Y784700D03*
X402376Y842677D03*
X399876D03*
X402376Y850677D03*
X399876D03*
X404468Y864407D03*
X396306Y864409D03*
X406967Y878764D03*
X406415Y874840D03*
X406770Y869767D03*
X405466Y881299D03*
X397431Y870654D03*
X401108Y878487D03*
X407193Y883566D03*
X401121Y929686D03*
X409121D03*
X401121Y936686D03*
X409121Y939186D03*
X401121D03*
X409121Y936686D03*
X401121Y932186D03*
X409121D03*
X396182Y955858D03*
X402682Y948536D03*
X402815Y951750D03*
X405179Y959051D03*
X404971Y956256D03*
X402354Y956465D03*
X401968Y959111D03*
X399173Y959468D03*
X397252Y962861D03*
X404176Y977684D03*
Y975084D03*
Y969984D03*
Y972484D03*
X396671Y968287D03*
X406954Y982970D03*
X409554D03*
X404354D03*
X407547Y1058097D03*
X410047D03*
X405047D03*
X407547Y1060697D03*
X410047D03*
X405047D03*
X399285Y1081599D03*
X408989Y1082501D03*
X409015Y1087705D03*
Y1085205D03*
X408847Y1090956D03*
X398915Y1097278D03*
X396415D03*
X408847Y1093956D03*
X406895Y1107997D03*
X402695D03*
X409231Y1123101D03*
X402695Y1110897D03*
X407780Y1113648D03*
X409231Y1118801D03*
X406995Y1110597D03*
X404895Y1112397D03*
X404795Y1109397D03*
X402695Y1113797D03*
X406105Y1139435D03*
X410131Y1129301D03*
X407631D03*
X409231Y1125801D03*
X406105Y1131935D03*
Y1134435D03*
Y1136935D03*
Y1141935D03*
Y1146935D03*
Y1144435D03*
X403263Y1152684D03*
X408961Y1162384D03*
Y1164884D03*
Y1167384D03*
Y1169884D03*
Y1172384D03*
X403263Y1160834D03*
X408961Y1174884D03*
X406319Y1186709D03*
Y1184209D03*
Y1181709D03*
Y1179209D03*
Y1204405D03*
X404004Y1198321D03*
Y1200821D03*
Y1192621D03*
Y1190121D03*
X406319Y1206905D03*
Y1211905D03*
Y1209405D03*
X397063Y1221428D03*
X401063D03*
X405063D03*
X409063D03*
X397063Y1233428D03*
Y1229428D03*
Y1225428D03*
X401063Y1237428D03*
Y1233428D03*
Y1229428D03*
Y1225428D03*
X405063Y1237428D03*
Y1233428D03*
Y1229428D03*
Y1225428D03*
X409063Y1237428D03*
Y1233428D03*
Y1229428D03*
Y1225428D03*
X401063Y1241428D03*
X405063Y1245428D03*
Y1241428D03*
X409063Y1245428D03*
Y1241428D03*
X404324Y1271889D03*
X397695Y1287071D03*
X404324Y1275889D03*
X399716Y1295198D03*
X407767Y1292198D03*
X403678Y1295426D03*
X398584Y1313443D03*
X401011Y1307258D03*
X402967Y1319815D03*
X409220Y1315516D03*
X404583Y1316131D03*
X404921Y1321819D03*
X408787Y1321795D03*
X408937Y1351568D03*
X395959Y1352153D03*
X403981Y1351568D03*
X399959Y1352153D03*
X408159Y1349072D03*
X404759D03*
X403029Y1379716D03*
X403111Y1384920D03*
X408212Y1379695D03*
X394657Y1377875D03*
X403111Y1390103D03*
X408212Y1390083D03*
X395112Y1395690D03*
X398340Y1399779D03*
X395770Y1389817D03*
X410152Y1410928D03*
X398112Y1403741D03*
X410172Y1402446D03*
X402489Y1417275D03*
X405889D03*
X401711Y1419771D03*
X406667D03*
X401990Y1446807D03*
X399731Y1442755D03*
X407970Y1449751D03*
X404500Y1452500D03*
X395888Y1450022D03*
X395199Y1482223D03*
X407469Y1495035D03*
X407854Y1492118D03*
X395380Y1485778D03*
X406377Y1499142D03*
X397245Y1511640D03*
X404053Y1513673D03*
X397266Y1514647D03*
X398747Y1500959D03*
X395370Y1501022D03*
X397220Y1521207D03*
X397266Y1518047D03*
X408964Y1531149D03*
X400911Y1537902D03*
X407048D03*
X400911Y1544424D03*
X394391Y1537786D03*
Y1535286D03*
X407048Y1549936D03*
X400911D03*
X399373Y1555855D03*
X405496Y1561024D03*
X400396D03*
X410596D03*
X409461Y1569560D03*
X405461D03*
X397461D03*
X401461D03*
X420050Y33425D03*
X416900Y33400D03*
X422473Y22627D03*
X422450Y30483D03*
X422378Y26534D03*
X414145Y27486D03*
X413904Y32569D03*
X426147Y147540D03*
Y151540D03*
X414626Y180665D03*
Y172665D03*
Y176665D03*
Y168665D03*
Y196665D03*
Y192665D03*
X414739Y186778D03*
X414658Y212864D03*
Y200864D03*
Y204864D03*
Y208864D03*
Y216864D03*
Y221864D03*
X422873Y309966D03*
X419955Y306966D03*
X414999D03*
X423651Y307470D03*
X419177Y304470D03*
X415777D03*
X411984Y314921D03*
X422988Y323627D03*
X415129Y325181D03*
X421231Y338523D03*
Y331255D03*
X412671Y333418D03*
X412812Y330617D03*
X421231Y345776D03*
X413432Y346797D03*
X426830Y359026D03*
X426138Y355079D03*
X416574Y357528D03*
X421413Y359053D03*
X416318Y367903D03*
X424479Y367859D03*
X412318Y367903D03*
X420422Y367859D03*
X418997Y382210D03*
Y384710D03*
Y387210D03*
X418876Y401661D03*
Y396661D03*
X411768Y408240D03*
X414268D03*
X418876Y399161D03*
X411847Y424240D03*
X414386Y420393D03*
X411886D03*
X422215Y424939D03*
X411847Y426740D03*
X422215Y427439D03*
X414924Y435321D03*
Y438121D03*
X412124Y435321D03*
Y438121D03*
X414924Y440921D03*
X412124D03*
X415453Y455039D03*
X414924Y443721D03*
X412124D03*
X426647Y452987D03*
X421267Y452799D03*
X414910Y448931D03*
X418754Y468607D03*
X411754Y474513D03*
X415433Y459170D03*
X425673Y461607D03*
X424876Y471334D03*
X418801Y474513D03*
X424731Y508152D03*
X414275Y492469D03*
X424731Y492704D03*
X414275Y497469D03*
Y499969D03*
X427693Y498943D03*
X424731Y497704D03*
Y495204D03*
Y500204D03*
X414275Y494969D03*
X424731Y513452D03*
Y515952D03*
X414275Y508217D03*
Y510717D03*
Y515717D03*
Y513217D03*
X424731Y510952D03*
X419040Y533690D03*
Y528390D03*
Y530990D03*
Y536290D03*
Y538890D03*
X419340Y549990D03*
X419140Y547390D03*
Y544790D03*
X419340Y552590D03*
Y555190D03*
X423266Y631438D03*
X420266D03*
X417666D03*
X420266Y637038D03*
Y634238D03*
X417666Y637038D03*
Y634238D03*
X423266Y637038D03*
Y634238D03*
X423963Y625778D03*
X418226Y653288D03*
X423266Y642638D03*
X420266D03*
X417666D03*
X423266Y639838D03*
X420266D03*
X418226Y646480D03*
Y648980D03*
X417666Y639838D03*
X418226Y655788D03*
X410603Y668060D03*
Y678060D03*
X426607Y712360D03*
Y709760D03*
X424993Y728291D03*
X415700Y755400D03*
X415696Y762466D03*
X415700Y770200D03*
X423700Y795500D03*
X426300Y797400D03*
X421200Y786400D03*
X422430Y834800D03*
X411267Y829193D03*
Y831693D03*
X416267D03*
X413767D03*
Y829193D03*
X416267D03*
X424649Y842644D03*
X422149D03*
Y850644D03*
X424649D03*
X422149Y858644D03*
X424649D03*
X425759Y869921D03*
Y872721D03*
Y875521D03*
Y867121D03*
X422379Y867229D03*
X425759Y878321D03*
X411214Y892109D03*
X425062Y883981D03*
X417121Y929686D03*
X425121D03*
Y936686D03*
Y939186D03*
X417121Y936686D03*
Y939186D03*
Y932186D03*
X425121D03*
X411960Y962261D03*
X414560D03*
X417160D03*
X411276Y978109D03*
X416476D03*
X413876D03*
X417677Y1052215D03*
X415047Y1058097D03*
X412547D03*
X415047Y1060697D03*
X412547D03*
X411989Y1082501D03*
X412015Y1085205D03*
X414989Y1082501D03*
X415015Y1085205D03*
Y1088205D03*
X412015D03*
X412297Y1091227D03*
X425175Y1098767D03*
X417171Y1098887D03*
X419987Y1098518D03*
X425060Y1101917D03*
X420782Y1105552D03*
X423340Y1104335D03*
X424995Y1106897D03*
X416988Y1104792D03*
X418495Y1106867D03*
X419731Y1123101D03*
X417231D03*
X414580Y1113648D03*
X412080D03*
X422631Y1125801D03*
X425131Y1129301D03*
X422631D03*
X420131D03*
X417631D03*
X415131D03*
X412631D03*
X420131Y1125801D03*
X417631D03*
X425131D03*
X422495Y1152713D03*
Y1155213D03*
X412095Y1152713D03*
Y1155213D03*
X411461Y1162384D03*
Y1164884D03*
Y1167384D03*
Y1169884D03*
Y1172384D03*
X420619Y1179421D03*
Y1181921D03*
Y1184421D03*
Y1186921D03*
X411461Y1174884D03*
X422934Y1200821D03*
Y1198321D03*
X420619Y1204617D03*
X417469Y1200821D03*
Y1198321D03*
X422934Y1192621D03*
Y1190121D03*
X417469Y1192621D03*
Y1190121D03*
X420619Y1207117D03*
Y1209617D03*
Y1212117D03*
X413063Y1221428D03*
X417063D03*
X421063D03*
X425063D03*
X413063Y1237428D03*
Y1233428D03*
Y1229428D03*
Y1225428D03*
X417063Y1237428D03*
Y1233428D03*
Y1229428D03*
Y1225428D03*
X421063Y1237428D03*
Y1233428D03*
Y1229428D03*
Y1225428D03*
X425063Y1237428D03*
Y1233428D03*
Y1229428D03*
Y1225428D03*
X413063Y1245428D03*
Y1241428D03*
X417063Y1245428D03*
Y1241428D03*
X421063Y1245428D03*
Y1241428D03*
X425063Y1245428D03*
Y1241428D03*
X425702Y1257160D03*
X422702Y1260160D03*
Y1257160D03*
X425702Y1260160D03*
X419702Y1257160D03*
Y1260160D03*
X411174Y1282776D03*
X418537Y1300197D03*
X423741Y1300115D03*
X413354Y1300197D03*
X425582Y1291743D03*
X413526Y1288938D03*
X419977Y1288843D03*
X413640Y1292856D03*
X423762Y1305298D03*
X413374D03*
X418558Y1310523D03*
X413395Y1310481D03*
X423721Y1310523D03*
X419545Y1317722D03*
X413127Y1318011D03*
X414280Y1362561D03*
X425283Y1364023D03*
X417305Y1359169D03*
X425855Y1360495D03*
X425912Y1357141D03*
X413437Y1379736D03*
Y1384899D03*
X425283Y1373958D03*
X416029Y1371572D03*
X420636Y1383912D03*
X418610Y1371590D03*
X413395Y1390062D03*
X423400Y1394500D03*
X423200Y1397500D03*
X418430Y1394237D03*
X422729Y1400490D03*
X420925Y1390330D03*
X419045Y1398874D03*
X421300Y1415400D03*
X419100Y1402200D03*
X421200Y1417900D03*
X411000Y1463500D03*
Y1460500D03*
Y1457500D03*
Y1454500D03*
Y1451000D03*
X411147Y1474993D03*
X419818Y1474945D03*
X413934Y1477101D03*
X417334D03*
X415241Y1492990D03*
X415202Y1496118D03*
X415095Y1502750D03*
X415202Y1499518D03*
X411353Y1519440D03*
X419467Y1519706D03*
X420279Y1525978D03*
X410626Y1525991D03*
X417153Y1516886D03*
X413753D03*
X413012Y1537902D03*
Y1544098D03*
X426196Y1534087D03*
X419619Y1539978D03*
X421454Y1544625D03*
X422539Y1534361D03*
X426701Y1541947D03*
X413012Y1549936D03*
X421616Y1549885D03*
X418151Y1552470D03*
X413461Y1569560D03*
X417461Y1569584D03*
X412000Y1644980D03*
X428059Y3000D03*
X441727Y146461D03*
X429919Y141247D03*
X437386Y143740D03*
X434766Y148277D03*
X440629Y152367D03*
X435703Y306966D03*
X430747D03*
X427829Y309966D03*
X431525Y304470D03*
X434925D03*
X427051Y307470D03*
X441296Y325061D03*
X436666Y322583D03*
X427713Y321965D03*
X430361Y323187D03*
X428459Y331255D03*
X435793D03*
X443424Y332988D03*
X428500Y345776D03*
X435793Y345738D03*
X430439Y358115D03*
X440538Y355372D03*
X428420Y353578D03*
X435886Y353867D03*
X435702Y367813D03*
X430746D03*
X431524Y370309D03*
X434924D03*
X428637Y408104D03*
X431437D03*
X434237D03*
X428354Y420375D03*
X431154D03*
X433954D03*
X433724Y433975D03*
X432310Y436164D03*
X438098Y442114D03*
X437835Y435101D03*
X432270Y431112D03*
X432440Y440101D03*
X432075Y452718D03*
X438086Y452601D03*
X438078Y447121D03*
X427782Y464026D03*
X433673Y461607D03*
X429673D03*
X442704Y506427D03*
X427693Y506520D03*
X435789Y501525D03*
X427568Y502003D03*
X435831Y498923D03*
X438644Y500461D03*
X438396Y511493D03*
X438353Y508685D03*
X427693Y509020D03*
X432700Y516277D03*
X435834Y509580D03*
X428740Y533690D03*
X442704Y533790D03*
X428740Y528390D03*
Y530990D03*
X442704Y528490D03*
Y531090D03*
X428740Y536290D03*
X431804Y536682D03*
X428740Y538890D03*
X431804Y539182D03*
X442704Y536390D03*
X439804Y536682D03*
X442704Y538990D03*
X439804Y539182D03*
X428740Y549990D03*
X442804Y546990D03*
Y544390D03*
X428740Y546990D03*
Y544390D03*
Y555190D03*
Y552590D03*
X431384D03*
Y555190D03*
Y544390D03*
Y546990D03*
Y549990D03*
X436369Y622883D03*
X441832Y626193D03*
X441612Y631011D03*
X443144Y628667D03*
X441162Y638313D03*
X439290Y712399D03*
X436790D03*
X439290Y709799D03*
X436790D03*
X434290Y712399D03*
Y709799D03*
X429290D03*
X431790Y712399D03*
X429290D03*
X431790Y709799D03*
X429253Y759847D03*
X429210Y784833D03*
X432303Y785067D03*
X434100Y797400D03*
X430600D03*
X428759Y869921D03*
Y867121D03*
Y872721D03*
Y875521D03*
Y878321D03*
X432332Y892049D03*
Y897649D03*
Y894849D03*
Y900449D03*
X443091Y1026266D03*
X432678Y1016186D03*
X429878D03*
X427078D03*
X427052Y1019384D03*
X429852D03*
X432652D03*
X433206Y1055498D03*
X430706D03*
Y1057998D03*
X433206D03*
Y1060498D03*
Y1062998D03*
X430706D03*
Y1060498D03*
X433378Y1091816D03*
Y1089316D03*
X430878Y1084316D03*
Y1086816D03*
X433378D03*
Y1084316D03*
X436244Y1090288D03*
X433378Y1081816D03*
X430878D03*
X429677Y1106955D03*
X439023Y1107997D03*
X436244Y1093088D03*
X434823Y1107997D03*
X441359Y1123101D03*
X431476Y1115896D03*
X427810Y1110092D03*
X439908Y1113648D03*
X441359Y1116101D03*
Y1118801D03*
X439123Y1110597D03*
X434823Y1113797D03*
Y1110897D03*
X437023Y1112397D03*
X436923Y1109397D03*
X431476Y1118396D03*
X438233Y1139435D03*
X441359Y1125801D03*
X439759Y1129301D03*
X442259D03*
X429331Y1136935D03*
Y1134435D03*
Y1139435D03*
Y1131935D03*
X435733D03*
Y1134435D03*
Y1136935D03*
Y1139435D03*
X438233Y1131935D03*
Y1134435D03*
Y1136935D03*
X429348Y1129092D03*
X432838Y1128821D03*
X429331Y1141935D03*
X435733D03*
Y1146935D03*
Y1144435D03*
X438233Y1141935D03*
Y1146935D03*
Y1144435D03*
X437231Y1154902D03*
Y1152402D03*
X429331Y1146935D03*
Y1144435D03*
X436789Y1167384D03*
Y1164884D03*
Y1162384D03*
Y1172384D03*
Y1169884D03*
X439289Y1167384D03*
Y1164884D03*
Y1162384D03*
X427231D03*
X429731D03*
Y1164884D03*
Y1167384D03*
Y1169884D03*
Y1172384D03*
X427231D03*
Y1169884D03*
Y1167384D03*
Y1164884D03*
X439289Y1172384D03*
Y1169884D03*
X437132Y1158266D03*
X433249Y1186709D03*
Y1184209D03*
Y1181709D03*
Y1179209D03*
X429731Y1174884D03*
X427231D03*
X436789D03*
X439289D03*
X433249Y1204405D03*
X430934Y1200821D03*
Y1198321D03*
Y1190121D03*
Y1192621D03*
X433249Y1209405D03*
Y1211905D03*
Y1206905D03*
X429063Y1221428D03*
X433063D03*
X429063Y1237428D03*
Y1233428D03*
Y1229428D03*
Y1225428D03*
X433063Y1237428D03*
Y1233428D03*
Y1229428D03*
Y1225428D03*
X429063Y1245428D03*
Y1241428D03*
X433063Y1245428D03*
Y1241428D03*
X440702Y1260160D03*
Y1257160D03*
X437702Y1260160D03*
Y1257160D03*
X428702D03*
X431702Y1260160D03*
Y1257160D03*
X434702Y1260160D03*
Y1257160D03*
X428702Y1260160D03*
X437991Y1286544D03*
X434424Y1286274D03*
X430527Y1289198D03*
X440906D03*
X440896Y1311366D03*
X431867Y1315696D03*
X431885Y1313115D03*
X432485Y1325784D03*
X439434Y1322369D03*
X429530Y1325051D03*
X436002Y1382252D03*
X437675Y1550158D03*
X430657Y1563562D03*
X429784Y1548222D03*
X432000Y1644980D03*
X448059Y3000D03*
X445949Y141247D03*
X450436Y143518D03*
X449536Y152373D03*
X452686Y152562D03*
X458181Y157370D03*
X458454Y328963D03*
Y324007D03*
Y339755D03*
Y344711D03*
X443508Y337713D03*
X446566Y337917D03*
X443480Y344014D03*
X453463Y370694D03*
X448092Y375770D03*
X450852Y372054D03*
X455885Y367702D03*
X448391Y382641D03*
X448323Y379643D03*
X446179Y447101D03*
X453544Y461961D03*
X451144Y472809D03*
Y468809D03*
X459414Y468689D03*
X459757Y463520D03*
X459461Y473805D03*
X443094Y491251D03*
X459929Y491669D03*
X450942Y506449D03*
X448442D03*
X445942D03*
X460537Y501905D03*
X459952Y496842D03*
X459645Y509486D03*
X446025Y511512D03*
X448525D03*
X446025Y519699D03*
X448525D03*
X452404Y533690D03*
Y528390D03*
Y530990D03*
X455104Y536582D03*
X452404Y536290D03*
X455104Y539082D03*
X452404Y538890D03*
Y549790D03*
X443004Y549890D03*
X452404Y546990D03*
Y544390D03*
X443004Y555090D03*
X452404Y552390D03*
Y554990D03*
X443004Y552490D03*
X455009Y554912D03*
Y552312D03*
Y544312D03*
Y546912D03*
Y549712D03*
X447279Y633881D03*
Y637031D03*
X447921Y630789D03*
X453552Y631779D03*
X448726Y653288D03*
Y646480D03*
Y648980D03*
X446987Y643360D03*
X456469Y638302D03*
X448726Y655788D03*
X447836Y711199D03*
X460498Y870334D03*
X454815Y974622D03*
X458120Y974701D03*
X451460Y974695D03*
X448999Y994483D03*
X456210Y1004680D03*
X452319Y1000828D03*
X449731Y1000855D03*
X450591Y1004766D03*
X453270Y1003763D03*
X459360Y1012325D03*
X453710Y1018825D03*
X443091Y1022766D03*
X443591Y1019766D03*
X459885Y1018860D03*
X451140Y1021793D03*
X447091Y1019766D03*
X450875Y1028416D03*
X443091Y1030266D03*
X450063Y1043140D03*
X443091Y1034266D03*
X452091Y1039880D03*
X459700Y1032266D03*
X449767Y1047047D03*
X450244Y1090268D03*
X457303Y1098767D03*
X452115Y1098518D03*
X446863Y1098428D03*
X450244Y1093068D03*
X455468Y1104335D03*
X457188Y1101917D03*
X452910Y1105552D03*
X457123Y1106897D03*
X449116Y1104792D03*
X450623Y1106867D03*
X449359Y1123101D03*
X451859D03*
X444208Y1113648D03*
X446708D03*
X457259Y1129301D03*
X449759Y1125801D03*
X452259D03*
X444759Y1129301D03*
X447259D03*
X449759D03*
X452259D03*
X454759Y1125801D03*
X457259D03*
X454759Y1129301D03*
X443223Y1155213D03*
Y1152713D03*
X452623D03*
Y1155213D03*
X457559Y1169884D03*
Y1167384D03*
Y1164884D03*
Y1162384D03*
X455059D03*
Y1164884D03*
Y1167384D03*
Y1169884D03*
Y1172384D03*
X457559D03*
X455059Y1174884D03*
X457559D03*
X447549Y1179421D03*
Y1181921D03*
Y1184421D03*
Y1186921D03*
Y1204617D03*
X449864Y1198321D03*
Y1200821D03*
Y1190121D03*
Y1192621D03*
X447549Y1209617D03*
Y1207117D03*
Y1212117D03*
X454120Y1269498D03*
X449702Y1260160D03*
Y1257160D03*
X443702Y1260160D03*
X446702D03*
Y1257160D03*
X443702D03*
X456213Y1286776D03*
X451889Y1301067D03*
X451304Y1293045D03*
X456832Y1299121D03*
X451304Y1297045D03*
X454385Y1301845D03*
X451889Y1306023D03*
X454385Y1305245D03*
X444288Y1314391D03*
X454125Y1471805D03*
Y1487159D03*
Y1502514D03*
Y1558813D03*
Y1574167D03*
Y1589522D03*
Y1604876D03*
X452000Y1644980D03*
X468059Y3000D03*
X474307Y102249D03*
X464738Y110784D03*
X462089Y113394D03*
X470307Y102249D03*
X466307D03*
X462089Y116594D03*
X474058D03*
X473032Y110784D03*
X468032D03*
X472332Y133298D03*
X464332D03*
X462089Y119594D03*
X474058D03*
X477592Y125107D03*
X462523Y124283D03*
X467589Y124879D03*
X472611Y124663D03*
X466479Y134579D03*
X473955Y138838D03*
X460930Y161306D03*
X470107Y195176D03*
X467607D03*
X472607D03*
X472226Y198883D03*
X475407Y195176D03*
X473655Y206838D03*
X467467Y203393D03*
X469967D03*
X472226Y201683D03*
X467346Y218085D03*
X470146D03*
X473946Y216385D03*
X475293Y244571D03*
X472673Y249108D03*
X464054Y252371D03*
Y248371D03*
X460950Y328185D03*
Y324785D03*
X461454Y336837D03*
Y331881D03*
X463950Y332659D03*
Y336059D03*
X460950Y343933D03*
Y340533D03*
X461454Y347629D03*
Y352585D03*
X472810Y347995D03*
X472913Y360089D03*
X472608Y352495D03*
X467335Y359944D03*
X463950Y351807D03*
Y348407D03*
X466375Y366365D03*
X472913Y369089D03*
Y373589D03*
X469530Y366754D03*
X470389Y389553D03*
X472913Y387089D03*
Y391589D03*
Y382589D03*
Y378089D03*
X470796Y394592D03*
X473658Y467215D03*
X471048Y464566D03*
X464848D03*
X467848D03*
X465126Y460435D03*
X462126D03*
X473658Y470509D03*
Y475509D03*
X468558Y491669D03*
X467848Y476535D03*
X464848D03*
X468558Y503669D03*
Y507669D03*
Y495669D03*
Y499669D03*
Y512669D03*
Y516609D03*
X464199Y510184D03*
X463104Y536582D03*
X468850Y537507D03*
X463104Y539082D03*
X468850Y545586D03*
X461849Y668016D03*
X459349D03*
X466849D03*
X469349D03*
X464349D03*
X469349Y678016D03*
X466849D03*
X459349D03*
X461849D03*
X464349D03*
X469300Y799500D03*
X462242Y809792D03*
X459245Y807152D03*
X473654Y821234D03*
X475032Y843252D03*
X472399Y839566D03*
X463404Y846870D03*
X474678Y857919D03*
X463134Y859203D03*
X465492Y861970D03*
X460455Y867050D03*
X475046Y885952D03*
X471726Y883705D03*
X467494Y924532D03*
X474540Y927341D03*
X471110Y921577D03*
X471876Y937236D03*
X471068Y930235D03*
X473992Y952546D03*
X475018Y992568D03*
X467345Y996480D03*
X469495Y1011303D03*
X459360Y1004680D03*
X464795Y1000647D03*
X469495Y1023303D03*
Y1017303D03*
X462185Y1016825D03*
X459860Y1015825D03*
X462427Y1030218D03*
X464385Y1038534D03*
X471558Y1029482D03*
X471755Y1038665D03*
X470610Y1033783D03*
X475588Y1043055D03*
X473639Y1030952D03*
X459700Y1035716D03*
X470978Y1046591D03*
X460277Y1090268D03*
X474348Y1090171D03*
X460277Y1093068D03*
X462913Y1106365D03*
X474277Y1093048D03*
X472482Y1107997D03*
X468282D03*
X474818Y1123101D03*
X459938Y1110092D03*
X463604Y1115896D03*
X473367Y1113648D03*
X474818Y1116101D03*
Y1118801D03*
X472582Y1110597D03*
X470482Y1112397D03*
X468282Y1110897D03*
Y1113797D03*
X470382Y1109397D03*
X463604Y1118396D03*
X469192Y1131935D03*
X474818Y1125801D03*
X473218Y1129301D03*
X461459Y1136935D03*
Y1134435D03*
Y1139435D03*
Y1131935D03*
X471692Y1139435D03*
Y1136935D03*
Y1134435D03*
Y1131935D03*
X469192Y1139435D03*
Y1136935D03*
Y1134435D03*
X471692Y1146935D03*
Y1141935D03*
X469192Y1144435D03*
Y1146935D03*
Y1141935D03*
X471692Y1144435D03*
X461459D03*
X462687Y1152684D03*
X468850D03*
X461459Y1141935D03*
Y1146935D03*
X462687Y1160834D03*
X474548Y1172384D03*
Y1169884D03*
Y1167384D03*
Y1164884D03*
Y1162384D03*
X468850Y1160834D03*
X474548Y1174884D03*
X465785Y1197471D03*
X461285Y1193471D03*
Y1197471D03*
X465785Y1193471D03*
X463216Y1254164D03*
Y1250760D03*
Y1244055D03*
X474647Y1260160D03*
Y1257160D03*
X471647D03*
Y1260160D03*
X461613Y1286776D03*
X459290Y1297035D03*
X463290D03*
X462786Y1460782D03*
X471448Y1471805D03*
X462786Y1476136D03*
Y1491490D03*
X471448Y1487159D03*
Y1502514D03*
X462786Y1506845D03*
Y1563144D03*
X471448Y1558813D03*
X462786Y1578498D03*
X471448Y1574167D03*
X462786Y1593853D03*
X471448Y1589522D03*
X462786Y1609207D03*
X471448Y1604876D03*
X472000Y1644980D03*
X484043Y4469D03*
X485404Y24773D03*
Y44773D03*
X492135Y103411D03*
X492529Y97667D03*
X483675D03*
X487925Y95111D03*
X480324Y109172D03*
X477324D03*
X479331Y106495D03*
X483075Y116497D03*
X487875D03*
X490375Y109410D03*
Y116497D03*
X479331Y102495D03*
X483075Y130670D03*
X487875Y123584D03*
Y130670D03*
X490375Y123583D03*
Y130670D03*
X483075Y123584D03*
X485475Y118342D03*
Y121742D03*
Y132515D03*
X479065Y146012D03*
X480971Y141228D03*
X483075Y137757D03*
X487875D03*
X485475Y135915D03*
X479065Y142862D03*
X486206Y143762D03*
X480106Y148717D03*
X483859Y150847D03*
X487654Y195176D03*
X489672Y199248D03*
X485154Y195176D03*
X482654D03*
X486672Y199248D03*
X490154Y195176D03*
X476155Y206838D03*
X491607Y213539D03*
X485235Y210509D03*
X482735D03*
X489672Y202048D03*
X486672Y201748D03*
X484508Y206806D03*
X487008D03*
X476659Y216970D03*
Y219470D03*
X476725Y226320D03*
X476659Y221970D03*
X493272Y230117D03*
X484427Y230556D03*
X488682Y227824D03*
X479686Y228646D03*
X485827Y247292D03*
X478617Y236121D03*
X475651Y238589D03*
X485053Y238689D03*
X483412Y242078D03*
X478643Y232971D03*
X488769Y246874D03*
X489288Y238714D03*
X490989Y244297D03*
X478536Y253198D03*
X482636Y256394D03*
X492817Y357111D03*
X491843Y351089D03*
X483242Y366481D03*
X483584Y375840D03*
X483736Y371266D03*
X481724Y373589D03*
Y369089D03*
X490885Y373589D03*
X491053Y365423D03*
X483541Y380306D03*
X481724Y391589D03*
Y387089D03*
X491289Y391589D03*
X481724Y382589D03*
Y378089D03*
X490885Y382570D03*
X488438Y425464D03*
X482532Y418464D03*
X490985Y412342D03*
X488438Y418417D03*
X485485Y439903D03*
X489485D03*
X481485Y439900D03*
Y431917D03*
X489485Y431417D03*
X482484Y444517D03*
X482193Y472784D03*
Y468784D03*
Y476784D03*
X492736Y478982D03*
Y491982D03*
X482905Y531726D03*
X482737Y537215D03*
X482836Y534249D03*
X491818Y534909D03*
X491445Y541135D03*
X482905Y527726D03*
Y552726D03*
Y540726D03*
Y548726D03*
Y544726D03*
X491534Y552726D03*
X491511Y546553D03*
X486738Y581222D03*
X489538D03*
Y591215D03*
X486738D03*
X491340Y611091D03*
X487209Y611071D03*
X484772Y621311D03*
X493392Y622285D03*
X493580Y616905D03*
X484772Y629311D03*
Y625311D03*
X493661Y627713D03*
X493778Y633724D03*
X481165Y646036D03*
X485005Y659771D03*
X491324Y667293D03*
X483059Y662649D03*
X488765Y667224D03*
X481742Y657477D03*
X485303Y681841D03*
X484341Y700528D03*
X486837Y701306D03*
X484341Y705484D03*
X486837Y704706D03*
X489406Y797558D03*
X486246Y804497D03*
X485824Y819787D03*
X481593Y826387D03*
X489572Y822805D03*
X479448Y828594D03*
X491453Y834546D03*
X491527Y843206D03*
X479700Y847600D03*
X488469Y857013D03*
X477574Y860815D03*
X490706Y859339D03*
X481943Y924633D03*
X488388Y938903D03*
X491616Y938771D03*
X483636Y952152D03*
X476475Y952249D03*
X479613Y952189D03*
X489163Y977163D03*
X490143Y989521D03*
X487091Y989550D03*
X481495Y1011303D03*
X475495D03*
X480711Y999941D03*
X477857Y1004375D03*
X481495Y1023303D03*
Y1017303D03*
X475495Y1023303D03*
X488041Y1020440D03*
X485678Y1039880D03*
X485633Y1036155D03*
X476148Y1057998D03*
Y1055498D03*
X478648D03*
Y1057998D03*
X476148Y1060498D03*
Y1062998D03*
X478648D03*
Y1060498D03*
X477765Y1093432D03*
X477607Y1089942D03*
X491503Y1086796D03*
Y1084296D03*
X478517Y1086724D03*
Y1084224D03*
Y1081724D03*
X476017D03*
Y1084224D03*
Y1086724D03*
X490762Y1098767D03*
X485574Y1098518D03*
X480322Y1098428D03*
X486369Y1105552D03*
X490647Y1101917D03*
X488927Y1104335D03*
X490582Y1106897D03*
X482575Y1104792D03*
X484082Y1106867D03*
X485318Y1123101D03*
X482818D03*
X480167Y1113648D03*
X477667D03*
X490718Y1129301D03*
X483218Y1125801D03*
X485718D03*
X475718Y1129301D03*
X478218D03*
X480718D03*
X483218D03*
X485718D03*
X488218Y1125801D03*
X490718D03*
X488218Y1129301D03*
X477682Y1152713D03*
Y1155213D03*
X488082D03*
Y1152713D03*
X477048Y1172384D03*
Y1169884D03*
Y1167384D03*
Y1164884D03*
Y1162384D03*
X479521Y1179209D03*
Y1181709D03*
Y1184209D03*
Y1186709D03*
X477048Y1174884D03*
X477206Y1198321D03*
X490671D03*
Y1200821D03*
X479521Y1204405D03*
X477206Y1200821D03*
X490671Y1192621D03*
Y1190121D03*
X477206Y1192621D03*
Y1190121D03*
X479521Y1206905D03*
Y1211905D03*
Y1209405D03*
X489647Y1260160D03*
Y1257160D03*
X486647D03*
Y1260160D03*
X480647Y1257160D03*
X477647D03*
Y1260160D03*
X480647D03*
X483647Y1257160D03*
Y1260160D03*
X484800Y1302000D03*
X490100Y1302100D03*
X487600D03*
X480109Y1460782D03*
Y1476136D03*
X488771Y1471805D03*
Y1487159D03*
X480109Y1491490D03*
Y1506845D03*
X488771Y1502514D03*
Y1558813D03*
X480109Y1563144D03*
Y1578498D03*
X488771Y1574167D03*
Y1589522D03*
X480109Y1593853D03*
X488771Y1604876D03*
X480109Y1609207D03*
X492725Y53597D03*
X503537Y77784D03*
Y75184D03*
Y80384D03*
Y82984D03*
X506091Y92849D03*
X503537Y85584D03*
X503325Y90650D03*
X508637Y90615D03*
X503075Y95236D03*
Y102323D03*
X503327Y109410D03*
Y116496D03*
X495075D03*
Y102323D03*
Y109410D03*
X492775Y114655D03*
Y111255D03*
X492294Y106561D03*
X495075Y130670D03*
Y123583D03*
X506653Y121652D03*
X504552Y130670D03*
X492775Y128828D03*
Y125428D03*
X504547Y137756D03*
X495075D03*
X493288Y238714D03*
X497424Y354559D03*
X496023Y362913D03*
X492317Y376252D03*
X497048Y369450D03*
X495750Y377531D03*
X506500Y379687D03*
X495203Y386890D03*
X493485Y439903D03*
X503729Y439919D03*
X503682Y455466D03*
X497776Y448466D03*
X503682Y448419D03*
X500729Y469905D03*
X496729Y470419D03*
X504729Y469905D03*
X496729Y461919D03*
X504729Y461419D03*
X492736Y487982D03*
Y483982D03*
X505476Y485128D03*
X497095Y481467D03*
X501224Y492050D03*
X501649Y482165D03*
X492736Y499982D03*
X501887Y504825D03*
X499387D03*
X496887D03*
X500890Y500202D03*
X502493Y495917D03*
X492736Y495982D03*
X501828Y517401D03*
X499328D03*
X496828D03*
X502379Y522569D03*
X495444Y531948D03*
X503494Y531882D03*
X502379Y525369D03*
X500994Y531882D03*
X498494D03*
X504079Y529169D03*
X506925Y546830D03*
X493929Y555194D03*
X496729D03*
X503729D03*
X500929D03*
X493929Y563194D03*
X496729D03*
X493929Y571194D03*
X496729D03*
X500929D03*
X503729D03*
Y563194D03*
X500929D03*
X492338Y581222D03*
X505286D03*
X502486D03*
X492338Y591215D03*
X505286D03*
X502486D03*
X505458Y610562D03*
X502658D03*
Y607762D03*
X505458D03*
X497448Y610548D03*
X504265Y633736D03*
X499258Y633716D03*
X506278Y628078D03*
X499278Y641817D03*
X493778D03*
X494632Y654622D03*
X494465Y657772D03*
X502755Y657694D03*
X496070Y665976D03*
X499528Y657843D03*
X504966Y678098D03*
X498284Y681453D03*
Y678953D03*
X501618Y698355D03*
X499012Y699819D03*
X503311Y715652D03*
X500705Y705524D03*
X500714Y708755D03*
X502832Y720491D03*
X507546Y738539D03*
X505673Y767961D03*
X500717D03*
X504895Y770457D03*
X501495D03*
X504508Y783817D03*
X506166Y793224D03*
X504641Y789139D03*
X504341Y812040D03*
X507095Y814784D03*
X491655Y829173D03*
X506246Y824689D03*
X494677Y830468D03*
X509665Y824512D03*
X492799Y846488D03*
X503741Y846830D03*
X497467Y833027D03*
X495073Y835586D03*
X495470Y844271D03*
X499640Y861538D03*
X495700Y849389D03*
X503383Y863025D03*
X498507Y865392D03*
X508248Y873319D03*
X509791Y881932D03*
X509017Y905295D03*
X494315Y941212D03*
X503144Y957934D03*
X499595Y963963D03*
X493050Y976078D03*
X504088Y985171D03*
X506888D03*
X506702Y978947D03*
X493091Y989550D03*
X503933Y981392D03*
X506566Y1000766D03*
Y1004766D03*
X498435Y1008766D03*
X506566D03*
Y996766D03*
X498524Y997590D03*
X506566Y1016266D03*
X498585D03*
X506566Y1012266D03*
Y1030766D03*
X505981Y1052487D03*
X503177Y1058097D03*
X495677D03*
X493177D03*
X498177D03*
X500677D03*
X503177Y1060697D03*
X495677D03*
X493177D03*
X498177D03*
X500677D03*
X494003Y1086796D03*
X496503D03*
X499003D03*
X501503D03*
Y1084296D03*
X499003D03*
X496503D03*
X494003D03*
X501831Y1090288D03*
X496372Y1106298D03*
X504610Y1107997D03*
X501831Y1093088D03*
X500410Y1107997D03*
X506946Y1123101D03*
X497063Y1115896D03*
X505495Y1113648D03*
X506946Y1116101D03*
Y1118801D03*
X504710Y1110597D03*
X500410Y1113797D03*
X502610Y1112397D03*
X500410Y1110897D03*
X502510Y1109397D03*
X493397Y1110092D03*
X497063Y1118396D03*
X506946Y1125801D03*
X505346Y1129301D03*
X507846D03*
X503820Y1139435D03*
Y1136935D03*
Y1134435D03*
Y1131935D03*
X501320Y1139435D03*
Y1136935D03*
Y1134435D03*
Y1131935D03*
X494918Y1136935D03*
Y1134435D03*
Y1139435D03*
Y1131935D03*
X498727Y1128759D03*
X495236Y1129094D03*
X503820Y1144435D03*
Y1146935D03*
Y1141935D03*
X501320Y1144435D03*
Y1146935D03*
Y1141935D03*
X494918Y1146935D03*
Y1144435D03*
Y1141935D03*
X502562Y1152713D03*
Y1155213D03*
X502376Y1172384D03*
Y1169884D03*
Y1167384D03*
Y1164884D03*
Y1162384D03*
X504876Y1172384D03*
Y1169884D03*
Y1167384D03*
Y1164884D03*
Y1162384D03*
X492818D03*
Y1164884D03*
Y1167384D03*
Y1169884D03*
Y1172384D03*
X495318D03*
Y1169884D03*
Y1167384D03*
Y1164884D03*
Y1162384D03*
X502562Y1158200D03*
X506451Y1179209D03*
Y1181709D03*
Y1184209D03*
Y1186709D03*
X504876Y1174884D03*
X493821Y1186921D03*
Y1184421D03*
Y1181921D03*
Y1179421D03*
X492818Y1174884D03*
X495318D03*
X502376D03*
X506451Y1204405D03*
X504136Y1198321D03*
Y1200821D03*
X493821Y1204617D03*
X496136Y1200821D03*
Y1198321D03*
X504136Y1190121D03*
Y1192621D03*
X496136Y1190121D03*
Y1192621D03*
X506451Y1206905D03*
Y1211905D03*
Y1209405D03*
X493821Y1207117D03*
Y1209617D03*
Y1212117D03*
X506562Y1222194D03*
X502562D03*
X498562D03*
X494562D03*
X506562Y1226194D03*
Y1230194D03*
Y1234194D03*
Y1238194D03*
X502562Y1226194D03*
Y1230194D03*
Y1234194D03*
Y1238194D03*
X498562Y1226194D03*
Y1230194D03*
Y1234194D03*
Y1238194D03*
X494562Y1226194D03*
Y1230194D03*
Y1234194D03*
Y1238194D03*
Y1246194D03*
Y1242194D03*
X506562D03*
Y1246194D03*
X502562Y1242194D03*
Y1246194D03*
X498562Y1242194D03*
Y1246194D03*
X504647Y1257160D03*
X507347D03*
X501647D03*
Y1260160D03*
X495647D03*
X492647D03*
Y1257160D03*
X495647D03*
X498647D03*
Y1260160D03*
X507347D03*
X504647D03*
X497432Y1460782D03*
Y1476136D03*
X506093Y1471805D03*
X497432Y1491490D03*
X506093Y1487159D03*
X497432Y1506845D03*
X506093Y1502514D03*
X497432Y1563144D03*
X506093Y1558813D03*
X497432Y1578498D03*
X506093Y1574167D03*
Y1589522D03*
X497432Y1593853D03*
X506093Y1604876D03*
X497432Y1609207D03*
X492000Y1644980D03*
X512725Y53597D03*
X521872Y82593D03*
Y85193D03*
Y74793D03*
Y77393D03*
Y79993D03*
X521916Y92874D03*
X512958Y99961D03*
X513008Y95236D03*
X513051Y103037D03*
X513185Y116496D03*
Y109410D03*
X521185Y116496D03*
Y109410D03*
Y102323D03*
X523943Y107649D03*
Y104249D03*
X513185Y130670D03*
Y123583D03*
X521185Y130670D03*
Y123583D03*
X509251Y137756D03*
X521185D03*
X520965Y162368D03*
X523565D03*
X511820Y207978D03*
Y210478D03*
Y215478D03*
Y212978D03*
X522276Y208213D03*
Y213213D03*
Y210713D03*
Y223661D03*
Y226461D03*
Y228961D03*
Y231461D03*
X511820Y231226D03*
Y228726D03*
Y223726D03*
Y226226D03*
X522276Y215713D03*
X515149Y264180D03*
X517649D03*
X515074Y258880D03*
X524043Y270026D03*
Y267526D03*
X517866Y293796D03*
X515366D03*
X523380Y285690D03*
Y288190D03*
X511342Y311124D03*
X514769Y312953D03*
X519638Y314346D03*
X511790Y313804D03*
X520845Y434508D03*
X516845D03*
X512845D03*
X512943Y443071D03*
X520823Y442603D03*
X514608Y445874D03*
X510022Y446352D03*
X523705Y444269D03*
X523583Y447201D03*
X511753Y454339D03*
Y456839D03*
X509253D03*
Y454339D03*
X518240Y459371D03*
X508729Y469905D03*
X521310Y470045D03*
X513310D03*
X509253Y459339D03*
X511753D03*
X512210Y475825D03*
X517310Y470045D03*
X513310Y462004D03*
X522756Y461818D03*
X523457Y482134D03*
Y484634D03*
X508325Y485138D03*
X512210Y478625D03*
X513910Y482425D03*
X513325Y485138D03*
X510825D03*
X519786Y491214D03*
X521636Y504699D03*
X516636D03*
X519136D03*
X516756Y500086D03*
X523489Y492987D03*
X519786Y493714D03*
X523489Y495487D03*
X517319Y521804D03*
X516338Y516979D03*
X521338D03*
X518838D03*
X513626Y528578D03*
Y531378D03*
X518781Y527449D03*
X517319Y524304D03*
X521581Y527449D03*
X509955Y537958D03*
X513658Y539731D03*
X518716Y541895D03*
X521216Y544895D03*
Y541895D03*
X513658Y542231D03*
X518416Y544895D03*
X509955Y540458D03*
X521494Y572975D03*
Y582747D03*
X508086Y581222D03*
X520945Y590801D03*
X508086Y591215D03*
X520770Y597130D03*
X524770Y605637D03*
X519875Y608311D03*
X518940Y620653D03*
Y617853D03*
X511058Y610562D03*
Y607762D03*
X508258Y610562D03*
Y607762D03*
X520770Y605443D03*
X516770D03*
X523596Y628242D03*
X512404Y629362D03*
X510215Y627948D03*
X523616Y625013D03*
X515267Y627908D03*
X511278Y633473D03*
X521778Y642184D03*
X518812Y665867D03*
X521868Y666577D03*
X518812Y662874D03*
X511990Y686365D03*
X510425Y683246D03*
X522200Y677613D03*
X521540Y686319D03*
X518001Y694940D03*
X522410Y694881D03*
X518067Y699378D03*
X518530Y703584D03*
X522628Y703884D03*
X512530Y718301D03*
X514531Y716398D03*
X508237Y723585D03*
X512502Y738539D03*
X516953Y738575D03*
X521909D03*
X521131Y741071D03*
X517731D03*
X511724Y741035D03*
X508324D03*
X520159Y758832D03*
X520549Y761982D03*
X509096Y753072D03*
X515422Y753455D03*
X513504Y755804D03*
X509063Y782867D03*
X517194Y773232D03*
X513278Y783286D03*
X520833Y773389D03*
X513551Y773203D03*
X522316Y793574D03*
X509316Y793224D03*
X508130Y787488D03*
X522697Y797102D03*
X519891Y795848D03*
X521178Y814001D03*
X518157Y803973D03*
X518565Y811973D03*
X520741Y805149D03*
X521565Y820931D03*
X522481Y824661D03*
X517702Y826600D03*
X520720Y846133D03*
X517832Y834558D03*
X514682Y834590D03*
X511741Y846649D03*
X524741Y845149D03*
X508049Y877789D03*
X523272Y880067D03*
X520870Y874694D03*
X509428Y888390D03*
X521115Y897500D03*
X511025Y911443D03*
X509673Y900295D03*
X525159Y913818D03*
X521572Y901500D03*
X516902Y910251D03*
X516256Y939157D03*
X520146Y939241D03*
X523289Y939195D03*
X524475Y952290D03*
X514886Y952189D03*
X521353Y952266D03*
X509471Y981608D03*
X522544Y992854D03*
X512232Y985172D03*
X514566Y1000766D03*
X514690Y996766D03*
Y1004766D03*
X514566Y1016266D03*
X514649Y1020266D03*
X519792Y1031271D03*
X514843Y1030766D03*
X519500Y1028377D03*
X515831Y1090568D03*
X517702Y1098518D03*
X512450Y1098428D03*
X515831Y1093068D03*
X522890Y1098767D03*
X518497Y1105552D03*
X522775Y1101917D03*
X521055Y1104335D03*
X514703Y1104792D03*
X522710Y1106897D03*
X516210Y1106867D03*
X514946Y1123101D03*
X517446D03*
X509795Y1113648D03*
X512295D03*
X522846Y1129301D03*
X515346Y1125801D03*
X517846D03*
X510346Y1129301D03*
X512846D03*
X515346D03*
X517846D03*
X520346Y1125801D03*
X522846D03*
X520346Y1129301D03*
X518210Y1155213D03*
Y1152713D03*
X508810D03*
Y1155213D03*
X520646Y1169884D03*
Y1167384D03*
Y1164884D03*
Y1162384D03*
X523146D03*
Y1164884D03*
Y1167384D03*
Y1169884D03*
Y1172384D03*
X520646D03*
X520751Y1186921D03*
Y1184421D03*
Y1181921D03*
Y1179421D03*
X523146Y1174884D03*
X520646D03*
X520751Y1204617D03*
X523066Y1200821D03*
Y1198321D03*
Y1190121D03*
Y1192621D03*
X520751Y1207117D03*
Y1209617D03*
Y1212117D03*
X522562Y1222194D03*
X518562D03*
X514562D03*
X510562D03*
X522562Y1226194D03*
X518562D03*
Y1230194D03*
Y1234194D03*
X514562Y1226194D03*
Y1230194D03*
Y1234194D03*
Y1238194D03*
X510562Y1226194D03*
Y1230194D03*
Y1234194D03*
Y1238194D03*
X514562Y1242194D03*
Y1246194D03*
X510562Y1242194D03*
Y1246194D03*
X517374Y1287222D03*
X514363Y1287370D03*
X520548Y1287181D03*
X514755Y1460782D03*
Y1476136D03*
Y1491490D03*
Y1506845D03*
Y1563144D03*
Y1578498D03*
Y1593853D03*
Y1609207D03*
X512000Y1644980D03*
X531518Y5374D03*
X530831Y24773D03*
Y44773D03*
X526468Y94017D03*
X530197Y101701D03*
X534468Y94017D03*
X538477D03*
X530468D03*
X530197Y98551D03*
X540751Y97475D03*
X530596Y115401D03*
X535588Y110445D03*
Y115401D03*
X530596Y110445D03*
X537747Y103783D03*
X533092Y114623D03*
Y111223D03*
X533747Y103783D03*
X530596Y124618D03*
Y129574D03*
X535588Y124618D03*
Y129574D03*
X533092Y128796D03*
Y125396D03*
X532281Y141247D03*
X528509Y147540D03*
X539748Y143740D03*
X537128Y148277D03*
X528509Y151540D03*
X530665Y162793D03*
Y165393D03*
Y170493D03*
Y167993D03*
X538170Y172190D03*
X535668Y181009D03*
X529662Y181426D03*
X532873Y181366D03*
X537589Y177616D03*
X538659Y184619D03*
X532159Y191941D03*
X532026Y188727D03*
X529870Y184221D03*
X532487Y184012D03*
X533906Y211359D03*
Y213859D03*
X528848Y211695D03*
X537609Y213132D03*
X526348Y208695D03*
X529148D03*
X526348Y211695D03*
X530245Y229286D03*
X528783Y226141D03*
X525983D03*
X533938Y222212D03*
Y224712D03*
X537609Y215632D03*
X526226Y236611D03*
X531226D03*
X528726D03*
X530245Y231786D03*
X528428Y248891D03*
X530928D03*
X533853Y256535D03*
X525928Y248891D03*
X537853Y256303D03*
X532525Y265701D03*
X537612Y265896D03*
X526843Y270026D03*
X529343D03*
X526843Y267526D03*
X529343D03*
X534160Y281716D03*
X540101Y281982D03*
X525880Y285690D03*
X528680D03*
X525880Y288190D03*
X528680D03*
X532906Y290755D03*
X536906D03*
X540906D03*
X524206Y354119D03*
X533027Y351836D03*
X532659Y359557D03*
X526388Y351301D03*
X531612Y354272D03*
X531636Y349057D03*
X530215Y364422D03*
X528812Y369164D03*
X533211Y364746D03*
X533115Y371856D03*
X530144Y376062D03*
X531953Y380749D03*
X542034Y392209D03*
X541706Y386223D03*
X533189Y390723D03*
X531953Y385749D03*
X535142Y397552D03*
X531992D03*
X526216Y456652D03*
X528716D03*
X526216Y459152D03*
Y461652D03*
X528716Y459152D03*
Y461652D03*
X535119Y483886D03*
Y481086D03*
Y478586D03*
X526902Y478446D03*
Y475946D03*
X531412Y480705D03*
X535119Y476086D03*
X528612Y480705D03*
X535119Y491133D03*
X531047Y498151D03*
X535119Y493633D03*
Y496133D03*
Y498633D03*
X531047Y495151D03*
X528547D03*
X528247Y498151D03*
X532936Y519544D03*
X525288Y522129D03*
X527936Y519544D03*
X525436D03*
X530436D03*
X525288Y524629D03*
Y527129D03*
Y529929D03*
X529481Y532849D03*
X532281D03*
X525288Y537877D03*
X535219Y555897D03*
Y553297D03*
X533488Y548344D03*
X525288Y540377D03*
Y545377D03*
Y542877D03*
X528488Y548344D03*
X525988D03*
X530988D03*
X524708Y572842D03*
X535219Y561097D03*
Y563697D03*
Y566797D03*
Y558497D03*
X532009Y570478D03*
X529214Y570686D03*
X532863Y585507D03*
X528270D03*
X528816Y579475D03*
X529423Y573303D03*
X532069Y573689D03*
X532426Y576484D03*
X535819Y578405D03*
X541245Y578986D03*
X532908Y590190D03*
X528314Y590145D03*
X524770Y597232D03*
X534820Y596782D03*
X540770Y596729D03*
X529601Y596089D03*
X532770Y605443D03*
X526756Y613913D03*
Y616713D03*
Y619513D03*
X538826Y614158D03*
Y616958D03*
Y619758D03*
X536770Y605443D03*
X538826Y633450D03*
X526756Y636005D03*
Y633205D03*
X538826Y636250D03*
Y639050D03*
X526756Y638805D03*
X524653Y643595D03*
X533486Y664052D03*
X538442D03*
X524941Y661387D03*
X530796D03*
X537664Y661556D03*
X534264D03*
X529664Y664056D03*
X526264D03*
X534940Y684489D03*
X539111Y681459D03*
X526956Y694959D03*
X526951Y699443D03*
X538316Y687357D03*
X535738Y687489D03*
X536087Y702364D03*
X535387Y712617D03*
X526933Y703820D03*
X532628Y720776D03*
X526276Y721339D03*
X539763Y734097D03*
X534807D03*
X531763Y739097D03*
X526807D03*
X535585Y736593D03*
X538985D03*
X530985Y741593D03*
X527585D03*
X532450Y767474D03*
X542275Y760782D03*
X532278Y762736D03*
X524598Y753387D03*
X532449Y782389D03*
X539449D03*
X537578Y772428D03*
X534672Y785037D03*
X531501Y792331D03*
X531260Y794934D03*
X531666Y815724D03*
X532304Y806649D03*
X531313Y812850D03*
Y822693D03*
Y826630D03*
X527733Y847026D03*
X536641Y838649D03*
X532316Y833649D03*
X534000Y843000D03*
X537300Y842900D03*
X530741Y845149D03*
X534632Y849830D03*
X528868Y873683D03*
X525718Y873821D03*
X533468Y878533D03*
X538468Y888033D03*
X530968Y888283D03*
X527346Y911458D03*
X528975Y898346D03*
X537279Y897943D03*
X533143Y897910D03*
X531076Y913190D03*
X527879Y952189D03*
X530473Y961728D03*
X528674Y964851D03*
X528500Y1106365D03*
X529191Y1115896D03*
X525525Y1110092D03*
X529191Y1118396D03*
X527046Y1131935D03*
Y1139435D03*
Y1134435D03*
Y1136935D03*
X528274Y1152684D03*
X527046Y1146935D03*
Y1144435D03*
Y1141935D03*
X528274Y1160834D03*
X532000Y1644980D03*
X550421Y3000D03*
X554198Y68581D03*
X543545Y84140D03*
Y80140D03*
Y76140D03*
X554211Y80581D03*
X546293Y76587D03*
Y72615D03*
X547732Y100625D03*
X540998Y117557D03*
X545990D03*
X548914Y103621D03*
X540682Y106186D03*
X552105Y112083D03*
X556394Y103621D03*
X545990Y122513D03*
Y131731D03*
X540998Y122513D03*
Y131731D03*
X543494Y121735D03*
Y132509D03*
Y118335D03*
Y135909D03*
X544089Y146461D03*
X545990Y136687D03*
X540998D03*
X548311Y141247D03*
X552798Y143518D03*
X551898Y152373D03*
X542991Y152367D03*
X555048Y152562D03*
X549374Y180527D03*
X544691Y180572D03*
X540843Y168697D03*
X555850Y178560D03*
X555913Y172665D03*
X555740Y183834D03*
X553097Y192421D03*
X549329Y185121D03*
X544691Y185165D03*
X541931Y191941D03*
X555260Y190185D03*
X549985Y192490D03*
X556030Y200864D03*
X540639Y206760D03*
X548940Y206767D03*
X546440D03*
X543940D03*
X556119Y212455D03*
X556053Y207037D03*
X549070Y221708D03*
X546570D03*
X553420Y221642D03*
X545185Y231021D03*
Y228221D03*
X544070Y221708D03*
X543485Y224421D03*
X550736Y236189D03*
X548236D03*
X545736D03*
X541853Y256535D03*
X550677Y248765D03*
X548177D03*
X545677D03*
X542628Y266114D03*
X542883Y279208D03*
X546987Y281307D03*
X545874Y268195D03*
X548374D03*
X551174Y270695D03*
X554834Y265897D03*
X551174Y268195D03*
X548374Y270695D03*
X545874D03*
X551477Y288345D03*
Y290845D03*
X548977Y288345D03*
Y290845D03*
Y293645D03*
X551477D03*
X551536Y359223D03*
Y354723D03*
Y350223D03*
Y345723D03*
Y377223D03*
Y372723D03*
Y368223D03*
Y363723D03*
X541644Y389047D03*
X553731Y388487D03*
X541706Y381723D03*
X551536D03*
X551620Y390723D03*
X553563Y384987D03*
X552905Y430829D03*
X544738Y581659D03*
X540770Y605443D03*
X544770D03*
X550274Y658676D03*
X551475Y661504D03*
X556574Y684031D03*
X547227Y678299D03*
X547276Y675521D03*
X556574Y700031D03*
Y688987D03*
X543101Y698772D03*
X556574Y716031D03*
Y704987D03*
Y720987D03*
X540379Y719785D03*
X557751Y750851D03*
X552384Y762892D03*
X552188Y766577D03*
X542599Y782389D03*
X549168Y781600D03*
X545768D03*
X542546Y784911D03*
X554357Y784889D03*
X551524D03*
X550420Y793743D03*
X556326D03*
X540578Y793889D03*
X544515Y793875D03*
X553871Y811298D03*
X545741Y804149D03*
X544741Y809649D03*
X544878Y816309D03*
X548464Y823156D03*
X540807Y816556D03*
X541129Y828335D03*
X546855Y829949D03*
X550087Y829836D03*
X556326Y829989D03*
X556741Y820149D03*
X544741Y823149D03*
X541129Y838865D03*
X545981Y846389D03*
X549241Y841388D03*
X546241Y843149D03*
X545237Y850319D03*
X557836Y851669D03*
X548665Y850399D03*
X548521Y877859D03*
Y874859D03*
X540968Y878360D03*
X546940Y871389D03*
X545144Y909025D03*
X544793Y899220D03*
X548327Y905295D03*
X552238Y959102D03*
X552923Y988813D03*
X548215Y1006560D03*
X552923Y997860D03*
X542793Y998507D03*
X544719Y1007522D03*
X551485Y1006648D03*
X541766Y1018368D03*
X551673Y1023900D03*
X548852Y1018307D03*
X545094Y1013678D03*
X545566Y1023731D03*
X554696Y1018469D03*
X557681Y1035088D03*
X556493Y1118351D03*
X557584Y1543411D03*
X552000Y1644980D03*
X570421Y3000D03*
X566287Y60922D03*
X561123Y55513D03*
X560573Y60513D03*
X563433Y60438D03*
X557973Y55513D03*
X569114Y86012D03*
X563224Y96813D03*
X558316Y91951D03*
X558341Y88801D03*
X569114Y94374D03*
X561258Y94351D03*
X565207Y94279D03*
X560701Y85731D03*
X564255Y86046D03*
X556920Y117261D03*
X567100Y110784D03*
X564451Y113394D03*
X572669Y102249D03*
X568669D03*
X564451Y116594D03*
X570394Y110784D03*
X567290Y130898D03*
X564451Y119594D03*
X574973Y124663D03*
X564885Y124283D03*
X569951Y124879D03*
X568841Y134579D03*
X563292Y161306D03*
X560543Y157370D03*
X564627Y180665D03*
Y172665D03*
Y176665D03*
Y168665D03*
X569969Y195176D03*
X572469D03*
X556726Y186629D03*
X564627Y196665D03*
Y192665D03*
X564740Y186778D03*
X572329Y203393D03*
X574588Y201683D03*
X564659Y212864D03*
Y200864D03*
X569829Y203393D03*
X564659Y204864D03*
Y208864D03*
Y221864D03*
Y216864D03*
X569708Y218085D03*
X572508D03*
X560300Y219379D03*
X560928Y228631D03*
X575035Y249108D03*
X566416Y252371D03*
Y248371D03*
X557334Y265897D03*
X570634Y375453D03*
X573479Y374705D03*
X569938Y378317D03*
X559070Y684809D03*
X559074Y696987D03*
Y692031D03*
X559070Y700809D03*
Y688209D03*
X561570Y696209D03*
Y692809D03*
X559074Y712987D03*
Y708031D03*
X559070Y716809D03*
X561570Y708809D03*
Y712209D03*
X559070Y704209D03*
X561886Y728138D03*
X559070Y720209D03*
X558616Y732530D03*
X562001Y732834D03*
X562374Y721593D03*
X559625Y739609D03*
X557813Y747814D03*
X570578Y749800D03*
X567428Y750145D03*
X557847Y744599D03*
X563200Y739600D03*
X570695Y767052D03*
X571493Y763090D03*
X570038Y752339D03*
X564362Y757979D03*
X564276Y776701D03*
X560263Y782207D03*
X567126Y779066D03*
X571984Y784507D03*
X558241Y796389D03*
X562231Y784911D03*
X558294D03*
X569186Y787332D03*
X561401Y811242D03*
X567559Y812850D03*
X567316Y806224D03*
X561061Y803606D03*
X561001Y806889D03*
X567559Y803008D03*
X563099Y829943D03*
X560263Y829989D03*
X567316Y827724D03*
X559741Y822149D03*
X567559Y824661D03*
X562400Y818900D03*
X572171Y842346D03*
X559196Y846296D03*
X560813Y840574D03*
X568990Y844721D03*
X572476Y845535D03*
X559295Y874267D03*
X559887Y877196D03*
X561134Y869291D03*
X569577Y886913D03*
X559260Y891043D03*
X559214Y897425D03*
X564165Y894411D03*
X567827Y884000D03*
X560814Y901022D03*
X568503Y936807D03*
X565003D03*
X562328Y957307D03*
X566303Y951807D03*
X569403D03*
X563103D03*
X570603Y957207D03*
X560923Y980443D03*
X556923Y980523D03*
X564923Y988813D03*
X560923D03*
X556923D03*
X568923D03*
X564923Y997860D03*
X560923D03*
X568923D03*
X556923D03*
X568362Y1008262D03*
X571857Y1009354D03*
X558112Y1009655D03*
X560912D03*
X568362Y1011762D03*
X567484Y1024003D03*
X571857Y1016827D03*
X565451Y1035102D03*
X559057Y1030563D03*
X562057D03*
X568057Y1030672D03*
X565057D03*
X571857Y1029427D03*
X569520Y1102091D03*
X560211D03*
X566020D03*
X566058Y1109564D03*
X569520Y1114691D03*
X566020D03*
X560211D03*
Y1109564D03*
X566058Y1122164D03*
X560211D03*
X569520Y1139891D03*
X566020D03*
X560211D03*
X566020Y1127291D03*
X560211D03*
X569520D03*
X566058Y1134764D03*
X560211D03*
X566020Y1152491D03*
X560211D03*
X569520D03*
X566058Y1147364D03*
X560211D03*
X566020Y1165091D03*
X560211D03*
X569520D03*
X566058Y1159964D03*
X560211D03*
X566058Y1172564D03*
X560211D03*
Y1177691D03*
X566020D03*
X569520D03*
X566058Y1185164D03*
X560211D03*
X563673Y1204932D03*
X566502Y1202103D03*
X568532Y1200001D03*
X575620Y1207737D03*
X569135Y1214372D03*
X564890Y1218169D03*
X569882Y1223749D03*
X565600Y1530800D03*
X570796Y1530309D03*
X567324Y1528151D03*
X572432Y1521462D03*
X569349Y1541947D03*
X560635Y1543531D03*
X566800Y1541800D03*
X565400Y1535100D03*
X563968Y1541445D03*
X568279Y1538438D03*
X572507Y1541375D03*
X586405Y4469D03*
X587766Y24773D03*
Y44773D03*
X576669Y102249D03*
X586037Y97667D03*
X582686Y109172D03*
X579686D03*
X581693Y106495D03*
X585437Y116497D03*
X581693Y102495D03*
X576420Y116594D03*
X575394Y110784D03*
X574694Y133298D03*
X585437Y123584D03*
Y130670D03*
X587837Y118342D03*
Y121742D03*
Y132515D03*
X576420Y119594D03*
X579954Y125107D03*
X581427Y146012D03*
X583333Y141228D03*
X585437Y137757D03*
X587837Y135915D03*
X581427Y142862D03*
X588568Y143762D03*
X582468Y148717D03*
X576317Y138838D03*
X586221Y150847D03*
X574969Y195176D03*
X577769D03*
X574588Y198883D03*
X587516Y195176D03*
X585016D03*
X589034Y199248D03*
X578517Y206838D03*
X576017D03*
X587597Y210509D03*
X585097D03*
X589034Y201748D03*
X586870Y206806D03*
X576308Y216385D03*
X579021Y216970D03*
Y219470D03*
X579087Y226320D03*
X579021Y221970D03*
X586789Y230556D03*
X591044Y227824D03*
X582048Y228646D03*
X587415Y238689D03*
X588189Y247292D03*
X580979Y236121D03*
X578013Y238589D03*
X585774Y242078D03*
X581005Y232971D03*
X577655Y244571D03*
X580898Y253198D03*
X584998Y256394D03*
X581487Y336676D03*
X578193Y336391D03*
X584679Y336285D03*
X573805Y728301D03*
X576556Y728219D03*
X575979Y732517D03*
X573778Y747437D03*
X577638Y769772D03*
X578271Y763556D03*
X583102Y767137D03*
X574620Y772724D03*
X584624Y781850D03*
X587183Y785008D03*
X578204Y775137D03*
X585912Y778470D03*
X588345Y798030D03*
X588659Y790336D03*
X582100Y787600D03*
X586060Y793145D03*
X581001Y814123D03*
X583501Y800831D03*
X581001Y810973D03*
X588377Y807536D03*
X588272Y804601D03*
X588231Y801520D03*
X579758Y817753D03*
X577501Y829069D03*
X588001Y829624D03*
X582737Y819831D03*
X581158Y823473D03*
X573300Y829600D03*
X579827Y884000D03*
Y888000D03*
X580327Y892000D03*
X579251Y903364D03*
X582706Y908959D03*
X586136Y908935D03*
X583065Y903294D03*
X577903Y940907D03*
X581703D03*
X576003Y935107D03*
X573103Y941307D03*
X585703D03*
X581903Y954507D03*
X577303D03*
X586103Y961807D03*
X577249Y965445D03*
X573895Y965319D03*
X584923Y988813D03*
X576923D03*
X580923D03*
X588923D03*
X572923D03*
X580923Y997860D03*
X576923D03*
X588923D03*
X577666Y1009354D03*
X581166D03*
X572923Y997860D03*
X584923D03*
X581166Y1021954D03*
X577666D03*
X577704Y1029427D03*
Y1016827D03*
X587880Y1034834D03*
X581967Y1105091D03*
X587467D03*
X582012Y1102091D03*
X587467Y1117691D03*
X581967D03*
X582012Y1127291D03*
Y1114691D03*
X587467Y1130291D03*
X581967D03*
X587467Y1142891D03*
X582012Y1139891D03*
X581967Y1155491D03*
X587467D03*
X581967Y1142891D03*
X582012Y1152491D03*
X581967Y1168091D03*
X587467D03*
X582012Y1165091D03*
X581967Y1180691D03*
X587467D03*
X582012Y1177691D03*
X578298Y1215195D03*
X584024Y1209607D03*
X586502Y1227300D03*
X583520Y1230407D03*
X581803Y1493687D03*
X578859Y1497758D03*
X588859Y1490895D03*
X590826Y1495688D03*
X587689Y1505724D03*
X588507Y1514141D03*
X582027Y1502800D03*
X581803Y1509687D03*
X577931Y1505687D03*
X583661Y1529142D03*
X573784Y1530646D03*
X575332Y1523740D03*
X583800Y1518000D03*
X583740Y1520640D03*
X587858Y1517942D03*
X575809Y1532912D03*
X572849Y1518702D03*
X587809Y1528389D03*
X583809Y1533025D03*
X579809Y1528163D03*
X577645Y1540982D03*
X580700Y1544100D03*
X587809Y1545854D03*
X583809Y1541607D03*
X577571Y1544013D03*
X595087Y53597D03*
X594497Y103411D03*
X594891Y97667D03*
X605687Y90650D03*
X590287Y95111D03*
X592737Y109410D03*
X590237Y116497D03*
X592737D03*
X597437Y102323D03*
Y109410D03*
Y116496D03*
X595137Y111255D03*
Y114655D03*
X594656Y106561D03*
X597437Y123583D03*
Y130670D03*
X592737Y123583D03*
X590237Y123584D03*
Y130670D03*
X592737D03*
X595137Y125428D03*
Y128828D03*
X597437Y137756D03*
X590237Y137757D03*
X590016Y195176D03*
X592516D03*
X592034Y199248D03*
X593969Y213539D03*
X592034Y202048D03*
X589370Y206806D03*
X595634Y230117D03*
X595650Y238714D03*
X591131Y246874D03*
X591650Y238714D03*
X593351Y244297D03*
X590178Y309760D03*
X592900Y309871D03*
X605147Y378600D03*
X603282Y390223D03*
X605147Y382600D03*
X600272Y397335D03*
X603282Y395179D03*
Y404396D03*
Y409352D03*
X595280Y402291D03*
X600272D03*
X595280Y397335D03*
X597776Y401513D03*
Y398113D03*
X592880Y416465D03*
Y411509D03*
X603282Y418569D03*
Y423525D03*
X597872Y425682D03*
X592880D03*
X597872Y416465D03*
Y411509D03*
X595376Y412287D03*
Y426460D03*
Y415687D03*
X603282Y432743D03*
Y437699D03*
X597872Y439855D03*
X592880D03*
X597872Y430638D03*
X592880D03*
X595376Y440633D03*
Y429860D03*
X597872Y444811D03*
X592880D03*
X593690Y450750D03*
X605262Y458711D03*
X595376Y444033D03*
X602462Y458711D03*
X592880Y468609D03*
X597872D03*
X592880Y473565D03*
X597872D03*
X595376Y469387D03*
Y472787D03*
X604606Y463600D03*
X603282Y489895D03*
X592880Y487738D03*
X597872D03*
X603282Y480677D03*
Y475721D03*
X592880Y482782D03*
X597872D03*
X595376Y483560D03*
Y486960D03*
X603282Y494851D03*
X598462Y504684D03*
X592880Y517699D03*
X597872D03*
X603282Y519855D03*
X597872Y512743D03*
X592880D03*
X595376Y513521D03*
Y516921D03*
X592880Y526916D03*
X597872Y531872D03*
X592880D03*
X603282Y524811D03*
Y538984D03*
Y534028D03*
X597872Y526916D03*
X597789Y536382D03*
X595376Y531094D03*
Y527694D03*
X599110Y552466D03*
X602756Y597580D03*
X604979Y599588D03*
X604241Y589556D03*
X604180Y592354D03*
X602695Y594668D03*
X604982Y596095D03*
X605011Y603600D03*
Y615600D03*
X604979Y607588D03*
X605011Y619600D03*
Y623600D03*
X592238Y880612D03*
X592272Y877262D03*
X592110Y895611D03*
X597129Y913386D03*
X601084Y913544D03*
X604715Y914640D03*
X602385Y940920D03*
X589203Y941407D03*
X591403Y938807D03*
Y936007D03*
X589603Y952907D03*
X591754Y956979D03*
X606142Y965665D03*
X597556Y965829D03*
X602484Y965764D03*
X600923Y988813D03*
X592923D03*
X604923D03*
X596923D03*
Y997860D03*
X592923D03*
X604923D03*
X600923D03*
X599113Y1012354D03*
X593658Y1009354D03*
X602603Y1012354D03*
Y1024954D03*
X593613Y1012354D03*
X599113Y1024954D03*
X593613D03*
X593658Y1021954D03*
X604405Y1034870D03*
X591898Y1035011D03*
X606434Y1041904D03*
X603682Y1053457D03*
X590957Y1105091D03*
Y1117691D03*
Y1130291D03*
Y1155491D03*
Y1142891D03*
Y1168091D03*
Y1180691D03*
X594183Y1220068D03*
X593519Y1224472D03*
X592885Y1229402D03*
X592634Y1234921D03*
X592978Y1514812D03*
X591487Y1501687D03*
X591481Y1509313D03*
X591858Y1523542D03*
X595809Y1532133D03*
X591872Y1518071D03*
X598800Y1546400D03*
X595809Y1546214D03*
X591809Y1542407D03*
X615087Y53597D03*
X605899Y80384D03*
Y82984D03*
Y77784D03*
Y75184D03*
X608453Y92849D03*
X605899Y85584D03*
X610999Y90615D03*
X615370Y95236D03*
X615320Y99961D03*
X605437Y95236D03*
X615413Y103037D03*
X605437Y102323D03*
X605689Y109410D03*
Y116496D03*
X615547D03*
Y109410D03*
X605861Y124576D03*
X615547Y130670D03*
Y123583D03*
X606914Y130670D03*
X606909Y137756D03*
X612138D03*
X620727Y162368D03*
X614182Y210478D03*
Y215478D03*
Y212978D03*
Y207978D03*
Y223726D03*
Y226226D03*
Y231226D03*
Y228726D03*
X617511Y264180D03*
X620011D03*
X617436Y258880D03*
X617728Y293796D03*
X620228D03*
X608274Y390223D03*
X605778Y391001D03*
X608274Y395179D03*
Y404396D03*
Y409352D03*
X605778Y405174D03*
Y394401D03*
Y408574D03*
X608274Y418569D03*
Y423525D03*
X605778Y422747D03*
Y419347D03*
X608274Y432743D03*
Y437699D03*
X605778Y433521D03*
Y436921D03*
X607789Y453682D03*
X606026Y455921D03*
X608274Y489895D03*
Y480677D03*
Y475721D03*
X605778Y479899D03*
Y490673D03*
Y476499D03*
X608274Y494851D03*
X605778Y494073D03*
X608274Y519855D03*
X605778Y520633D03*
Y524033D03*
X608274Y538984D03*
Y534028D03*
Y524811D03*
X605778Y534806D03*
Y538206D03*
X614461Y555234D03*
X614176Y562003D03*
X609472Y634946D03*
X612489Y941024D03*
X609133Y941137D03*
X605733D03*
X608965Y966414D03*
X616923Y988813D03*
X608923D03*
X616923Y997860D03*
X608923D03*
X612923D03*
X618878Y1011914D03*
X620151Y1040363D03*
X621479Y1030482D03*
X607993Y1036920D03*
X619086Y1056453D03*
X620715Y1046785D03*
X610780Y1051037D03*
X617634Y1049283D03*
X617894Y1043955D03*
X612955Y1062941D03*
X622736Y1151870D03*
Y1159350D03*
X613738Y1546507D03*
X612000Y1644980D03*
X633248Y44884D03*
X624234Y74793D03*
Y82593D03*
Y85193D03*
Y77393D03*
Y79993D03*
X636830Y94017D03*
X628830D03*
X632830D03*
X632559Y101701D03*
X624278Y92874D03*
X632559Y98551D03*
X632958Y110445D03*
X623547Y109410D03*
Y116496D03*
X632958Y115401D03*
X623547Y102323D03*
X635454Y114623D03*
Y111223D03*
X636109Y103783D03*
X626305Y104249D03*
Y107649D03*
X635454Y128796D03*
X632958Y124618D03*
X623547Y123583D03*
Y130670D03*
X632958Y129574D03*
X635454Y125396D03*
X623547Y137756D03*
X630871Y147540D03*
X634643Y141247D03*
X639490Y148277D03*
X630871Y151540D03*
X625927Y162368D03*
X623327D03*
X633027Y165393D03*
Y162793D03*
Y170493D03*
Y167993D03*
X639951Y177616D03*
X632024Y181426D03*
X635235Y181366D03*
X634521Y191941D03*
X634388Y188727D03*
X632232Y184221D03*
X634849Y184012D03*
X628710Y211695D03*
Y208695D03*
X631510D03*
X624638Y208213D03*
X636268Y211359D03*
Y213859D03*
X631210Y211695D03*
X624638Y213213D03*
Y210713D03*
Y231461D03*
X636300Y222212D03*
Y224712D03*
X632607Y229286D03*
X624638Y223661D03*
X631145Y226141D03*
X624638Y226461D03*
X628345Y226141D03*
X624638Y228961D03*
Y215713D03*
X633588Y236611D03*
X631088D03*
X632607Y231786D03*
X628588Y236611D03*
X630790Y248891D03*
X633290D03*
X628290D03*
X636215Y256535D03*
X639974Y265896D03*
X634887Y265701D03*
X629205Y267526D03*
X626405D03*
X631705D03*
X629205Y270026D03*
X626405D03*
X631705D03*
X636522Y281716D03*
X631042Y288190D03*
Y285690D03*
X625742Y288190D03*
X628242Y285690D03*
X625742D03*
X628242Y288190D03*
X635268Y290755D03*
X634455Y389154D03*
Y396240D03*
Y403327D03*
Y410413D03*
Y417500D03*
Y424587D03*
Y431673D03*
Y438760D03*
Y445847D03*
Y467539D03*
Y474626D03*
Y488799D03*
Y481713D03*
Y495886D03*
Y511673D03*
Y518760D03*
Y525847D03*
Y532933D03*
Y540020D03*
Y547106D03*
X632009Y541863D03*
Y545263D03*
X630201Y553407D03*
X632701D03*
X630201Y550907D03*
X632701D03*
X634185Y569426D03*
X634471Y566929D03*
X628425Y572070D03*
X629772Y569928D03*
X632119Y570962D03*
X631862Y568475D03*
X633736Y602197D03*
X634200Y595108D03*
X622270Y864781D03*
X621592Y1033862D03*
X626476Y1155610D03*
X636015Y1460782D03*
X627354Y1461182D03*
X636015Y1465513D03*
X627354Y1465913D03*
Y1456451D03*
X636015Y1476136D03*
X627354Y1476536D03*
X636015Y1480867D03*
X627354Y1481267D03*
Y1471805D03*
X636015Y1470244D03*
X627354Y1487159D03*
X636015Y1485598D03*
Y1491490D03*
X627354Y1491890D03*
X636015Y1496221D03*
X627354Y1496621D03*
Y1507245D03*
Y1511976D03*
X636015Y1511576D03*
X627354Y1502514D03*
X636015Y1500952D03*
Y1506845D03*
Y1516307D03*
X627354Y1558813D03*
X636015Y1563144D03*
X627354Y1563544D03*
X621727Y1556800D03*
X636015Y1567875D03*
X627354Y1568275D03*
Y1574167D03*
X636015Y1572606D03*
Y1578498D03*
X627354Y1578898D03*
X636015Y1593853D03*
X627354Y1594253D03*
X636015Y1583229D03*
X627354Y1583629D03*
Y1589522D03*
X636015Y1587960D03*
X627354Y1604876D03*
X636015Y1603315D03*
Y1598584D03*
X627354Y1598984D03*
X636015Y1609207D03*
X627354Y1609607D03*
X636015Y1618669D03*
Y1613938D03*
X627354Y1614338D03*
X632000Y1644980D03*
X645907Y76140D03*
Y84140D03*
Y80140D03*
X648655Y76587D03*
Y72615D03*
X640839Y94017D03*
X650094Y100625D03*
X643113Y97475D03*
X643360Y117557D03*
X637950Y110445D03*
Y115401D03*
X648352Y117557D03*
X651276Y103621D03*
X640109Y103783D03*
X643044Y106186D03*
X645856Y118335D03*
X643360Y122513D03*
Y131731D03*
X637950Y124618D03*
Y129574D03*
X648352Y122513D03*
Y131731D03*
X645856Y132509D03*
Y121735D03*
X646451Y146461D03*
X643360Y136687D03*
X648352D03*
X645856Y135909D03*
X650673Y141247D03*
X655160Y143518D03*
X642110Y143740D03*
X654260Y152373D03*
X645353Y152367D03*
X647053Y180572D03*
X651736Y180527D03*
X640532Y172190D03*
X638030Y181009D03*
X643205Y168697D03*
X651691Y185121D03*
X647053Y185165D03*
X641021Y184619D03*
X644293Y191941D03*
X652347Y192490D03*
X643001Y206760D03*
X646302Y206767D03*
X651302D03*
X648802D03*
X639971Y213132D03*
X648932Y221708D03*
X647547Y228221D03*
X645847Y224421D03*
X647547Y231021D03*
X646432Y221708D03*
X651432D03*
X639971Y215632D03*
X650598Y236189D03*
X648098D03*
X653098D03*
X644215Y256535D03*
X653039Y248765D03*
X650539D03*
X648039D03*
X640215Y256303D03*
X644990Y266114D03*
X645245Y279208D03*
X649349Y281307D03*
X650736Y268195D03*
X653536Y270695D03*
Y268195D03*
X650736Y270695D03*
X648236D03*
Y268195D03*
X642463Y281982D03*
X651339Y290845D03*
Y293645D03*
X653839D03*
X639268Y290755D03*
X643268D03*
X653839Y288345D03*
Y290845D03*
X651339Y288345D03*
X642255Y389154D03*
X649074D03*
X642255Y396240D03*
X643534Y404911D03*
X647604Y396240D03*
X642488Y412571D03*
X652381Y414823D03*
X651689Y422864D03*
X643675Y426299D03*
X651759Y429832D03*
X651364Y436447D03*
X653399Y447953D03*
X643986Y445847D03*
X642255Y467539D03*
X652566D03*
X642255Y474626D03*
X651308Y472772D03*
X652042Y487711D03*
X652155Y479104D03*
X642516Y480828D03*
X644466Y498834D03*
X652566Y495886D03*
X647915Y516841D03*
X651166Y510565D03*
X642255Y518760D03*
Y511673D03*
Y525847D03*
X642862Y550123D03*
X642740Y552872D03*
X642414Y545528D03*
X644494Y572334D03*
X642185Y562443D03*
X643953Y560675D03*
X642726Y574102D03*
X651149Y577716D03*
X648211Y602400D03*
Y598400D03*
Y594400D03*
Y606400D03*
Y614400D03*
Y610400D03*
X647361Y653161D03*
X648352Y645467D03*
X650958Y668153D03*
Y677843D03*
X653338Y1465513D03*
X644677Y1461182D03*
Y1456451D03*
Y1465913D03*
X653338Y1460782D03*
X644677Y1476536D03*
Y1471805D03*
X653338Y1480867D03*
Y1470244D03*
Y1476136D03*
X644677Y1481267D03*
X653338Y1491490D03*
X644677Y1496621D03*
Y1491890D03*
Y1487159D03*
X653338Y1496221D03*
Y1485598D03*
X644677Y1511976D03*
X653338Y1511576D03*
Y1500952D03*
Y1506845D03*
X644677Y1502514D03*
Y1507245D03*
X653338Y1516307D03*
X644677Y1558813D03*
X653338Y1563144D03*
X644677Y1563544D03*
X653338Y1572606D03*
Y1578498D03*
X644677Y1578898D03*
Y1574167D03*
X653338Y1567875D03*
X644677Y1568275D03*
X653338Y1587960D03*
Y1593853D03*
X644677Y1594253D03*
Y1589522D03*
X653338Y1583229D03*
X644677Y1583629D03*
X653338Y1609207D03*
X644677Y1598984D03*
Y1604876D03*
Y1609607D03*
X653338Y1603315D03*
Y1598584D03*
Y1613938D03*
X644677Y1614338D03*
X653338Y1618669D03*
X652000Y1644980D03*
X668649Y60922D03*
X666209Y57297D03*
X662935Y60513D03*
X665795Y60438D03*
X657507Y58013D03*
X656560Y68581D03*
X671476Y86012D03*
X656573Y80581D03*
X665423Y96853D03*
X660678Y91951D03*
X660703Y88801D03*
X663620Y94351D03*
X667569Y94279D03*
X663063Y85731D03*
X666617Y86046D03*
X658756Y103621D03*
X659282Y117261D03*
X666813Y113394D03*
X669462Y110784D03*
X666813Y116594D03*
X654467Y112083D03*
X669056Y133298D03*
X666813Y119594D03*
X667247Y124283D03*
X672313Y124879D03*
X665654Y161306D03*
X657410Y152562D03*
X662905Y157370D03*
X666989Y172665D03*
Y180665D03*
Y176665D03*
Y168665D03*
X658275Y172665D03*
X658212Y178560D03*
X658102Y183834D03*
X655459Y192421D03*
X659088Y186629D03*
X657622Y190185D03*
X658392Y200864D03*
X666989Y196665D03*
Y192665D03*
X667102Y186778D03*
X667021Y200864D03*
Y212864D03*
Y204864D03*
Y208864D03*
X658481Y212455D03*
X658415Y207037D03*
X667021Y221864D03*
Y216864D03*
X655782Y221642D03*
X662662Y219379D03*
X663290Y228631D03*
X668778Y252371D03*
X668886Y248371D03*
X657196Y265897D03*
X659696D03*
X660366Y389154D03*
X667666Y389153D03*
X670066Y390995D03*
X661761Y382109D03*
X660366Y403327D03*
Y410413D03*
X665166Y396240D03*
X667666D03*
X665166Y403327D03*
X667666Y403326D03*
X665166Y410413D03*
X667666D03*
X660366Y396240D03*
X670066Y405168D03*
X662766Y398082D03*
X670066Y408568D03*
Y394395D03*
X662766Y401482D03*
X667666Y417499D03*
X665166Y424586D03*
X667666D03*
X660366Y417500D03*
Y424586D03*
X665166Y417500D03*
X670066Y422741D03*
Y419341D03*
X662766Y415655D03*
Y426428D03*
Y412255D03*
X665166Y431673D03*
Y438760D03*
X667666D03*
Y431673D03*
X660366D03*
Y438760D03*
X662766Y440602D03*
X670066Y433515D03*
X662766Y429828D03*
X670066Y436915D03*
X665166Y445847D03*
X660366D03*
X662766Y444002D03*
X667666Y467539D03*
X660366D03*
X665166Y474626D03*
X667666D03*
X660366D03*
X670066Y469381D03*
Y472781D03*
X660366Y488799D03*
X665166D03*
X667666D03*
Y481712D03*
X665166D03*
X660366Y481713D03*
X662766Y476468D03*
Y490641D03*
X670066Y483554D03*
Y486954D03*
X662766Y479868D03*
X665166Y495886D03*
X660366D03*
X662766Y494041D03*
X667666Y518760D03*
X665166D03*
X667666Y511673D03*
X660366D03*
Y518760D03*
X670066Y516915D03*
X662766Y520602D03*
Y524002D03*
X670066Y513515D03*
X667666Y532933D03*
X665166D03*
Y540020D03*
Y525846D03*
X667666D03*
X660366Y525847D03*
Y532933D03*
Y540020D03*
X670066Y527688D03*
X662766Y534775D03*
X670066Y531088D03*
X662766Y538175D03*
X660366Y554193D03*
Y547106D03*
X661760Y551683D03*
X660826Y570414D03*
Y567914D03*
Y565414D03*
X669546Y560500D03*
X661760Y561420D03*
Y558917D03*
X660826Y575414D03*
Y572914D03*
X657581Y577937D03*
X660366Y602205D03*
Y595118D03*
X660586Y606929D03*
X665086Y604567D03*
X665586Y595500D03*
X660827Y612592D03*
X666244Y610072D03*
X660546Y618400D03*
X666180Y616317D03*
X665643Y646055D03*
X658233Y646449D03*
X658064Y650119D03*
X655752Y668885D03*
X661776Y662981D03*
X657967D03*
X662092Y666275D03*
X656157Y691851D03*
X659209D03*
X661768Y705043D03*
X661018Y707592D03*
X662000Y1456451D03*
Y1465913D03*
Y1461182D03*
Y1481267D03*
Y1476536D03*
Y1471805D03*
Y1496621D03*
Y1491890D03*
Y1487159D03*
Y1511976D03*
Y1502514D03*
Y1507245D03*
Y1563544D03*
Y1558813D03*
Y1568275D03*
Y1578898D03*
Y1574167D03*
Y1594253D03*
Y1589522D03*
Y1583629D03*
Y1598984D03*
Y1604876D03*
Y1609607D03*
Y1614338D03*
X679031Y102249D03*
X688399Y97667D03*
X671476Y94374D03*
X682048Y109172D03*
X685048D03*
X684055Y106495D03*
X678782Y116594D03*
X684055Y102495D03*
X677756Y110784D03*
X672756D03*
X677056Y133298D03*
X678782Y119594D03*
X682316Y125107D03*
X677335Y124663D03*
X671203Y134579D03*
X683789Y146012D03*
X685695Y141228D03*
X683789Y142862D03*
X684830Y148717D03*
X678679Y138838D03*
X672331Y195176D03*
X674831D03*
X677331D03*
X676950Y198883D03*
X680131Y195176D03*
X672191Y203393D03*
X676950Y201683D03*
X674691Y203393D03*
X678379Y206838D03*
X680879D03*
X674870Y218085D03*
X681383Y219470D03*
Y216970D03*
X678670Y216385D03*
X681383Y221970D03*
X681449Y226320D03*
X672070Y218085D03*
X684410Y228646D03*
X680375Y238589D03*
X683341Y236121D03*
X683367Y232971D03*
X677397Y249108D03*
X680017Y244571D03*
X683260Y253198D03*
X686012Y339795D03*
X682857Y339477D03*
X687055Y376456D03*
X685353Y392718D03*
X672466Y389153D03*
Y410413D03*
X685353Y408718D03*
Y400718D03*
Y404718D03*
X672466Y396240D03*
Y403326D03*
X685353Y396718D03*
X672466Y424586D03*
Y417499D03*
X685353Y412718D03*
X672466Y438760D03*
Y431673D03*
X678461Y455981D03*
X672466Y467539D03*
Y474626D03*
X675237Y465611D03*
X672466Y488799D03*
Y481712D03*
Y518760D03*
Y511673D03*
Y525846D03*
Y532933D03*
X682586Y530000D03*
X681586Y555000D03*
X681011Y543925D03*
X682086Y540500D03*
X681086Y547075D03*
X681286Y549800D03*
X680586Y568000D03*
X681126Y558800D03*
X681190Y562800D03*
X679322Y1461182D03*
Y1456451D03*
Y1465913D03*
X670661Y1460782D03*
Y1465513D03*
Y1470244D03*
Y1476136D03*
X679322Y1481267D03*
Y1476536D03*
Y1471805D03*
X670661Y1480867D03*
X679322Y1487159D03*
X670661Y1496221D03*
Y1485598D03*
Y1491490D03*
X679322Y1496621D03*
Y1491890D03*
X670661Y1500952D03*
Y1506845D03*
X679322Y1511976D03*
Y1502514D03*
Y1507245D03*
X670661Y1511576D03*
Y1516307D03*
X679322Y1558813D03*
X670661Y1563144D03*
X679322Y1563544D03*
Y1578898D03*
Y1574167D03*
Y1568275D03*
X670661Y1572606D03*
Y1578498D03*
Y1567875D03*
X679322Y1583629D03*
X670661Y1587960D03*
Y1593853D03*
Y1583229D03*
X679322Y1594253D03*
Y1589522D03*
Y1604876D03*
Y1609607D03*
X670661Y1603315D03*
Y1598584D03*
Y1609207D03*
X679322Y1598984D03*
Y1614338D03*
X670661Y1618669D03*
Y1613938D03*
X672000Y1644980D03*
X690073Y44662D03*
X697387Y53619D03*
X696859Y103411D03*
X697253Y97667D03*
X692649Y95111D03*
X695099Y109410D03*
X687799Y116497D03*
X692599D03*
X695099D03*
X699799Y116496D03*
Y109410D03*
Y102323D03*
X697499Y114655D03*
Y111255D03*
X697018Y106561D03*
X687799Y123584D03*
X695099Y123583D03*
X692599Y123584D03*
X687799Y130670D03*
X692599D03*
X695099D03*
X699799Y123583D03*
Y130670D03*
X690199Y132515D03*
X697499Y125428D03*
Y128828D03*
X690199Y121742D03*
Y118342D03*
X687799Y137757D03*
X692599D03*
X699799Y137756D03*
X690199Y135915D03*
X690930Y143762D03*
X688583Y150847D03*
X691396Y199248D03*
X687378Y195176D03*
X689878D03*
X694396Y199248D03*
X694878Y195176D03*
X692378D03*
X696331Y213539D03*
X691396Y201748D03*
X689232Y206806D03*
X687459Y210509D03*
X689959D03*
X694396Y202048D03*
X691732Y206806D03*
X697996Y230117D03*
X689151Y230556D03*
X693406Y227824D03*
X698012Y238714D03*
X689777Y238689D03*
X690551Y247292D03*
X694012Y238714D03*
X688136Y242078D03*
X693493Y246874D03*
X695713Y244297D03*
X690504Y253198D03*
X689486Y339583D03*
X702448Y546712D03*
Y542712D03*
X700164Y636842D03*
X699188Y656321D03*
X698936Y678462D03*
X702086D03*
X692478Y730641D03*
X702691Y766471D03*
Y753471D03*
Y762971D03*
Y756971D03*
X692356Y764614D03*
X691991Y759581D03*
X702677Y771159D03*
Y780659D03*
Y775159D03*
X692155Y778974D03*
X692221Y773449D03*
X702677Y784659D03*
X690449Y814406D03*
X696645Y1461183D03*
Y1456452D03*
Y1465914D03*
X687984Y1460782D03*
Y1465513D03*
Y1470244D03*
Y1476136D03*
X696645Y1481268D03*
Y1471806D03*
Y1476537D03*
X687984Y1480867D03*
X696645Y1491891D03*
X687984Y1496221D03*
Y1485598D03*
Y1491490D03*
X696645Y1496622D03*
Y1487160D03*
Y1511977D03*
Y1502515D03*
Y1507246D03*
X687984Y1511576D03*
Y1500952D03*
Y1506845D03*
Y1516307D03*
X696645Y1558813D03*
Y1563544D03*
X687984Y1563144D03*
X696645Y1574167D03*
Y1578898D03*
X687984Y1572606D03*
Y1578498D03*
X696645Y1568275D03*
X687984Y1567875D03*
Y1583229D03*
X696645Y1589522D03*
Y1594253D03*
X687984Y1587960D03*
Y1593853D03*
X696645Y1583629D03*
Y1598984D03*
Y1609607D03*
X687984Y1603315D03*
Y1598584D03*
Y1609207D03*
X696645Y1604876D03*
X687984Y1613938D03*
X696645Y1614338D03*
X687984Y1618669D03*
X692000Y1644980D03*
X718503Y-38525D03*
X718500Y-33320D03*
Y-30420D03*
X718488Y-36010D03*
Y-27642D03*
X718503Y-25127D03*
X717387Y53619D03*
X708261Y82984D03*
Y80384D03*
Y77784D03*
Y75184D03*
X710815Y92849D03*
X708261Y85584D03*
X708049Y90650D03*
X713361Y90615D03*
X717732Y95236D03*
X717682Y99961D03*
X707799Y95236D03*
X717775Y103037D03*
X707799Y102323D03*
X708051Y109410D03*
Y116496D03*
X717909D03*
Y109410D03*
X708223Y124576D03*
X717909Y130670D03*
Y123583D03*
X709276Y130670D03*
X714500Y137756D03*
X709271D03*
X716544Y215478D03*
Y210478D03*
Y207978D03*
Y212978D03*
Y228726D03*
Y231226D03*
Y226226D03*
Y223726D03*
X718338Y305272D03*
X712692Y356779D03*
X717105Y410964D03*
X717420Y404334D03*
X713162Y434493D03*
X709781Y442956D03*
X720996Y442856D03*
X711598Y438323D03*
X711764Y449873D03*
X719051Y458455D03*
X719612Y451108D03*
X710643Y456335D03*
X711764Y445873D03*
X706211Y465874D03*
X718691Y465492D03*
Y472579D03*
X716191D03*
X711391D03*
X713791Y474424D03*
X716191Y479666D03*
X718691D03*
X711391D03*
Y486752D03*
X716191D03*
X718691D03*
X713791Y488597D03*
Y477824D03*
X711391Y493839D03*
X716191D03*
X713791Y491997D03*
X716191Y516713D03*
Y523800D03*
X718691D03*
X711391D03*
Y516713D03*
X718691D03*
Y509626D03*
X713791Y518558D03*
Y521958D03*
X718691Y530886D03*
X716191D03*
Y537973D03*
X711391Y530886D03*
Y537973D03*
X713791Y536131D03*
Y532731D03*
X711463Y546712D03*
X711391Y566752D03*
X718691Y559665D03*
Y566752D03*
X716191D03*
X713791Y571997D03*
Y568597D03*
X711391Y573839D03*
X718691D03*
X716191D03*
X711391Y588013D03*
X718691Y588012D03*
X716191Y588013D03*
X718691Y580926D03*
X716191D03*
X711391D03*
X713791Y582771D03*
Y586171D03*
X716191Y602186D03*
X711391D03*
X718691Y602185D03*
Y595099D03*
X711391D03*
X716191D03*
X713791Y596944D03*
Y600344D03*
X711391Y609272D03*
X716191D03*
X718691D03*
X716191Y616359D03*
X711391D03*
X713791Y611117D03*
Y614517D03*
X704364Y618288D03*
X706070Y638125D03*
X716656Y646429D03*
X711328Y653821D03*
X703669Y665140D03*
X705390Y655789D03*
X705776Y678519D03*
X716350Y699477D03*
X703604Y699653D03*
X713200Y699676D03*
X716623Y702463D03*
X703600Y702212D03*
X703680Y697094D03*
X715802Y706446D03*
X710196Y707562D03*
X704446Y760611D03*
X713425Y786029D03*
X717434Y782500D03*
X710275Y786131D03*
X713222Y793312D03*
Y790812D03*
X712901Y821600D03*
X712000Y1644980D03*
X721756Y-38539D03*
X724781Y-37219D03*
X721741Y-36024D03*
Y-27628D03*
X721756Y-25113D03*
X724781Y-26433D03*
X726596Y74793D03*
Y77393D03*
Y79993D03*
Y85193D03*
Y82593D03*
X735192Y94017D03*
X731192D03*
X734921Y101701D03*
X726640Y92874D03*
X734921Y98551D03*
X725909Y102323D03*
Y116496D03*
Y109410D03*
X728667Y104249D03*
Y107649D03*
X725909Y130670D03*
Y123583D03*
Y137756D03*
X733233Y147540D03*
Y151540D03*
X728289Y162368D03*
X725689D03*
X734386Y181426D03*
X736750Y188727D03*
X734594Y184221D03*
X727000Y213213D03*
Y208213D03*
X733872Y208695D03*
X731072D03*
X733572Y211695D03*
X731072D03*
X727000Y210713D03*
Y228961D03*
X730707Y226141D03*
X727000Y226461D03*
X733507Y226141D03*
X727000Y223661D03*
X734969Y229286D03*
X727000Y231461D03*
Y215713D03*
X733450Y236611D03*
X730950D03*
X734969Y231786D03*
X733152Y248891D03*
X730652D03*
X722373Y264180D03*
X719873D03*
X719798Y258880D03*
X737249Y265701D03*
X731567Y267526D03*
X728767D03*
X734067D03*
Y270026D03*
X731567D03*
X728767D03*
X733404Y285690D03*
X720090Y293796D03*
X722590D03*
X728104Y288190D03*
X730604Y285690D03*
X728104D03*
X730604Y288190D03*
X733404D03*
X723404Y379657D03*
X731511Y390500D03*
X734606Y379562D03*
X721900Y384500D03*
X723440Y391496D03*
X734661Y393633D03*
X731511Y381113D03*
X722097Y410394D03*
Y403307D03*
X723440Y398583D03*
X723031Y440098D03*
Y437598D03*
Y435098D03*
Y432598D03*
Y430098D03*
X732035Y442606D03*
X723491Y458406D03*
Y451319D03*
X722097Y453881D03*
X731952Y446606D03*
X722097Y446595D03*
X723491Y465492D03*
X731291Y466027D03*
X723315Y462264D03*
X723491Y472579D03*
X731433Y475262D03*
X721091Y470737D03*
Y467337D03*
X732959Y463479D03*
X733430Y467367D03*
X731433Y489435D03*
Y482666D03*
X723491Y479665D03*
Y486752D03*
X721091Y484910D03*
Y481510D03*
X723491Y493839D03*
X731249Y495088D03*
X724362Y504731D03*
X723491Y523799D03*
Y516713D03*
Y509626D03*
X731984Y514608D03*
X731906Y522134D03*
X731291Y509626D03*
X721091Y514871D03*
Y511471D03*
X723491Y530886D03*
Y537973D03*
X732549Y529136D03*
X732388Y535677D03*
X721091Y525644D03*
Y529044D03*
X723491Y566752D03*
Y559665D03*
X731291D03*
X731672Y565574D03*
X721091Y561510D03*
Y564910D03*
X723491Y573839D03*
Y588012D03*
Y580926D03*
X731319Y574338D03*
X721091Y579084D03*
Y575684D03*
X723491Y595099D03*
Y602185D03*
X721091Y593257D03*
Y604030D03*
Y589857D03*
X723491Y609272D03*
Y616358D03*
X731418D03*
X721091Y607430D03*
X734819Y646429D03*
X722473Y693718D03*
X723656Y705858D03*
X720985Y711658D03*
X725667Y732161D03*
X723177Y728219D03*
X721218Y742131D03*
X721163Y738981D03*
X720271Y782481D03*
X733000Y816000D03*
X730880Y828924D03*
X733680Y828977D03*
X732713Y853890D03*
X722600Y869600D03*
X725318Y890354D03*
X728503Y891692D03*
X736452Y890548D03*
X728692Y886653D03*
X724707Y893143D03*
X719661Y904900D03*
X722789Y927095D03*
X720373Y940310D03*
X722400Y942500D03*
X725194Y942073D03*
X720271Y931730D03*
X732306Y942682D03*
X724547Y958287D03*
X728846Y948331D03*
X733798Y950186D03*
X727116Y959326D03*
X732825Y1604100D03*
X736067Y1611892D03*
X729600Y1625165D03*
X732268Y1618260D03*
X732000Y1644980D03*
X736242Y5374D03*
X735555Y24773D03*
Y44773D03*
X748269Y84140D03*
Y76140D03*
Y80140D03*
X751017Y76587D03*
Y72615D03*
X743201Y94017D03*
X739192D03*
X752456Y100625D03*
X745475Y97475D03*
X737816Y114623D03*
X750714Y117557D03*
X745722D03*
X740312Y115401D03*
Y110445D03*
X735320D03*
Y115401D03*
X742471Y103783D03*
X737816Y111223D03*
X745406Y106186D03*
X738471Y103783D03*
X748218Y118335D03*
X745722Y131731D03*
Y122513D03*
X740312Y129574D03*
Y124618D03*
X735320D03*
Y129574D03*
X750714Y131731D03*
Y122513D03*
X737816Y128796D03*
X748218Y132509D03*
Y121735D03*
X737816Y125396D03*
X748218Y135909D03*
X750714Y136687D03*
X745722D03*
X748813Y146461D03*
X737005Y141247D03*
X744472Y143740D03*
X741852Y148277D03*
X747715Y152367D03*
X735389Y165393D03*
Y162793D03*
X749415Y180572D03*
X735389Y170493D03*
Y167993D03*
X740392Y181009D03*
X737597Y181366D03*
X745567Y168697D03*
X742894Y172190D03*
X742313Y177616D03*
X749415Y185165D03*
X743383Y184619D03*
X736883Y191941D03*
X746655D03*
X737211Y184012D03*
X750667Y192300D03*
X745363Y206760D03*
X751164Y206767D03*
X748664D03*
X738630Y213859D03*
Y211359D03*
X742333Y213132D03*
X738662Y224712D03*
Y222212D03*
X749909Y228221D03*
Y231021D03*
X751294Y221708D03*
X748209Y224421D03*
X748794Y221708D03*
X742333Y215632D03*
X735950Y236611D03*
X750460Y236189D03*
X735652Y248891D03*
X738577Y256535D03*
X746577D03*
X750401Y248765D03*
X742577Y256303D03*
X747352Y266114D03*
X742336Y265896D03*
X747607Y279208D03*
X751711Y281307D03*
X750598Y268195D03*
Y270695D03*
X744825Y281982D03*
X738884Y281716D03*
X741630Y290755D03*
X737630D03*
X745630D03*
X741051Y316389D03*
X741161Y381500D03*
X749444Y393858D03*
X749606Y384410D03*
X752785Y382047D03*
X749586Y410394D03*
Y403307D03*
X753086Y403500D03*
X751086Y398583D03*
X741259Y439963D03*
X741381Y430760D03*
X741402Y433570D03*
X741218Y437072D03*
X749539Y438269D03*
Y440869D03*
Y435669D03*
Y430469D03*
Y433069D03*
X741503Y443180D03*
X741523Y454744D03*
X741465Y452018D03*
X749402Y458406D03*
X735599Y449961D03*
X739316Y458572D03*
X750393Y451677D03*
Y454177D03*
X741602Y465492D03*
X741568Y460250D03*
X739333Y470136D03*
X749402Y465492D03*
X741602Y472579D03*
X749402D03*
X741072Y478958D03*
X741602Y486752D03*
X749402Y479665D03*
Y486752D03*
Y493839D03*
X741602D03*
X749402Y523799D03*
Y516713D03*
Y509626D03*
X741602D03*
Y516713D03*
X749402Y537973D03*
Y530886D03*
X738062Y537973D03*
X740542Y525483D03*
X740463Y532756D03*
X749402Y559665D03*
Y566752D03*
X741602Y559665D03*
Y566752D03*
X749402Y573839D03*
Y588012D03*
Y580925D03*
X741452Y579978D03*
X741602Y573839D03*
X749402Y602185D03*
Y595099D03*
Y609272D03*
Y616358D03*
X741666Y608117D03*
X744069Y746617D03*
X741992Y763480D03*
X742000Y768137D03*
X741000Y771100D03*
X743428Y772418D03*
X741993Y775909D03*
X735576Y861780D03*
X736000Y864266D03*
X738707Y987952D03*
X742407Y988452D03*
X745673Y1007009D03*
X743062Y1004460D03*
X742655Y1445733D03*
X749439Y1458777D03*
X751140Y1581335D03*
X740640Y1586885D03*
X747140Y1581335D03*
X749786Y1590517D03*
X738775Y1597866D03*
X737892Y1602340D03*
X749704Y1608631D03*
X748924Y1617709D03*
X735878Y1617010D03*
X747590Y1627871D03*
X744924Y1617709D03*
X743331Y1627871D03*
X741705Y1622015D03*
X738325Y1634485D03*
X755145Y3000D03*
X765847Y55513D03*
X762697D03*
X758922Y68581D03*
X765297Y60513D03*
X758935Y80581D03*
X763040Y91951D03*
X763065Y88801D03*
X765982Y94351D03*
X769931Y94279D03*
X765425Y85731D03*
X762065Y117040D03*
X753638Y103621D03*
X756829Y112083D03*
X761118Y103621D03*
X769609Y124283D03*
X753035Y141247D03*
X757522Y143518D03*
X756622Y152373D03*
X759772Y152562D03*
X765267Y157370D03*
X754098Y180527D03*
X760637Y172665D03*
X760464Y183834D03*
X760574Y178560D03*
X757821Y192421D03*
X754053Y185121D03*
X761450Y186629D03*
X754709Y192490D03*
X759984Y190185D03*
X760754Y200864D03*
X753182Y198671D03*
X753664Y206767D03*
X769383Y208864D03*
X760843Y212455D03*
X760777Y207037D03*
X753794Y221708D03*
X758144Y221642D03*
X765024Y219379D03*
X763653Y224536D03*
X752960Y236189D03*
X755460D03*
X755401Y248765D03*
X752901D03*
X753098Y268195D03*
X755898D03*
X753098Y270695D03*
X755898D03*
X759558Y265897D03*
X762058D03*
X756201Y288345D03*
Y290845D03*
X753701Y288345D03*
Y290845D03*
Y293645D03*
X756201D03*
X760407Y324494D03*
X767099Y316731D03*
X769349Y324518D03*
X759029Y328867D03*
X763898Y342319D03*
X759029Y332017D03*
X754805Y339559D03*
X759624Y353961D03*
X756086Y377912D03*
X766344D03*
Y393924D03*
Y389912D03*
Y385912D03*
X758038Y381143D03*
X755086Y391496D03*
X756086Y386500D03*
X766344Y381912D03*
Y409924D03*
Y405924D03*
Y401924D03*
X752341Y407148D03*
X756800Y403824D03*
X758381Y395391D03*
X756174Y397912D03*
X755086Y409000D03*
X766344Y397912D03*
X752339Y438269D03*
Y433069D03*
Y430469D03*
Y435669D03*
Y440869D03*
X759543Y445787D03*
X755593Y445908D03*
X752893Y451677D03*
Y454177D03*
X752097Y460218D03*
Y463618D03*
X755035Y1443524D03*
X765713Y1437365D03*
X760398Y1440276D03*
X766433Y1583713D03*
X755187Y1580821D03*
X759802Y1590864D03*
X763542Y1590186D03*
X767310Y1599164D03*
X768361Y1610083D03*
X756358Y1616917D03*
X752150Y1627871D03*
X762671Y1619367D03*
X756358Y1613767D03*
X762776Y1629415D03*
X752000Y1644980D03*
X775145Y3000D03*
X771011Y60922D03*
X768157Y60438D03*
X773838Y86012D03*
X781393Y102249D03*
X767929Y96890D03*
X773838Y94374D03*
X768979Y86046D03*
X771824Y110784D03*
X777393Y102249D03*
X773393D03*
X769175Y113394D03*
X781144Y116594D03*
X769175D03*
X775118Y110784D03*
X780118D03*
X779418Y133298D03*
X771960Y130898D03*
X781144Y119594D03*
X769175D03*
X784678Y125107D03*
X779697Y124663D03*
X774675Y124879D03*
X773565Y134579D03*
X781041Y138838D03*
X768016Y161306D03*
X769351Y172665D03*
Y180665D03*
Y176665D03*
Y168665D03*
X779693Y195176D03*
X779312Y198883D03*
X777193Y195176D03*
X782493D03*
X774693D03*
X769351Y192665D03*
X769464Y186778D03*
X780741Y206838D03*
X783241D03*
X777053Y203393D03*
X779312Y201683D03*
X774553Y203393D03*
X769383Y200864D03*
Y212864D03*
Y204864D03*
Y221864D03*
Y216864D03*
X774432Y218085D03*
X777232D03*
X783745Y216970D03*
X781032Y216385D03*
X783745Y221970D03*
X783811Y226320D03*
X783745Y219470D03*
X782737Y238589D03*
X782379Y244571D03*
X779759Y249108D03*
X771140Y252371D03*
Y248371D03*
X772165Y314890D03*
X780968Y303839D03*
X784118Y303962D03*
X771941Y311740D03*
X776943Y321649D03*
X772990Y336324D03*
X772162Y332584D03*
X777569Y353506D03*
X778502Y348015D03*
X772859Y347937D03*
X774419Y353470D03*
X784902Y428653D03*
X778985Y442498D03*
X778881Y446510D03*
X779029Y450510D03*
X780575Y471484D03*
X775584Y466528D03*
X780575D03*
X775583Y471484D03*
X778079Y467306D03*
Y470706D03*
X780575Y480701D03*
X775583D03*
Y485657D03*
X780575D03*
X778079Y481479D03*
Y484879D03*
X780575Y510661D03*
X775583Y515617D03*
X780575D03*
X775583Y510661D03*
X778079Y514839D03*
Y511439D03*
X780575Y524835D03*
Y529791D03*
X775583Y524835D03*
Y529791D03*
X778079Y529013D03*
Y525613D03*
X775746Y539315D03*
X777708Y553287D03*
X781429Y545017D03*
X780575Y560701D03*
Y565657D03*
X775583Y560701D03*
Y565657D03*
X778079Y561479D03*
Y564879D03*
X775583Y579830D03*
X780575D03*
X775583Y574874D03*
X780575D03*
X775583Y589047D03*
X780575D03*
X778079Y575652D03*
Y579052D03*
X780575Y594003D03*
X775583D03*
Y603221D03*
X780575D03*
X778079Y589825D03*
Y593225D03*
Y603999D03*
X775583Y608177D03*
X780575D03*
X778079Y607399D03*
X778860Y626912D03*
X778205Y622912D03*
X783694Y1410977D03*
X778685Y1416198D03*
X780162Y1412848D03*
X777749Y1431432D03*
X783469Y1424655D03*
X777114Y1442270D03*
X771557Y1446818D03*
X768910Y1437741D03*
X777749Y1435432D03*
Y1439432D03*
X777260Y1446237D03*
X778428Y1455156D03*
X777725Y1450193D03*
X783620Y1460108D03*
X768812Y1453306D03*
X777033Y1595215D03*
X781124Y1583553D03*
X781110Y1595254D03*
X781545Y1602835D03*
X774658Y1601012D03*
X777059Y1608982D03*
X784046Y1600438D03*
X778045Y1622545D03*
X782289Y1620109D03*
X773822Y1627418D03*
X778045Y1619395D03*
X778358Y1627418D03*
X771383Y1616917D03*
X772000Y1644980D03*
X791129Y4469D03*
X792490Y24773D03*
Y44773D03*
X799811Y53597D03*
X799221Y103411D03*
X799615Y97667D03*
X790761D03*
X795011Y95111D03*
X784410Y109172D03*
X787410D03*
X794961Y116497D03*
X797461D03*
X790161D03*
X786417Y106495D03*
X797461Y109410D03*
X799861Y114655D03*
Y111255D03*
X786417Y102495D03*
X799380Y106561D03*
X797461Y123583D03*
X794961Y123584D03*
X790161D03*
X794961Y130670D03*
X797461D03*
X790161D03*
X792561Y132515D03*
Y118342D03*
X799861Y128828D03*
X792561Y121742D03*
X799861Y125428D03*
X794961Y137757D03*
X790161D03*
X788057Y141228D03*
X786151Y146012D03*
X793221Y140296D03*
X792561Y135915D03*
X786151Y142862D03*
X793292Y143762D03*
X787192Y148717D03*
X790945Y150847D03*
X796758Y199248D03*
X797240Y195176D03*
X794740D03*
X789740D03*
X792240D03*
X793758Y199248D03*
X798693Y213539D03*
X794094Y206806D03*
X791594D03*
X789821Y210509D03*
X792321D03*
X793758Y201748D03*
X796758Y202048D03*
X800358Y230117D03*
X795768Y227824D03*
X791513Y230556D03*
X786772Y228646D03*
X792913Y247292D03*
X792139Y238689D03*
X785703Y236121D03*
X796374Y238714D03*
X790498Y242078D03*
X785729Y232971D03*
X795855Y246874D03*
X798075Y244297D03*
X785622Y253198D03*
X789722Y256394D03*
X788522Y290304D03*
X786461Y293028D03*
X790280Y287421D03*
X800155Y337368D03*
X800029Y333368D03*
X799937Y347340D03*
X797141Y350368D03*
X795445Y356950D03*
X792564Y406410D03*
X789581Y405011D03*
X793893Y409502D03*
X784586Y421000D03*
Y418500D03*
Y413500D03*
Y416000D03*
X784804Y425371D03*
X794173Y450510D03*
X802136Y448334D03*
X785985Y473640D03*
X790977D03*
X788481Y474418D03*
X785985Y487813D03*
X790977D03*
X785985Y478596D03*
X790977D03*
X788481Y477818D03*
Y488591D03*
X785985Y492769D03*
X790977D03*
X788481Y491991D03*
X790977Y517774D03*
Y522730D03*
X785985Y517774D03*
Y522730D03*
X788481Y518552D03*
Y521952D03*
X785985Y531947D03*
Y536903D03*
X790977Y531947D03*
Y536903D03*
X788481Y532725D03*
Y536125D03*
X796000Y553101D03*
X784665Y564843D03*
X790977Y567813D03*
X785985Y572769D03*
X790977D03*
X785985Y567813D03*
X788481Y571991D03*
Y568591D03*
X790977Y581987D03*
Y586943D03*
X785985Y581987D03*
Y586943D03*
X788481Y586165D03*
Y582765D03*
X790977Y601116D03*
X785985D03*
Y596160D03*
X790977D03*
X788481Y600338D03*
Y596938D03*
X790977Y615289D03*
Y610333D03*
X785985Y615289D03*
Y610333D03*
X788481Y614511D03*
Y611111D03*
X788600Y1006923D03*
X791686Y1025440D03*
X799631D03*
X795631D03*
X789050Y1026150D03*
X796338Y1138130D03*
X793842Y1143384D03*
X797160Y1146609D03*
X792277Y1173065D03*
X799020Y1175975D03*
X798353Y1172011D03*
X794716Y1186071D03*
X787887Y1174500D03*
X798542Y1188345D03*
X792382Y1191664D03*
X794533Y1195766D03*
X792183Y1334030D03*
Y1331230D03*
X789383Y1334030D03*
Y1331230D03*
X794983Y1334030D03*
Y1331230D03*
X793548Y1397690D03*
X794506Y1411307D03*
X795296Y1416995D03*
X792848Y1414718D03*
X793459Y1429165D03*
X789647Y1427518D03*
X788648Y1422044D03*
X785820Y1425993D03*
X798601Y1431673D03*
X793288Y1450918D03*
X793744Y1437159D03*
X786787Y1433800D03*
X787694Y1442749D03*
X800607Y1440760D03*
X793994Y1441499D03*
X799057Y1449158D03*
X797083Y1467883D03*
X799057Y1456016D03*
X794005Y1464178D03*
X786591Y1452803D03*
X793723Y1468071D03*
X799314Y1475693D03*
X797318Y1471242D03*
X787447Y1593586D03*
X791610Y1593708D03*
X793564Y1642682D03*
X810623Y77784D03*
Y82984D03*
Y80384D03*
Y75184D03*
X813177Y92849D03*
X810623Y85584D03*
X810411Y90650D03*
X815723Y90615D03*
X810161Y95236D03*
Y102323D03*
X810413Y109410D03*
Y116496D03*
X802161D03*
Y109410D03*
Y102323D03*
X810585Y124576D03*
X811638Y130670D03*
X802161D03*
Y123583D03*
X811633Y137756D03*
X802161D03*
X800374Y238714D03*
X805952Y301675D03*
X817456Y305368D03*
Y313368D03*
X809490Y305368D03*
X809466Y310604D03*
X801097Y325858D03*
X817100Y319600D03*
X809457Y330459D03*
X809490Y325368D03*
Y317368D03*
X809489Y313830D03*
X809490Y321368D03*
Y333368D03*
X804536Y441486D03*
X816177Y441442D03*
X813456Y441474D03*
X810749Y443045D03*
X802136Y452334D03*
X815840Y444091D03*
Y456060D03*
X810453Y453330D03*
X810406Y448214D03*
X810756Y471071D03*
Y468571D03*
X814580Y468806D03*
X814828Y472053D03*
X810756Y473571D03*
Y491118D03*
Y488618D03*
Y483618D03*
X816364Y486870D03*
X810756Y486118D03*
X813864Y486870D03*
X810756Y476071D03*
X815492Y732917D03*
X813902Y730738D03*
X813566Y744187D03*
X813678Y740979D03*
X813653Y746856D03*
X817584Y764219D03*
X818000Y797000D03*
X812661Y810032D03*
X817845Y817879D03*
X818500Y810135D03*
X813000Y805000D03*
X813548Y814000D03*
X812980Y824166D03*
X813009Y819734D03*
X815500Y824000D03*
X815863Y830097D03*
X816016Y838036D03*
X814299Y840877D03*
X813887Y835146D03*
X816037Y845578D03*
X813182Y852800D03*
X812440Y862306D03*
X814080Y864464D03*
X812575Y880834D03*
X814731Y889365D03*
X812219Y883586D03*
X812811Y908162D03*
X817884Y915425D03*
X803673Y1025440D03*
X809682Y1133284D03*
X803453Y1134729D03*
X814835D03*
X806835D03*
X809632Y1142666D03*
X806787Y1148000D03*
X817964Y1157404D03*
X811507Y1157544D03*
X815034Y1159455D03*
X809623Y1160168D03*
X810018Y1167768D03*
X815037D03*
X809393Y1187252D03*
X814160Y1178240D03*
X814170Y1185205D03*
X805212Y1180175D03*
X805519Y1187215D03*
X807487Y1193019D03*
X815487D03*
X811487D03*
X815455Y1201043D03*
X811485D03*
X807489D03*
X804452Y1199814D03*
X804458Y1193112D03*
X817446Y1210089D03*
X809027Y1219895D03*
X807020Y1217900D03*
X812302Y1223170D03*
X815149Y1226016D03*
X810148Y1374884D03*
X806148Y1383715D03*
Y1375208D03*
X800627Y1392748D03*
X810204Y1401661D03*
X806318D03*
X804654Y1404769D03*
X800703Y1426779D03*
X812901Y1432804D03*
X815901D03*
X810059Y1432778D03*
X812104Y1426483D03*
X809986Y1438785D03*
X812986D03*
X815986D03*
X809986Y1441485D03*
X812986D03*
X815986D03*
X812901Y1435504D03*
X815901D03*
X810001D03*
X806874Y1447457D03*
X812474D03*
X803057Y1449158D03*
X801057Y1447158D03*
X805569Y1441519D03*
X806874Y1452587D03*
Y1457717D03*
X812474D03*
X815096Y1464387D03*
X803057Y1456016D03*
X801057Y1458016D03*
X802684Y1465549D03*
X812009Y1473432D03*
Y1470432D03*
X815096Y1467387D03*
X812096Y1479587D03*
Y1476587D03*
X815096Y1473387D03*
Y1479587D03*
Y1476587D03*
Y1470387D03*
X801354Y1478681D03*
X807576Y1469584D03*
X804919Y1489247D03*
X811457Y1639797D03*
X819811Y53597D03*
X828958Y79993D03*
Y77393D03*
Y74793D03*
Y85193D03*
Y82593D03*
X829002Y92874D03*
X820094Y95236D03*
X820044Y99961D03*
X820137Y103037D03*
X820271Y116496D03*
Y109410D03*
X828271Y116496D03*
Y109410D03*
Y102323D03*
X831029Y104249D03*
Y107649D03*
X820271Y130670D03*
Y123583D03*
X828271Y130670D03*
Y123583D03*
X816637Y137756D03*
X828271D03*
X830651Y162368D03*
X828051D03*
X829362Y213213D03*
X818906Y207978D03*
Y212978D03*
Y215478D03*
Y210478D03*
X829362Y208213D03*
Y210713D03*
Y231461D03*
Y228961D03*
Y226461D03*
Y223661D03*
X818906Y228726D03*
Y231226D03*
Y226226D03*
Y223726D03*
X829362Y215713D03*
X822235Y264180D03*
X824735D03*
X822160Y258880D03*
X831129Y267526D03*
Y270026D03*
X824952Y293796D03*
X822452D03*
X830466Y285690D03*
Y288190D03*
X825792Y305225D03*
X822477Y309368D03*
X825971Y345101D03*
X829485D03*
X829381Y348036D03*
X822626Y348066D03*
X818840Y444091D03*
X825103Y430358D03*
Y435558D03*
Y432958D03*
X831378Y433086D03*
Y435686D03*
Y430486D03*
X824650Y446740D03*
X822040Y444091D03*
X818840Y456060D03*
X824650Y455034D03*
Y450034D03*
X826262Y462326D03*
Y459326D03*
X823529Y467189D03*
X817328Y472053D03*
X820810Y471243D03*
X817380Y468806D03*
X823544Y475061D03*
Y472561D03*
X820810Y473743D03*
X818973Y491258D03*
Y488758D03*
X822418Y485070D03*
Y482570D03*
X828918Y480580D03*
X831418D03*
X831057Y484036D03*
X828272Y535462D03*
X827291Y533100D03*
X830318Y674164D03*
X829496Y676793D03*
X823790Y713375D03*
X829784Y713939D03*
Y716589D03*
Y705489D03*
X823890Y703415D03*
X823670Y710542D03*
X823843Y732109D03*
X832284Y731216D03*
X824387Y726246D03*
X818307Y724144D03*
X821582Y727140D03*
X830484Y746701D03*
X819890Y736924D03*
X826484Y747127D03*
X827500Y750000D03*
X819788Y739634D03*
X830484Y738750D03*
X819993Y754109D03*
X817500Y760000D03*
X824500Y760500D03*
X830075Y769000D03*
X822151Y752283D03*
X824500Y756000D03*
X817365Y756827D03*
X820547Y780314D03*
X826925Y769000D03*
X820500Y777500D03*
X824500Y778500D03*
Y774000D03*
Y782500D03*
X826925Y787000D03*
X820500Y792000D03*
X830075Y787000D03*
X824500Y796500D03*
X824342Y792315D03*
X824500Y800500D03*
X818500Y814000D03*
X820432Y800529D03*
X826925Y805000D03*
X830075D03*
X824500Y814500D03*
X826925Y823000D03*
X830075D03*
X829946Y829788D03*
X829791Y839020D03*
X825721Y836666D03*
Y839816D03*
X830014Y833046D03*
X829757Y842672D03*
X822608Y848526D03*
X826165Y863000D03*
X819134Y863607D03*
X829000Y852000D03*
X822916Y852576D03*
X823540Y857956D03*
X831654Y864494D03*
X831583Y853454D03*
X822938Y863298D03*
X825686Y869496D03*
X823234Y867680D03*
X826209Y866052D03*
X823234Y870830D03*
X833194Y873561D03*
X827992Y874107D03*
X826797Y883756D03*
X825774Y895553D03*
X826070Y893014D03*
X817152Y896380D03*
X817139Y890330D03*
X830063Y898500D03*
X819918Y889365D03*
X823900Y882083D03*
X824804Y898395D03*
X834465Y884538D03*
X825508Y913869D03*
X829848Y914211D03*
X818031Y907747D03*
X822462Y915095D03*
X825336Y916774D03*
X831057Y916745D03*
X834751Y922368D03*
X818347Y939610D03*
X823552Y930700D03*
X829617Y939583D03*
X824414Y939655D03*
X816519Y931147D03*
X828193Y949324D03*
X824168Y949538D03*
X828423Y964731D03*
X832432Y977982D03*
X825670Y964671D03*
X832423Y964669D03*
X828964Y977780D03*
X832711Y993268D03*
X828385Y1120599D03*
X830356Y1116251D03*
X827856D03*
X817006Y1133027D03*
X822006Y1130208D03*
X825335Y1137129D03*
X819449Y1134534D03*
X819026Y1128137D03*
X825744Y1146937D03*
Y1150087D03*
X823220Y1162817D03*
Y1170767D03*
X818879Y1187310D03*
X823309Y1180235D03*
X823516Y1185238D03*
X823487Y1193019D03*
X819487D03*
X819489Y1201039D03*
X823489Y1200969D03*
X826612Y1219254D03*
X819522Y1212164D03*
X821816Y1214458D03*
X823608Y1208993D03*
X819419Y1230265D03*
X817360Y1228226D03*
X816648Y1377608D03*
Y1380758D03*
X824901Y1427404D03*
X827901D03*
X821901D03*
X818901Y1430104D03*
X821901D03*
X830901D03*
X827901D03*
X824901D03*
Y1432804D03*
X827901D03*
X830901D03*
X821901D03*
X818901D03*
X824901Y1435504D03*
X827901D03*
X821901D03*
X818901D03*
X821986Y1441485D03*
X818986D03*
Y1438785D03*
X821986D03*
X817974Y1447457D03*
X826204Y1440689D03*
X826341Y1451236D03*
X832084Y1461072D03*
X817974Y1452587D03*
Y1457717D03*
X818096Y1464387D03*
X821096D03*
X826365Y1458974D03*
X818096Y1473387D03*
X821096D03*
X824096D03*
X818096Y1479587D03*
X821096D03*
X824096D03*
X818096Y1476587D03*
X821096D03*
X824096D03*
X818096Y1467387D03*
Y1470387D03*
X821096D03*
Y1467387D03*
X824096D03*
Y1470387D03*
X831457Y1639797D03*
X838503Y-77705D03*
X841756Y-77719D03*
X838500Y-72500D03*
X838488Y-75190D03*
X841741Y-75204D03*
X844781Y-76399D03*
X838500Y-69600D03*
X844781Y-65613D03*
X841756Y-64293D03*
X838503Y-64307D03*
X841741Y-66808D03*
X838488Y-66822D03*
X838606Y5374D03*
X837919Y24773D03*
Y44773D03*
X841554Y94017D03*
X837554D03*
X845563D03*
X833554D03*
X837283Y101701D03*
Y98551D03*
X847837Y97475D03*
X840178Y114623D03*
X837682Y110445D03*
Y115401D03*
X848084Y117557D03*
X842674Y115401D03*
Y110445D03*
X844833Y103783D03*
X840178Y111223D03*
X840833Y103783D03*
X847768Y106186D03*
X842674Y129574D03*
Y124618D03*
X837682D03*
Y129574D03*
X848084Y131731D03*
Y122513D03*
X840178Y128796D03*
Y125396D03*
X848084Y136687D03*
X837751Y165393D03*
Y162793D03*
Y170493D03*
Y167993D03*
X842754Y181009D03*
X839959Y181366D03*
X836748Y181426D03*
X847929Y168697D03*
X844675Y177616D03*
X845256Y172190D03*
X839112Y188727D03*
X839245Y191941D03*
X845745Y184619D03*
X839573Y184012D03*
X836956Y184221D03*
X847725Y206760D03*
X836234Y208695D03*
X833434D03*
X835934Y211695D03*
X840992Y213859D03*
Y211359D03*
X833434Y211695D03*
X844695Y213132D03*
X837331Y229286D03*
X841024Y224712D03*
Y222212D03*
X833069Y226141D03*
X835869D03*
X844695Y215632D03*
X835812Y236611D03*
X838312D03*
X833312D03*
X837331Y231786D03*
X833014Y248891D03*
X848939Y256535D03*
X840939D03*
X838014Y248891D03*
X835514D03*
X844939Y256303D03*
X844698Y265896D03*
X839611Y265701D03*
X849714Y266114D03*
X836429Y267526D03*
X833929D03*
Y270026D03*
X836429D03*
X841246Y281716D03*
X847187Y281982D03*
X832966Y288190D03*
Y285690D03*
X835766Y288190D03*
Y285690D03*
X843992Y290755D03*
X839992D03*
X847992D03*
X839573Y325327D03*
X842240Y324854D03*
X848879Y360849D03*
X845435Y356172D03*
X846098Y408715D03*
X849591Y411388D03*
X833185Y456309D03*
Y452309D03*
Y448309D03*
X842515Y461382D03*
X850732Y469382D03*
X842779Y473076D03*
X842916Y467009D03*
X833293Y490636D03*
Y487836D03*
X833918Y480580D03*
X834215Y484138D03*
X844227Y479882D03*
X842476Y482382D03*
X833269Y506683D03*
X835236Y533174D03*
X833953Y530621D03*
X845729Y661263D03*
X836503Y667845D03*
X848444Y657756D03*
X837272Y663910D03*
X839636Y666533D03*
X842352Y659243D03*
X842640Y662814D03*
X838152Y700215D03*
X845784Y713939D03*
Y705489D03*
Y716589D03*
X845850Y710969D03*
X845784Y708089D03*
X836078Y709619D03*
X835987Y713745D03*
X848284Y731181D03*
X846484Y746701D03*
X838484D03*
X846484Y738750D03*
X836713Y738751D03*
X841500Y758161D03*
Y776161D03*
X842661Y769521D03*
X846000Y772079D03*
X841500Y794161D03*
Y812161D03*
X840136Y830903D03*
X836839Y831301D03*
X836894Y824401D03*
X848224Y823502D03*
X838685Y832987D03*
X835626Y843629D03*
X838189Y843459D03*
Y847490D03*
X835215Y847719D03*
X848384Y843459D03*
X846239Y847490D03*
X835553Y835119D03*
X848384Y839459D03*
Y835459D03*
X838194Y836962D03*
X848739Y847459D03*
X837183Y855459D03*
X840234Y851459D03*
X847138Y859459D03*
X839530Y859408D03*
X848384Y863459D03*
X846336Y855459D03*
X845820Y863413D03*
X848384Y851459D03*
X843574Y859423D03*
X837434Y851459D03*
X833327Y855560D03*
X837383Y879530D03*
X837396Y871459D03*
X840234Y875459D03*
X836999Y867413D03*
X845876Y879459D03*
X848384Y867459D03*
X845820Y867413D03*
X848384Y879459D03*
Y871459D03*
Y875459D03*
X845654Y895437D03*
X833870Y881860D03*
X837290Y887490D03*
X842827Y895443D03*
X835346Y891346D03*
X848322Y888421D03*
X848792Y896472D03*
X836066Y894955D03*
X847098Y891213D03*
X845633Y883492D03*
X845964Y887490D03*
X837276Y883459D03*
X848200Y883400D03*
X839381Y915839D03*
X841329Y926602D03*
X841274Y914060D03*
X843315Y916612D03*
X836909Y916618D03*
Y914018D03*
X839122Y939655D03*
X833683Y939579D03*
X836243D03*
X833683Y949105D03*
X836243D03*
X842856Y949146D03*
X836423Y964669D03*
X835431Y977775D03*
X843734Y1008778D03*
X848520Y1016855D03*
X840935Y1011499D03*
X844058Y1011738D03*
X848045Y1019310D03*
X848070Y1022190D03*
X839744Y1444959D03*
Y1440859D03*
Y1448959D03*
X836704Y1448849D03*
Y1440849D03*
X836744Y1444849D03*
X845306Y1438269D03*
X846844Y1454334D03*
X837685Y1453196D03*
X839744Y1457959D03*
X835474Y1457397D03*
X846044Y1451459D03*
X839744Y1461959D03*
X834475Y1460059D03*
X850145Y3000D03*
X865059Y55513D03*
X861284Y68581D03*
X850631Y84140D03*
Y80140D03*
Y76140D03*
X861297Y80581D03*
X853379Y76587D03*
Y72615D03*
X854818Y100625D03*
X864006Y117261D03*
X853076Y117557D03*
X856000Y103621D03*
X859191Y112083D03*
X863480Y103621D03*
X850580Y118335D03*
Y132509D03*
X853076Y131731D03*
Y122513D03*
X850580Y121735D03*
X853076Y136687D03*
X850580Y135909D03*
X851777Y180572D03*
X856460Y180527D03*
X862826Y183834D03*
X862999Y172665D03*
X862936Y178560D03*
X860183Y192421D03*
X851777Y185165D03*
X856415Y185121D03*
X849017Y191941D03*
X863812Y186629D03*
X857071Y192490D03*
X862346Y190185D03*
X863116Y200864D03*
X853029Y192300D03*
X853526Y206767D03*
X856026D03*
X851026D03*
X863205Y212455D03*
X863139Y207037D03*
X860506Y221642D03*
X852271Y228221D03*
Y231021D03*
X853656Y221708D03*
X856156D03*
X850571Y224421D03*
X851156Y221708D03*
X866015Y224536D03*
X852822Y236189D03*
X855322D03*
X857822D03*
X852763Y248765D03*
X855263D03*
X857763D03*
X849969Y279208D03*
X854073Y281307D03*
X852960Y268195D03*
Y270695D03*
X855460D03*
X864420Y265897D03*
X858260Y268195D03*
Y270695D03*
X861920Y265897D03*
X855460Y268195D03*
X858563Y293645D03*
Y290845D03*
X856063Y293645D03*
Y290845D03*
X858563Y288345D03*
X856063D03*
X863430Y309368D03*
Y316970D03*
X863114Y324505D03*
X863040Y330140D03*
X864920Y343168D03*
X861770Y343006D03*
X854622Y359004D03*
X852569Y356712D03*
X856069Y356426D03*
X854086Y374500D03*
X858586D03*
X863086D03*
X854086Y385000D03*
X858586D03*
X860586Y383000D03*
X861235Y394000D03*
X854086Y392999D03*
X864086Y384000D03*
X857973Y404867D03*
X862522Y400229D03*
X862566Y404867D03*
X857928Y400184D03*
X855017Y411969D03*
X862020Y410899D03*
X861413Y417071D03*
X858827Y419896D03*
X858410Y413890D03*
X858767Y416685D03*
X861622Y419688D03*
X862882Y458991D03*
X854882D03*
X862882Y468791D03*
Y465991D03*
X854882D03*
Y468791D03*
X850733Y461382D03*
X850832Y473382D03*
X862882Y461791D03*
X854882D03*
X850748Y465382D03*
X861468Y491303D03*
X850738Y477382D03*
X850909Y482382D03*
X861468Y483303D03*
Y487303D03*
X858169Y495032D03*
X867093Y570703D03*
Y582828D03*
X853900Y627700D03*
X853989Y630453D03*
Y632953D03*
X858202Y646330D03*
X861663Y646653D03*
X855300Y646819D03*
X851111Y656635D03*
X853982Y657506D03*
X856145Y677887D03*
X855646Y685230D03*
X859441Y678015D03*
X849680Y694789D03*
X858186Y701170D03*
X855646Y692710D03*
X864029Y688970D03*
X858186Y713170D03*
X867455Y710611D03*
X858002Y707244D03*
X867227Y722060D03*
X857986Y722670D03*
X854484Y746701D03*
X859199Y744517D03*
X854484Y738633D03*
X849500Y761000D03*
X859000Y756000D03*
X849500Y758500D03*
Y763500D03*
X863443Y753254D03*
X859000Y764000D03*
Y760000D03*
X864575Y770500D03*
X849500Y779000D03*
X859000Y774000D03*
X849500Y776500D03*
Y781500D03*
X861425Y770500D03*
X859000Y781000D03*
Y778000D03*
X864575Y788500D03*
X849500Y797000D03*
X853282Y789887D03*
X857632Y789385D03*
X859000Y792000D03*
X849500Y794500D03*
Y799500D03*
X861425Y788500D03*
X859000Y800000D03*
Y796000D03*
X849500Y815000D03*
X864575Y806500D03*
X861425D03*
X859000Y810000D03*
X849500Y812500D03*
X859000Y814000D03*
X865004Y831273D03*
X864464Y828503D03*
X864575Y824500D03*
X851782Y823720D03*
X850496Y831469D03*
X861425Y824500D03*
X849500Y817500D03*
X859000Y818000D03*
X851184Y839459D03*
Y835459D03*
X859165Y848728D03*
X851239Y847459D03*
X851184Y843459D03*
X851161Y855205D03*
X851184Y863459D03*
X862114Y859479D03*
X851184Y851459D03*
X859603Y863570D03*
X859461Y859459D03*
X851184Y867459D03*
Y871459D03*
Y875459D03*
X859234Y879600D03*
X859463Y866125D03*
X851184Y879459D03*
X849267Y892567D03*
X859614Y883800D03*
Y887846D03*
X850900Y888359D03*
X850800Y883500D03*
X858988Y898307D03*
X855524Y898505D03*
X856628Y915242D03*
X864253D03*
X849600Y915266D03*
X864253Y918042D03*
X856628D03*
X849600Y918028D03*
X849205Y924129D03*
X855867Y935540D03*
X867096Y935963D03*
X858601Y934505D03*
X853030Y934690D03*
X849088Y951081D03*
X851925Y951350D03*
X852247Y1009529D03*
X850686Y1006923D03*
X853449Y1007048D03*
X863334Y1009393D03*
X861047Y1018909D03*
X860887Y1023208D03*
Y1026762D03*
X863956Y1020763D03*
X863689Y1024974D03*
X849996Y1091073D03*
X850023Y1095179D03*
X863342Y1120636D03*
X855542D03*
X858142D03*
X860842D03*
X863442Y1130336D03*
X858242D03*
X855642D03*
X860942D03*
Y1139336D03*
X863442D03*
X861119Y1148080D03*
X863619D03*
X863944Y1432359D03*
Y1429359D03*
X860944Y1432359D03*
X857944Y1429359D03*
X860944D03*
Y1426359D03*
X857944D03*
X863944D03*
X857944Y1432359D03*
X863944Y1435359D03*
Y1441359D03*
Y1438359D03*
X860944Y1441359D03*
X857944Y1435359D03*
X860944D03*
X857944Y1441359D03*
Y1438359D03*
X860944D03*
X859071Y1447459D03*
X864671D03*
X850544Y1447559D03*
X859071Y1452589D03*
Y1457719D03*
X864671D03*
X864644Y1464759D03*
X861644D03*
X855644D03*
X858644D03*
X853514Y1457510D03*
X850644Y1457359D03*
X858644Y1467759D03*
X855644Y1470759D03*
X858644D03*
X864644Y1467759D03*
Y1470759D03*
X861644Y1467759D03*
Y1470759D03*
X855644Y1467759D03*
Y1473759D03*
X858644D03*
X864644D03*
X861644D03*
X855644Y1476759D03*
X858644D03*
X864644D03*
X861644D03*
X851457Y1639797D03*
X873373Y60922D03*
X868209Y55513D03*
X870519Y60438D03*
X867659Y60513D03*
X876200Y86012D03*
X867787Y85731D03*
X870395Y96738D03*
X865402Y91951D03*
X865427Y88801D03*
X876200Y94374D03*
X872293Y94279D03*
X868344Y94351D03*
X871341Y86046D03*
X871713Y172665D03*
Y180665D03*
Y168665D03*
Y176665D03*
Y196665D03*
Y192665D03*
X871826Y186778D03*
X871745Y200864D03*
Y212864D03*
Y204864D03*
Y208864D03*
Y216864D03*
Y221864D03*
X867386Y219379D03*
X883118Y262687D03*
X876622Y293721D03*
X876246Y302754D03*
X872050Y302644D03*
X873262Y300030D03*
X869924Y305368D03*
X879112Y302369D03*
X877977Y305368D03*
Y309368D03*
X869924Y313368D03*
X877977D03*
Y325368D03*
Y317368D03*
Y321368D03*
X869924D03*
Y328722D03*
X873885Y340892D03*
X874005Y344917D03*
X870413Y342791D03*
X869924Y333722D03*
X877977Y333368D03*
Y329368D03*
X873733Y357844D03*
X872158Y359962D03*
X871382Y373971D03*
X868086Y373750D03*
X872736Y383125D03*
X876736D03*
X877909Y391731D03*
X880736Y383125D03*
X882925Y391099D03*
X872736Y391754D03*
X867586Y393000D03*
Y385000D03*
X872318Y408589D03*
X869342Y407627D03*
X868586Y398500D03*
X866128Y417532D03*
X869342Y417399D03*
X877253Y420380D03*
X876917Y415322D03*
X879417D03*
X881190Y411619D03*
X878690D03*
X874253Y422880D03*
Y420080D03*
X877253Y422880D03*
X881271Y426952D03*
X878771D03*
X873536Y437408D03*
X876036D03*
X881036D03*
X878536D03*
X873771Y426952D03*
X876271D03*
X870882Y458991D03*
X880910Y454634D03*
Y457434D03*
Y471982D03*
Y469182D03*
Y466382D03*
X870882Y465991D03*
Y468791D03*
X880910Y460234D03*
X870882Y461791D03*
X875907Y486256D03*
X869454Y479303D03*
X869954Y487303D03*
X882954Y486256D03*
X882195Y539204D03*
X867093Y554703D03*
X866938Y549771D03*
X878382Y554942D03*
X874649Y545296D03*
X867093Y558703D03*
Y562703D03*
Y566703D03*
X876949Y571419D03*
X867093Y578703D03*
Y586828D03*
Y574703D03*
X881476Y588202D03*
X881131Y577349D03*
X875290Y578703D03*
X876351Y605023D03*
Y608523D03*
X879135Y632552D03*
X870137Y669461D03*
X872862Y666859D03*
X878881Y667156D03*
X869313Y688486D03*
X872069Y700894D03*
X876286Y686970D03*
Y690970D03*
X868919Y700894D03*
X876286Y694970D03*
Y698970D03*
X880501Y710611D03*
X873021Y715729D03*
X877616Y749484D03*
X878610Y747171D03*
X873318Y744597D03*
X881157Y749148D03*
X874142Y748914D03*
X879875Y753612D03*
X873728Y752692D03*
X875473Y742056D03*
X878670Y742841D03*
X869325Y761259D03*
X870017Y757313D03*
X871294Y771809D03*
X867000Y774000D03*
X870000Y780000D03*
X879887Y784719D03*
X873250Y798750D03*
X880040Y792851D03*
X867000Y792000D03*
X876402Y797415D03*
X875916Y808965D03*
X874925Y800746D03*
X870035Y801032D03*
X867000Y810000D03*
X879916Y808965D03*
X872700Y816615D03*
X877407Y828017D03*
X877818Y824214D03*
X876475Y830372D03*
X871600Y898584D03*
X872628Y915242D03*
X880628D03*
X872628Y918042D03*
X876628Y915242D03*
X880628Y918042D03*
X876628D03*
X876481Y941126D03*
X868908Y933640D03*
X872126Y934766D03*
X867199Y949372D03*
X865830Y961600D03*
X870209Y949384D03*
X869390Y978003D03*
X865973Y978187D03*
X874066Y977928D03*
X875391Y993796D03*
X872183Y993980D03*
X878976Y994020D03*
X871069Y1023114D03*
X878927Y1022387D03*
X878783Y1018751D03*
X872845Y1018988D03*
X866906Y1018751D03*
X866887Y1023208D03*
X875887D03*
X878887Y1026762D03*
X872887D03*
X866887D03*
X869741Y1025895D03*
X873824Y1071604D03*
X871224D03*
X876424D03*
Y1074104D03*
X871224D03*
X873824D03*
X868624Y1071604D03*
Y1074104D03*
X870057Y1091604D03*
X875257D03*
Y1089104D03*
X870057D03*
X872657D03*
X880115Y1084666D03*
X867457Y1091604D03*
Y1089104D03*
X872657Y1091604D03*
X875375Y1107647D03*
X872675D03*
X870075D03*
X867475D03*
X871364Y1120636D03*
X873964D03*
X876564D03*
X879264D03*
X875376Y1110175D03*
X872676D03*
X870076D03*
X867476D03*
X871364Y1139336D03*
X868664D03*
X879264Y1130336D03*
X876564D03*
X873964D03*
X871364D03*
X870522Y1148080D03*
X868022D03*
X875321Y1207654D03*
X871624Y1213314D03*
X874624D03*
X871624Y1221714D03*
Y1218914D03*
Y1216114D03*
X874624Y1221714D03*
Y1218914D03*
Y1216114D03*
X872440Y1230083D03*
Y1227583D03*
X871624Y1224514D03*
X874624D03*
X872440Y1234483D03*
Y1236983D03*
X878004Y1224406D03*
X872440Y1243883D03*
Y1241383D03*
Y1248283D03*
Y1250783D03*
X883142Y1259935D03*
X875700Y1299700D03*
X872600Y1300833D03*
Y1298333D03*
X872944Y1432359D03*
Y1429359D03*
Y1426359D03*
X869944Y1432359D03*
Y1429359D03*
Y1426359D03*
X866944Y1432359D03*
Y1429359D03*
Y1426359D03*
X872944Y1435359D03*
Y1441359D03*
Y1438359D03*
X869944Y1435359D03*
X866944D03*
X869944Y1441359D03*
Y1438359D03*
X866944Y1441359D03*
Y1438359D03*
X870171Y1447459D03*
X881244Y1448859D03*
Y1440859D03*
X878244Y1451605D03*
X870171Y1452589D03*
Y1457719D03*
X867644Y1464759D03*
X870644D03*
X881244Y1464859D03*
Y1453059D03*
Y1456859D03*
X875744Y1453573D03*
X867644Y1467759D03*
X870644D03*
X867644Y1470759D03*
X870644D03*
X867644Y1473759D03*
X870644D03*
X867644Y1476759D03*
X870644D03*
X881244Y1476859D03*
X871457Y1639797D03*
X883233Y147540D03*
X887005Y141247D03*
X894472Y143740D03*
X891852Y148277D03*
X886011Y154100D03*
X895780Y237517D03*
Y232634D03*
X893284Y233339D03*
Y236739D03*
X895064Y250186D03*
X891383Y243203D03*
X896034Y243307D03*
X886261Y252090D03*
X885741Y261150D03*
X885884Y255118D03*
X897004Y257480D03*
X892484Y260860D03*
X887148Y249670D03*
X896953Y272012D03*
X886496Y268968D03*
X895140Y265236D03*
X886059Y284644D03*
X885918Y289500D03*
X885989Y309368D03*
Y305368D03*
Y317368D03*
X885953Y325368D03*
X885989Y313368D03*
X885953Y321368D03*
Y329368D03*
Y333368D03*
X886026Y346584D03*
X896592Y358369D03*
Y354369D03*
X888812Y357372D03*
X883552Y357276D03*
X896592Y362369D03*
Y366369D03*
Y370369D03*
Y374369D03*
X884736Y383125D03*
X893736D03*
X888736D03*
X891251Y387484D03*
X890553Y392038D03*
X887266Y400158D03*
Y405158D03*
Y402658D03*
X896579Y404043D03*
X893779D03*
X889979Y405743D03*
X894844Y418983D03*
X889219Y426952D03*
X887770Y415290D03*
X891699Y420445D03*
X890270Y415290D03*
X891699Y423245D03*
X897344Y418983D03*
X894519Y426952D03*
X889596Y437264D03*
X896388Y437614D03*
X887096Y437264D03*
X892019Y426952D03*
X897019D03*
X890903Y454634D03*
Y457434D03*
Y469182D03*
Y471982D03*
Y466382D03*
Y460234D03*
X882907Y480350D03*
X891454Y486303D03*
X896431Y534093D03*
X882891Y536122D03*
X892931Y534093D03*
X885931D03*
X896449Y550863D03*
X893949Y550363D03*
X891449Y547363D03*
X893949D03*
X886549Y553963D03*
X885556Y543664D03*
X892023Y570176D03*
X882949Y557363D03*
X887417Y566713D03*
X890959Y579788D03*
X890956Y588325D03*
X894015Y588253D03*
X891673Y600049D03*
X895933Y618143D03*
X887949Y608863D03*
X894449Y606363D03*
X891933Y618143D03*
X895933Y609696D03*
X883309Y666608D03*
X892461Y666671D03*
X886304Y666650D03*
X884903Y694119D03*
Y696678D03*
X884911Y690279D03*
X889436Y715970D03*
X886836D03*
X893241Y704656D03*
X886836Y729778D03*
X883686D03*
X889525Y722060D03*
X882098Y741565D03*
X884976Y740891D03*
X884463Y744757D03*
X881637Y744154D03*
X883126Y766124D03*
X883413Y759855D03*
X889083Y780371D03*
X892040Y784511D03*
X888545Y785528D03*
X888514Y797602D03*
X889763Y788159D03*
X898737Y792289D03*
X889516Y792851D03*
X891916Y799605D03*
X884002Y797616D03*
X891916Y808965D03*
X887916Y800815D03*
X895916Y808965D03*
X883916D03*
X887916D03*
X895829Y800660D03*
X883916Y800815D03*
X890326Y828548D03*
X895050D03*
X889178Y905619D03*
X884628Y915242D03*
Y918042D03*
X896553D03*
X892628Y915242D03*
X888628D03*
Y918042D03*
X882763Y933472D03*
X891367Y941126D03*
X882609Y994245D03*
X888400Y994579D03*
X894660Y994330D03*
X891343Y994378D03*
X885099Y1021685D03*
X881887Y1023208D03*
X888743Y1019931D03*
X895394Y1026985D03*
X893147Y1020025D03*
X893887Y1023208D03*
X887887D03*
X890887Y1026762D03*
X884887D03*
X882779Y1074104D03*
Y1071604D03*
X887979Y1074104D03*
X885379D03*
X890579D03*
Y1071604D03*
X885379D03*
X887979D03*
X897056Y1091391D03*
X882615Y1084666D03*
X887862Y1088067D03*
X894004Y1081231D03*
X891055Y1095407D03*
X897056Y1095984D03*
X884906Y1102760D03*
X884890Y1098724D03*
X892856Y1102760D03*
X894249Y1114103D03*
X891549D03*
X888949D03*
X886349D03*
Y1123803D03*
X888949D03*
X891549D03*
X894249D03*
X895275Y1132870D03*
X892575D03*
X895547Y1145169D03*
X888650Y1199622D03*
X893190Y1208069D03*
X893328Y1212887D03*
X894713Y1210419D03*
X898878Y1214182D03*
X899286Y1219469D03*
X892532Y1220112D03*
X894887Y1227209D03*
X897169Y1225259D03*
X886888Y1263058D03*
X889388D03*
X891888D03*
X889388Y1260558D03*
X886888D03*
X891888D03*
X891003Y1292765D03*
X886926Y1298712D03*
X889729Y1295516D03*
X890738Y1311132D03*
X891107Y1314305D03*
X887342Y1314990D03*
X889244Y1444859D03*
X892244Y1449636D03*
Y1440859D03*
X889944Y1457959D03*
X889244Y1460859D03*
X895244Y1457510D03*
X889336Y1452554D03*
X893919Y1462132D03*
X889244Y1472859D03*
Y1468859D03*
X891457Y1639797D03*
X898813Y146461D03*
X903035Y141247D03*
X907522Y143518D03*
X906622Y152373D03*
X897715Y152367D03*
X909772Y152562D03*
X899573Y158195D03*
X898851Y231496D03*
Y238583D03*
Y245669D03*
X910977Y238583D03*
Y243307D03*
X898851Y259843D03*
X898576Y253056D03*
X910977Y252756D03*
Y257480D03*
Y248032D03*
Y262205D03*
X898851Y274016D03*
X910977Y266929D03*
X898851D03*
X898048Y269387D03*
X912786Y306697D03*
X901848Y307782D03*
Y312738D03*
X910076Y304843D03*
X905120D03*
X913057Y311046D03*
X915653Y307438D03*
X899352Y308560D03*
Y311960D03*
X909298Y302347D03*
X905898D03*
X909417Y323302D03*
X912278Y343881D03*
X913206Y336489D03*
X912085Y332335D03*
X898533Y334498D03*
X910040Y353532D03*
X908521Y356708D03*
X908625Y359317D03*
X905483Y355262D03*
X905000Y362158D03*
X898869Y351114D03*
X906161Y367191D03*
X913288Y372752D03*
X910646Y376084D03*
X906344Y372524D03*
X911072Y386992D03*
X897736Y383125D03*
X901747Y398492D03*
Y403492D03*
Y400992D03*
X902169Y413002D03*
Y418002D03*
Y415502D03*
X905094Y424581D03*
X902594D03*
X907594D03*
X905212Y436734D03*
X902712D03*
X907712D03*
X907173Y440581D03*
X898888Y437614D03*
X907173Y443081D03*
X910250Y457262D03*
Y454462D03*
X907450D03*
Y457262D03*
X910250Y451662D03*
X907450D03*
X910779Y471380D03*
X910250Y460062D03*
X907450D03*
X910236Y465272D03*
X910759Y475511D03*
X903431Y534093D03*
X906996Y530707D03*
X902459Y530755D03*
X899931Y534093D03*
X899530Y530753D03*
X911630Y543998D03*
X910578Y550186D03*
X909362Y555614D03*
X898156Y554812D03*
X914296Y558143D03*
X913728Y550495D03*
X913853Y561487D03*
X904393Y570176D03*
X908517D03*
X898815D03*
X899407Y560019D03*
X908846Y560124D03*
X909024Y578394D03*
X898232Y588320D03*
X909024Y586768D03*
X902635Y588305D03*
X906999Y588274D03*
X909024Y574394D03*
X910789Y598726D03*
X898207Y599891D03*
X908730Y619120D03*
X913686D03*
X899898Y619040D03*
X904854D03*
X900676Y621536D03*
X904076D03*
X909508Y621616D03*
X912908D03*
X900753Y656925D03*
X912462Y683770D03*
X909265Y677795D03*
X912462Y695770D03*
X910036Y702285D03*
X912462Y687770D03*
X906886Y702285D03*
X905313Y709259D03*
X910753Y715864D03*
X908699Y709387D03*
X913247Y714204D03*
X902841Y703665D03*
X905050Y720268D03*
X910836Y721570D03*
X913858Y721289D03*
X907866Y795572D03*
X911028Y796598D03*
X913716Y800815D03*
X899916D03*
X911053Y800510D03*
X909785Y810778D03*
X903916Y810809D03*
X913716Y811954D03*
X899916Y808965D03*
X902641Y800748D03*
X907884Y829866D03*
X899693Y895207D03*
X908920Y905630D03*
X904833Y915340D03*
X912628Y928101D03*
X900628Y918042D03*
X912628Y915242D03*
X908628Y918042D03*
X900628Y915242D03*
X912628Y918042D03*
X904838D03*
X908628Y915242D03*
X911355Y944909D03*
X900983Y940895D03*
X906710Y962433D03*
X906909Y951494D03*
X903759Y951358D03*
X909811Y962400D03*
X913005Y969605D03*
X912690Y994350D03*
X897825Y994413D03*
X909166Y994188D03*
X909296Y1020224D03*
X909300Y1014639D03*
X897717Y1019915D03*
X899887Y1023208D03*
Y1026762D03*
X908422Y1023103D03*
X908856Y1017677D03*
X901739Y1091346D03*
X897815Y1078042D03*
X901366Y1078069D03*
X902389Y1081764D03*
X908799Y1093659D03*
Y1088659D03*
X908278Y1083484D03*
X901694Y1095940D03*
X908799Y1096659D03*
Y1100659D03*
X902353Y1104333D03*
X911071Y1123803D03*
X905771D03*
X903171D03*
X908371D03*
X910971Y1114103D03*
X908271D03*
X903071D03*
X905671D03*
X911699Y1129488D03*
X909041Y1126328D03*
X911641D03*
X901428Y1136426D03*
X903908Y1132870D03*
X904063Y1135946D03*
X898278Y1136426D03*
X904897Y1145169D03*
X902397D03*
X898047D03*
X903959Y1207823D03*
X906784Y1216607D03*
X913784Y1221057D03*
X901940Y1236799D03*
Y1229899D03*
Y1232399D03*
X910633Y1222799D03*
X906309Y1226647D03*
X909077Y1232724D03*
X901940Y1246199D03*
Y1243699D03*
Y1239299D03*
X899699Y1283872D03*
X904703Y1297398D03*
X910788Y1299456D03*
X906506Y1299188D03*
X902908Y1299828D03*
X911117Y1314130D03*
X902875Y1309301D03*
X905740Y1309264D03*
X908700Y1316300D03*
X911135Y1345560D03*
X904177Y1359955D03*
X899944Y1432359D03*
X908944Y1426359D03*
Y1429359D03*
Y1432359D03*
X911944Y1426359D03*
Y1429359D03*
Y1432359D03*
X905944Y1426359D03*
X899944D03*
X902944D03*
Y1429359D03*
X899944D03*
X902944Y1432359D03*
X905944Y1429359D03*
Y1432359D03*
X902944Y1438359D03*
X899944D03*
Y1441359D03*
X902944Y1435359D03*
X899944D03*
X908944Y1438359D03*
Y1441359D03*
X911944Y1438359D03*
Y1441359D03*
X902944D03*
X905944Y1438359D03*
Y1441359D03*
X908944Y1435359D03*
X911944D03*
X905944D03*
X912171Y1447459D03*
X906671D03*
X901071D03*
X912171Y1457719D03*
Y1452589D03*
X906671Y1457719D03*
X901071D03*
Y1452589D03*
X908370Y1464583D03*
X905370D03*
X899370D03*
X902370D03*
X911370D03*
X905370Y1476583D03*
X908370D03*
X902370D03*
X899370D03*
X905370Y1473583D03*
X908370D03*
X902370D03*
X899370D03*
X902370Y1467583D03*
X899370Y1470583D03*
X902370D03*
X908370Y1467583D03*
Y1470583D03*
X905370Y1467583D03*
Y1470583D03*
X899370Y1467583D03*
X911370Y1476583D03*
Y1473583D03*
Y1467583D03*
Y1470583D03*
X911457Y1639797D03*
X930145Y3000D03*
X931393Y102249D03*
X919175Y113394D03*
X921824Y110784D03*
X923393Y102249D03*
X927393D03*
X919175Y116594D03*
X930118Y110784D03*
X925118D03*
X921418Y133298D03*
X929418D03*
X919175Y119594D03*
X924675Y124879D03*
X929697Y124663D03*
X919609Y124283D03*
X923565Y134579D03*
X931041Y138838D03*
X918016Y161306D03*
X915267Y157370D03*
X925359Y180347D03*
X927859D03*
X916453Y167975D03*
X925219Y188564D03*
X929978Y186854D03*
X927719Y188564D03*
X929978Y184054D03*
X927898Y203256D03*
X925098D03*
X919606Y231000D03*
X919577Y245669D03*
Y233858D03*
X919682Y236921D03*
X919577Y240945D03*
Y259843D03*
Y255118D03*
Y250394D03*
X919729Y274580D03*
X919577Y271654D03*
X919616Y268462D03*
X919577Y264567D03*
X920142Y308501D03*
X923732Y304585D03*
X926801Y323302D03*
X917906Y321670D03*
X917882Y328216D03*
Y324816D03*
X922629Y336609D03*
X922198Y342051D03*
X917858Y331453D03*
X923902Y332411D03*
X915954Y344150D03*
X916229Y336333D03*
X919354Y344150D03*
X919629Y336333D03*
X927964Y344041D03*
X924564D03*
X927309Y357267D03*
X921389D03*
X915395D03*
X921847Y346622D03*
X923311Y349959D03*
X915395Y363212D03*
X927309Y363239D03*
Y369210D03*
X921468D03*
X915395D03*
X929943Y372600D03*
X921343Y376888D03*
X916330Y377748D03*
X929947Y376821D03*
X927072Y386992D03*
X919072D03*
X923072D03*
X915072D03*
X914323Y398551D03*
Y403551D03*
Y401051D03*
X914202Y418002D03*
Y413002D03*
Y415502D03*
X927563Y424445D03*
X924763D03*
X921963D03*
X927280Y436716D03*
X921680D03*
X924480D03*
X917541Y441280D03*
X927636Y452505D03*
X929050Y450316D03*
X917541Y443780D03*
X927766Y456442D03*
X927596Y447453D03*
X921973Y469328D03*
X927401Y469059D03*
X916593Y469140D03*
X928999Y477948D03*
X920999D03*
X924999D03*
X924600Y533706D03*
X920961Y550075D03*
X917811Y544325D03*
X915949Y563363D03*
X923453Y569578D03*
X923642Y561578D03*
X919080Y587640D03*
X921507Y578791D03*
X919038Y579378D03*
X923599Y581578D03*
X921217Y589216D03*
X913998Y597103D03*
X915712Y613792D03*
X925949Y612363D03*
Y608863D03*
X922626Y633772D03*
X915800Y629700D03*
X918300D03*
X915194Y666671D03*
X929690Y666593D03*
X920090Y666714D03*
X928043Y677795D03*
X917286Y679625D03*
X928353Y686342D03*
X928704Y680261D03*
X924932Y701051D03*
X921061Y715386D03*
X926961Y723797D03*
X914202Y797460D03*
X923872Y798271D03*
X916590Y800636D03*
X921790Y810965D03*
X922352Y800809D03*
X917803Y811365D03*
X927916Y800909D03*
X929790Y828603D03*
X927916Y817015D03*
X925228Y816934D03*
X929181Y895029D03*
X921451Y903800D03*
X920628Y928101D03*
X928628D03*
X916628D03*
X924628D03*
X920628Y918042D03*
X916628D03*
X924628D03*
X928628D03*
X924628Y915242D03*
X920628D03*
X928628D03*
X916628D03*
X914193Y945318D03*
X924487Y951244D03*
X928227Y951125D03*
X921364Y951251D03*
X918648Y964717D03*
X915490Y969886D03*
X918265Y969745D03*
X923289Y965780D03*
X926796Y966297D03*
X929741Y967006D03*
X916932Y994405D03*
X924956Y994321D03*
X924864Y1026762D03*
Y1023208D03*
X925024Y1018909D03*
X927861Y1024768D03*
X916749Y1080659D03*
Y1088659D03*
Y1084659D03*
X916992Y1076659D03*
X916749Y1092664D03*
X917110Y1101902D03*
X916875Y1098643D03*
X916749Y1104659D03*
X927598Y1120636D03*
X924898D03*
X914661Y1132612D03*
X914299Y1129488D03*
X914241Y1126328D03*
X924919Y1130336D03*
X927619D03*
X924919Y1139336D03*
X927419D03*
X925097Y1147708D03*
X927597D03*
X914637Y1210568D03*
Y1214838D03*
X930754Y1310564D03*
X927146Y1328597D03*
Y1323641D03*
X924650Y1327819D03*
Y1324419D03*
X914033Y1345613D03*
X927193Y1361547D03*
X920255Y1383264D03*
X914944Y1426359D03*
Y1429359D03*
Y1432359D03*
Y1438359D03*
Y1441359D03*
Y1435359D03*
X921498Y1446692D03*
X914370Y1464583D03*
X925697Y1460109D03*
X917744Y1453573D03*
X920244Y1451605D03*
X919285Y1456226D03*
X914370Y1476583D03*
Y1473583D03*
Y1467583D03*
Y1470583D03*
X924803Y1474743D03*
X925435Y1478114D03*
X926044Y1545370D03*
Y1542370D03*
X929094Y1542353D03*
Y1545353D03*
X926041Y1554503D03*
Y1551503D03*
Y1548503D03*
Y1557503D03*
Y1560503D03*
X941129Y4469D03*
X942490Y24773D03*
Y44773D03*
X940761Y97667D03*
X945011Y95111D03*
X944961Y116497D03*
X934410Y109172D03*
X936417Y106495D03*
X937410Y109172D03*
X940161Y116497D03*
X931144Y116594D03*
X936417Y102495D03*
X940161Y123584D03*
X944961D03*
X940161Y130670D03*
X944961D03*
X931144Y119594D03*
X942561Y118342D03*
Y132515D03*
Y121742D03*
X934678Y125107D03*
X940161Y137757D03*
X944961D03*
X936151Y146012D03*
X938057Y141228D03*
X942561Y135915D03*
X936151Y142862D03*
X943292Y143762D03*
X937192Y148717D03*
X940945Y150847D03*
X930359Y180347D03*
X933159D03*
X945406D03*
X940406D03*
X942906D03*
X947424Y184419D03*
X931407Y192009D03*
X933907D03*
X944424Y186919D03*
X944760Y191977D03*
X942260D03*
X940487Y195680D03*
X942987D03*
X944424Y184419D03*
X934411Y202141D03*
X931698Y201556D03*
X934411Y207141D03*
X934477Y211491D03*
X934411Y204641D03*
X946234Y213390D03*
X942179Y215727D03*
X937438Y213817D03*
X938125Y230891D03*
X942805Y223860D03*
X936369Y221292D03*
X936395Y218142D03*
X940158Y245707D03*
X933403Y245507D03*
X936962Y249807D03*
X944248Y239844D03*
X946064Y252998D03*
X941845Y278968D03*
X945018Y276051D03*
X943183Y281652D03*
X939606Y310521D03*
X930727Y302571D03*
X937000Y312284D03*
X939653Y317474D03*
X940924Y328959D03*
X936608Y326058D03*
X945120Y326441D03*
X937000Y315684D03*
X942731Y324044D03*
X939331D03*
X932388Y330517D03*
X930398Y342050D03*
X936453Y345336D03*
X945599Y345383D03*
X940972Y338238D03*
X932622Y336817D03*
X940997Y331912D03*
Y335312D03*
X943663Y355674D03*
X944694Y352192D03*
X942700Y346363D03*
X939300D03*
X934128Y355168D03*
X934464Y358618D03*
X944238Y360828D03*
X944900Y363700D03*
X938499Y362202D03*
X940600Y370600D03*
X934047Y369160D03*
X936175Y364823D03*
X931072Y386992D03*
X941872Y440942D03*
X933424Y458455D03*
X933161Y451442D03*
X941505Y463442D03*
X933404Y463462D03*
X933412Y468942D03*
X939827Y531104D03*
X939992Y536726D03*
X936653Y526836D03*
X944351Y534211D03*
X948532Y541135D03*
X939992Y527726D03*
Y540726D03*
Y552726D03*
Y548726D03*
Y544726D03*
X948598Y546553D03*
X948621Y552726D03*
X931627Y561578D03*
Y565578D03*
Y557641D03*
Y569578D03*
X943825Y581222D03*
X931620Y584417D03*
X931627Y581578D03*
Y577578D03*
Y573578D03*
X933725Y585936D03*
X943825Y591215D03*
X931594Y599420D03*
X931647Y593271D03*
X931578Y590669D03*
X933741Y598087D03*
Y594687D03*
X933725Y589336D03*
X944296Y611071D03*
X941859Y621311D03*
Y629311D03*
X943181Y632536D03*
X945434Y634325D03*
X941859Y625311D03*
X946128Y666522D03*
X935281Y677795D03*
Y680945D03*
X939314Y707847D03*
X931244Y720471D03*
X936026Y730600D03*
Y727450D03*
X933974Y719371D03*
X945626Y789761D03*
X942676Y789286D03*
X933201Y798297D03*
X946970Y786366D03*
X941916Y808965D03*
X944916D03*
X938357Y808856D03*
X932000Y831000D03*
X931916Y817015D03*
X942858Y819430D03*
X945736Y819397D03*
X935124Y831382D03*
X940100Y830700D03*
X935262Y825135D03*
X932418D03*
X940716Y840074D03*
X944297Y839975D03*
X933021Y840893D03*
X933054Y843804D03*
X937200Y841000D03*
X936450Y858327D03*
X937551Y860801D03*
X932770Y878233D03*
X935765Y878317D03*
X934928Y871727D03*
X932319Y871626D03*
X942634Y886520D03*
X933700Y887508D03*
X945982Y886737D03*
X932300Y890200D03*
X942194Y891216D03*
X944839Y902400D03*
X938188Y900853D03*
X930800Y904840D03*
X941592Y900908D03*
X944628Y928101D03*
X932628D03*
X936628D03*
X940497D03*
X936628Y915242D03*
X940628D03*
X932628D03*
X936628Y918042D03*
X932628D03*
X936371Y951484D03*
X940716Y951733D03*
X946363Y951179D03*
X933810Y972433D03*
X935255Y962725D03*
X945671Y982191D03*
X940015Y1020176D03*
X934911Y1023579D03*
X945864Y1023208D03*
X930864Y1026762D03*
X936864D03*
X942864D03*
X939864Y1023208D03*
X930864D03*
X930883Y1018751D03*
X936822Y1018988D03*
X942760Y1018751D03*
X943093Y1021769D03*
X932289Y1074182D03*
Y1071682D03*
X937489Y1074182D03*
X934889D03*
X940089D03*
Y1071682D03*
X934889D03*
X937489D03*
X944092Y1084666D03*
X931628Y1091409D03*
Y1088909D03*
X936828Y1091409D03*
X934228D03*
X939428D03*
Y1088909D03*
X934228D03*
X936828D03*
X943241Y1120636D03*
X940541D03*
X937941D03*
X935341D03*
X937941Y1130336D03*
X940541D03*
X943241D03*
X932641Y1139336D03*
X935341Y1130336D03*
Y1139336D03*
X934500Y1147708D03*
X932000D03*
X939298Y1207654D03*
X935601Y1221714D03*
Y1218914D03*
Y1216114D03*
Y1213314D03*
X938601Y1221714D03*
Y1218914D03*
Y1216114D03*
Y1213314D03*
X936417Y1234483D03*
Y1236983D03*
Y1230083D03*
Y1227583D03*
X935601Y1224514D03*
X938601D03*
X941981Y1224406D03*
X936417Y1243883D03*
Y1241383D03*
Y1248283D03*
Y1250783D03*
X947119Y1259935D03*
X933254Y1308273D03*
X940848Y1310181D03*
X943891Y1306608D03*
X944207Y1320739D03*
X947308Y1325035D03*
X931137Y1375878D03*
X931159Y1383227D03*
Y1394627D03*
Y1387027D03*
Y1398427D03*
Y1402227D03*
X939559D03*
X944235Y1406262D03*
X943725Y1430744D03*
Y1427744D03*
X934725Y1430744D03*
X940725Y1427744D03*
Y1430744D03*
X934725Y1427744D03*
X937725D03*
Y1430744D03*
X943725Y1433744D03*
Y1439744D03*
Y1436744D03*
X940725Y1433744D03*
Y1439744D03*
Y1436744D03*
X934725Y1433744D03*
X937725D03*
X934725Y1439744D03*
X937725D03*
X934725Y1436744D03*
X937725D03*
X930441Y1455039D03*
Y1458039D03*
Y1464039D03*
Y1461039D03*
Y1467039D03*
X937671Y1492139D03*
Y1488139D03*
X938670Y1510528D03*
X941270D03*
Y1505328D03*
X938670D03*
X940170Y1507928D03*
X943870Y1510528D03*
Y1505328D03*
X945370Y1507928D03*
X942770D03*
X935094Y1542353D03*
X932094D03*
X935094Y1545353D03*
X932094D03*
X938094Y1542353D03*
Y1545353D03*
X941094Y1542353D03*
X944094D03*
X941094Y1545353D03*
X944094D03*
X931457Y1639797D03*
X956448Y-30304D03*
Y-33204D03*
X956460Y-35982D03*
X953207Y-35996D03*
X956445Y-38497D03*
X953192Y-38511D03*
X950167Y-37191D03*
X953192Y-25085D03*
X956445Y-25099D03*
X950167Y-26405D03*
X953207Y-27600D03*
X956460Y-27614D03*
X949811Y53597D03*
X960623Y82984D03*
Y77784D03*
Y80384D03*
Y75184D03*
Y85584D03*
X949221Y103411D03*
X949615Y97667D03*
X960411Y90650D03*
X960161Y95236D03*
Y102323D03*
X960413Y109410D03*
Y116496D03*
X947461Y116497D03*
X952161Y116496D03*
Y109410D03*
Y102323D03*
X947461Y109410D03*
X949861Y111255D03*
Y114655D03*
X949380Y106561D03*
X961638Y130670D03*
X947461D03*
X952161D03*
Y123583D03*
X947461D03*
X949861Y125428D03*
Y128828D03*
X961633Y137756D03*
X952161D03*
X947906Y180347D03*
X949359Y198710D03*
X947424Y187219D03*
X949443Y208206D03*
X950177Y215730D03*
X951040Y223885D03*
X947040D03*
X948741Y229468D03*
X948785Y242464D03*
X951278Y250583D03*
X946482Y255940D03*
X949974Y291554D03*
X947733Y319680D03*
X950953Y317947D03*
X949579Y330517D03*
X949813Y336817D03*
X956348Y356371D03*
X952170Y356131D03*
X958823Y362802D03*
X954888Y369513D03*
X948400Y370045D03*
X960376Y392807D03*
X956863Y451466D03*
X962769Y451419D03*
X950315Y464851D03*
X959816Y472905D03*
X955816Y473419D03*
Y464919D03*
X963816Y464419D03*
X949823Y487982D03*
X949876Y478486D03*
X949823Y483982D03*
X962563Y485128D03*
X954182Y481467D03*
X958124Y492354D03*
X958736Y482165D03*
X949823Y499982D03*
X958974Y504825D03*
X956474D03*
X953974D03*
X949823Y491982D03*
X959600Y496486D03*
X949823Y495982D03*
X957977Y500202D03*
X958915Y517401D03*
X956415D03*
X953915D03*
X959466Y522569D03*
Y525369D03*
X958081Y531882D03*
X955581D03*
X961166Y529169D03*
X952531Y531948D03*
X960581Y531882D03*
X948905Y534909D03*
X953816Y555194D03*
X951016D03*
X958016D03*
X960816D03*
X953816Y571194D03*
X951016D03*
X953816Y563194D03*
X951016D03*
X958016D03*
X960816D03*
Y571194D03*
X958016D03*
X946625Y581222D03*
X949425D03*
X959573D03*
X962373D03*
X949425Y591215D03*
X946625D03*
X959573D03*
X962373D03*
X948427Y611091D03*
X962545Y607762D03*
X959745D03*
Y610562D03*
X962545D03*
X950479Y622285D03*
X954535Y610548D03*
X950667Y616905D03*
X963365Y628078D03*
X961352Y633736D03*
X950865Y633724D03*
X950748Y627713D03*
X956345Y633716D03*
X956365Y641817D03*
X950865D03*
X949137Y666660D03*
X954526Y666671D03*
X957551Y698251D03*
X947556Y699550D03*
X956023Y706907D03*
X954023Y725336D03*
X951195Y727165D03*
X952681Y735256D03*
X951151Y730111D03*
X963869Y725057D03*
X955950Y734178D03*
X957763Y725336D03*
X959950Y734178D03*
X956323Y748412D03*
X957579Y744168D03*
X957474Y764426D03*
X953837Y763025D03*
X955086Y779798D03*
X950699Y779711D03*
X956017Y770300D03*
X957500Y780800D03*
X956051Y793937D03*
X955076Y784861D03*
X950475Y789361D03*
X955225Y788984D03*
X949609Y796051D03*
X957487Y798553D03*
X951461Y812223D03*
X951791Y808121D03*
X947735Y824921D03*
X957379Y826586D03*
X954760Y826734D03*
X951708Y818894D03*
X955712Y833988D03*
X956239Y829577D03*
X948935Y835800D03*
X954700Y842700D03*
X960100Y846665D03*
X954700Y837700D03*
X961175Y838525D03*
X947735Y854935D03*
X953091Y857440D03*
X953217Y861440D03*
X955967Y860376D03*
X946700Y849200D03*
X955343Y866850D03*
X955850Y862902D03*
X957900Y856300D03*
X950251Y874268D03*
X950291Y870240D03*
Y866240D03*
X953145Y874240D03*
X950300Y877800D03*
X953240Y876834D03*
X952738Y886624D03*
X949382Y886737D03*
X953587Y902814D03*
X950567Y927654D03*
X961479Y927643D03*
X954567Y927654D03*
X964280Y927777D03*
X958567Y927654D03*
X947029Y915242D03*
X959545Y918306D03*
X951863Y936168D03*
X957235Y936398D03*
X962329Y936229D03*
X957671Y977921D03*
X949671D03*
X957671Y991564D03*
X946642Y991361D03*
X961671Y991564D03*
X953671D03*
X949671D03*
X953671Y982191D03*
X954937Y1021998D03*
X948864Y1026762D03*
X954864D03*
X951864Y1023208D03*
X957864D03*
X957678Y1018555D03*
X961208Y1018592D03*
X960636Y1021917D03*
X959371Y1026985D03*
X948975Y1021325D03*
X951956Y1071604D03*
X949356D03*
X954556D03*
Y1074104D03*
X949356D03*
X951956D03*
X946756Y1071604D03*
Y1074104D03*
X961033Y1091391D03*
X946592Y1084666D03*
X957981Y1081231D03*
X951839Y1088067D03*
X948883Y1102760D03*
X948867Y1098724D03*
X955032Y1095407D03*
X961033Y1095984D03*
X956833Y1102760D03*
X950326Y1114103D03*
Y1123803D03*
X952926D03*
X955526D03*
Y1114103D03*
X958226D03*
X952926D03*
X958226Y1123803D03*
X956552Y1132870D03*
X959252D03*
X962255Y1136426D03*
X962024Y1145169D03*
X959524D03*
X952627Y1199622D03*
X957305Y1212887D03*
X957167Y1208069D03*
X958690Y1210419D03*
X963263Y1219469D03*
X962855Y1214182D03*
X956509Y1220112D03*
X958864Y1227209D03*
X961146Y1225259D03*
X950865Y1263058D03*
X953365D03*
X955865D03*
X953365Y1260558D03*
X950865D03*
X955865D03*
X948259Y1295965D03*
X949970Y1321749D03*
X952070Y1367717D03*
X949070D03*
X948832Y1371654D03*
X951832D03*
X952561Y1383465D03*
X952417Y1379528D03*
X949469D03*
X949385Y1375591D03*
X952385D03*
X952514Y1391339D03*
X952395Y1395276D03*
X952716Y1387402D03*
X952180Y1407087D03*
X950239Y1409555D03*
X948235Y1406262D03*
X946725Y1427744D03*
Y1430744D03*
X949725D03*
Y1427744D03*
X960883Y1427997D03*
Y1430997D03*
X946725Y1433744D03*
X949725D03*
X946725Y1439744D03*
X949725D03*
X946725Y1436744D03*
X949725D03*
X960883Y1433997D03*
Y1436997D03*
Y1439997D03*
X952695Y1444139D03*
X956238Y1455139D03*
Y1458139D03*
Y1461139D03*
Y1464139D03*
X952676Y1461039D03*
Y1464039D03*
Y1458039D03*
Y1455039D03*
X956238Y1467139D03*
Y1469902D03*
X952676Y1467039D03*
X946470Y1510528D03*
Y1505328D03*
X956035Y1545333D03*
X959035D03*
X953035D03*
X950035D03*
X959035Y1542333D03*
X956035D03*
X953035D03*
X950035D03*
X947094Y1545353D03*
Y1542353D03*
X951457Y1639797D03*
X978036Y-77691D03*
Y-64265D03*
X978051Y-75176D03*
X975011Y-76371D03*
Y-65585D03*
X978051Y-66780D03*
X969811Y53597D03*
X963177Y92849D03*
X979002Y92874D03*
X965723Y90615D03*
X970094Y95236D03*
X970044Y99961D03*
X978271Y109410D03*
Y102323D03*
X970137Y103037D03*
X970271Y116496D03*
Y109410D03*
X978271Y116496D03*
X970271Y130670D03*
Y123583D03*
X978271Y130670D03*
Y123583D03*
X963360Y121459D03*
X966347Y137756D03*
X978271D03*
X978051Y162368D03*
X968906Y207978D03*
Y212978D03*
Y215478D03*
Y210478D03*
Y223726D03*
Y228726D03*
Y231226D03*
X979362Y223661D03*
X968906Y226226D03*
X970865Y264068D03*
X973365D03*
X972160Y258880D03*
X974952Y293796D03*
X972452D03*
X976763Y307303D03*
X972147Y323681D03*
X977150Y328472D03*
X973338Y345018D03*
X977150Y335472D03*
Y331972D03*
Y338972D03*
X975631Y343112D03*
Y346612D03*
X969623Y405614D03*
X971721Y407762D03*
X968348Y402369D03*
X963577Y426391D03*
X975932Y437508D03*
X971932D03*
X971826Y430187D03*
X966694Y427599D03*
X968462Y429368D03*
X962769Y458466D03*
X973695Y448874D03*
X969109Y449352D03*
X970840Y457339D03*
X968340D03*
X962816Y442919D03*
X972030Y446071D03*
X979910Y445603D03*
X967816Y472905D03*
X972397Y472954D03*
X970840Y459839D03*
Y462339D03*
X968340D03*
Y459839D03*
X963816Y472905D03*
X976397Y473045D03*
X972397Y465004D03*
X977327Y462371D03*
X965412Y485138D03*
X969297Y478625D03*
Y475825D03*
X970997Y482425D03*
X970412Y485138D03*
X967912D03*
X976873Y491214D03*
X973843Y500086D03*
X978723Y504699D03*
X976223D03*
X973723D03*
X976873Y493714D03*
X978425Y516979D03*
X973425D03*
X974406Y521804D03*
X975925Y516979D03*
X978668Y527449D03*
X974406Y524304D03*
X970713Y531378D03*
Y528878D03*
X975868Y527449D03*
X970745Y539731D03*
X967042Y537658D03*
X964012Y546830D03*
X970745Y542231D03*
X978303Y541895D03*
X975803D03*
X967042Y540458D03*
X975503Y544895D03*
X978303D03*
X978581Y572975D03*
Y582747D03*
X965173Y581222D03*
X978032Y590801D03*
X965173Y591215D03*
X977857Y597130D03*
X976962Y608311D03*
X976027Y620653D03*
Y617853D03*
X968145Y610562D03*
X965345Y607762D03*
Y610562D03*
X968145Y607762D03*
X977857Y605443D03*
X973857D03*
X980683Y628242D03*
X967302Y627948D03*
X969491Y629362D03*
X972354Y627908D03*
X968365Y633473D03*
X978865Y642184D03*
X963187Y667620D03*
X973138Y667621D03*
X966797Y667653D03*
X970197D03*
X965774Y706907D03*
X973712Y722064D03*
X968589Y722434D03*
X970839Y729923D03*
X965042Y722234D03*
X971081Y722637D03*
X978352Y730766D03*
X963950Y734178D03*
X978059Y747438D03*
X973450Y747280D03*
X965983Y763567D03*
X966127Y776382D03*
X976764Y786563D03*
X968094Y799792D03*
X976186Y789819D03*
X964070Y807686D03*
Y813006D03*
X977218Y802178D03*
X967562Y802982D03*
X978978Y817618D03*
X964036Y818961D03*
X968319Y826191D03*
X978214Y821224D03*
X967337Y828901D03*
X976635Y835018D03*
X976800Y838011D03*
X974282D03*
X976902Y847135D03*
X970040Y842903D03*
X969309Y839334D03*
X974437Y849140D03*
X973510Y834991D03*
X971808Y851242D03*
X975925Y854783D03*
X967842Y864801D03*
X970299Y853773D03*
X978880Y869552D03*
X967510Y868971D03*
X978201Y897500D03*
X971144Y908972D03*
X966813Y904556D03*
X973988Y910038D03*
X972278Y934429D03*
X968507Y937615D03*
X971443Y938828D03*
X969806Y993033D03*
X965671Y991564D03*
Y982191D03*
X963864Y1026762D03*
Y1023208D03*
X965716Y1091346D03*
X966366Y1081764D03*
X972776Y1093659D03*
X972255Y1083484D03*
X972776Y1088659D03*
X965671Y1095940D03*
X972776Y1096659D03*
X966330Y1104333D03*
X972776Y1100659D03*
X967148Y1123803D03*
X969748D03*
X969648Y1114103D03*
X967048D03*
X972348Y1123803D03*
X975048D03*
X972248Y1114103D03*
X974948D03*
X965405Y1136426D03*
X970485Y1132870D03*
X967885D03*
X968874Y1145169D03*
X966374D03*
X967936Y1207823D03*
X978614Y1210568D03*
X970761Y1216607D03*
X978614Y1214838D03*
X978169Y1221268D03*
X965917Y1236799D03*
Y1229899D03*
Y1232399D03*
Y1246199D03*
Y1243699D03*
Y1239299D03*
X978727Y1284908D03*
X974985Y1290950D03*
X978857Y1360945D03*
X979996Y1386100D03*
X963883Y1430997D03*
Y1427997D03*
X966883Y1430997D03*
Y1427997D03*
X969883D03*
Y1430997D03*
X975883Y1427997D03*
Y1430997D03*
X972883D03*
Y1427997D03*
X963883Y1433997D03*
X966883D03*
X969883D03*
X963883Y1436997D03*
Y1439997D03*
X966883Y1436997D03*
Y1439997D03*
X969883Y1436997D03*
Y1439997D03*
X975883Y1433997D03*
X972883D03*
X975883Y1436997D03*
X972883D03*
X975883Y1439997D03*
X972883D03*
X971467Y1509515D03*
X974067D03*
X972567Y1512115D03*
X969967D03*
X976667Y1509515D03*
X977767Y1506915D03*
X975167D03*
X969967D03*
X972567D03*
X975167Y1512115D03*
X977767D03*
X971140Y1514693D03*
X968540D03*
X973740D03*
X976340D03*
X977547Y1546081D03*
X974547D03*
X971547D03*
X971457Y1639797D03*
X981289Y-77677D03*
Y-64279D03*
X981292Y-69484D03*
Y-72384D03*
X981304Y-75162D03*
Y-66794D03*
X988606Y5374D03*
X987919Y24773D03*
Y44773D03*
X978958Y85193D03*
Y82593D03*
Y77393D03*
Y74793D03*
Y79993D03*
X983554Y94017D03*
X987554D03*
X991554D03*
X987283Y101701D03*
Y98551D03*
X990178Y114623D03*
Y111223D03*
X987682Y115401D03*
X992674D03*
Y110445D03*
X987682D03*
X994833Y103783D03*
X990833D03*
X981029Y104249D03*
Y107649D03*
X990178Y128796D03*
Y125396D03*
X992674Y124618D03*
X987682D03*
Y129574D03*
X992674D03*
X985595Y147540D03*
X989367Y141247D03*
X996834Y143740D03*
X994214Y148277D03*
X985595Y151540D03*
X980651Y162368D03*
X987751Y162793D03*
Y165393D03*
Y167993D03*
Y170493D03*
X995256Y172190D03*
X994675Y177616D03*
X989959Y181366D03*
X986748Y181426D03*
X992754Y181009D03*
X989245Y191941D03*
X989112Y188727D03*
X986956Y184221D03*
X989573Y184012D03*
X994695Y213132D03*
X979362Y208213D03*
Y210713D03*
Y213213D03*
X986234Y208695D03*
X983434D03*
X985934Y211695D03*
X990992Y213859D03*
Y211359D03*
X983434Y211695D03*
X987331Y229286D03*
X991024Y224712D03*
Y222212D03*
X983069Y226141D03*
X985869D03*
X979362Y231461D03*
Y228961D03*
Y226461D03*
Y215713D03*
X994695Y215632D03*
X987331Y231786D03*
X985812Y236611D03*
X988312D03*
X983312D03*
X983014Y248891D03*
X988014D03*
X985514D03*
X990939Y256535D03*
X994939Y256303D03*
X989611Y265701D03*
X994698Y265896D03*
X986429Y270026D03*
X983929D03*
X981129D03*
X983929Y267526D03*
X986429D03*
X981129D03*
X991246Y281716D03*
X997187Y281982D03*
X985766Y288190D03*
X982966D03*
X985766Y285690D03*
X982966D03*
X980466Y288190D03*
Y285690D03*
X993992Y290755D03*
X989992D03*
X993132Y310942D03*
X987517Y314092D03*
X993243Y321325D03*
X987055Y320273D03*
X993552Y318175D03*
X993920Y335454D03*
X993420Y337954D03*
X990420Y340454D03*
Y337954D03*
X989630Y343862D03*
X983717Y341665D03*
X983956Y346652D03*
X993026Y353813D03*
X981719Y352217D03*
X988631Y349496D03*
X992045Y366559D03*
X984045D03*
X988045D03*
X980045D03*
X986373Y370467D03*
X991392Y409230D03*
X979932Y437508D03*
X982792Y447269D03*
X982670Y450201D03*
X980397Y473045D03*
X985303Y464652D03*
Y462152D03*
Y459652D03*
X987803Y464652D03*
Y462152D03*
Y459652D03*
X981843Y464818D03*
X992206Y478586D03*
Y481086D03*
Y483886D03*
X985699Y480705D03*
X980544Y482134D03*
Y484634D03*
X992206Y476086D03*
X988499Y480705D03*
X983989Y475946D03*
Y478446D03*
X992206Y491133D03*
Y498633D03*
X988134Y495151D03*
X985634D03*
X980576Y492987D03*
X985334Y498151D03*
X980576Y495487D03*
X988134Y498151D03*
X992206Y493633D03*
Y496133D03*
X982375Y522129D03*
X989936Y519531D03*
X987436D03*
X982436D03*
X984936D03*
X982375Y527129D03*
Y524629D03*
Y529929D03*
X989068Y532949D03*
X986268D03*
X982375Y537877D03*
X992306Y555897D03*
Y553297D03*
X989888Y548366D03*
X987388D03*
X982388D03*
X984888D03*
X982375Y542877D03*
Y545377D03*
Y540377D03*
X981795Y572842D03*
X992306Y561097D03*
Y563697D03*
Y566797D03*
Y558497D03*
X986301Y570686D03*
X989096Y570478D03*
X985903Y579475D03*
X985357Y585507D03*
X989950D03*
X989513Y576484D03*
X989156Y573689D03*
X986510Y573303D03*
X992906Y578405D03*
X985401Y590145D03*
X989995Y590190D03*
X981857Y597232D03*
X991907Y596782D03*
X986688Y596089D03*
X989857Y605443D03*
X983843Y619513D03*
Y616713D03*
Y613913D03*
X993857Y605443D03*
X981857Y605637D03*
X983843Y633205D03*
Y636005D03*
X980703Y625013D03*
X983843Y638805D03*
X986600Y717641D03*
X983712Y722064D03*
X984307Y748432D03*
X987461Y745796D03*
X981876Y745179D03*
X988371Y764143D03*
X983786Y765647D03*
X985030Y781204D03*
X988329Y781445D03*
X991990Y773974D03*
X984357Y777555D03*
X997051Y778833D03*
X990699Y778630D03*
X987990Y774005D03*
X984963Y785387D03*
X987394Y787490D03*
X979313Y814316D03*
X987501Y812573D03*
X985921Y805135D03*
X994051Y810871D03*
X996385Y816141D03*
X987903Y818645D03*
X979203Y829159D03*
X994094Y829000D03*
X982300Y821200D03*
X987702Y829159D03*
X993061Y833135D03*
X979203Y837159D03*
X989700Y846500D03*
X987202Y846395D03*
X987319Y843589D03*
X979203Y833159D03*
X989800Y843900D03*
X987200Y848940D03*
X987703Y837159D03*
X988820Y858903D03*
X990457Y852043D03*
X983269Y853883D03*
X981700Y856300D03*
X980529Y879097D03*
X988231Y878203D03*
X984892Y868720D03*
X979891Y876589D03*
X992441Y870398D03*
X987790Y896596D03*
X995133Y888503D03*
X988054Y888283D03*
X990300Y897500D03*
X982787Y899757D03*
X979592Y902849D03*
X982783Y909995D03*
X979498Y907500D03*
X989311Y920364D03*
X983227Y968565D03*
X988461Y1013841D03*
X988240Y1020015D03*
Y1016923D03*
Y1023968D03*
X980726Y1080659D03*
Y1088659D03*
X984909Y1081071D03*
X983751Y1078675D03*
X980969Y1076659D03*
X980726Y1084659D03*
X981087Y1101902D03*
X980852Y1098643D03*
X980726Y1104659D03*
Y1092664D03*
X986645Y1108465D03*
X989513Y1097683D03*
X995009Y1131223D03*
X991763Y1140378D03*
Y1128378D03*
Y1134378D03*
X984558Y1140774D03*
X988112Y1137774D03*
X984558Y1128774D03*
Y1134774D03*
X987804Y1131619D03*
X988389Y1302558D03*
X984817Y1303297D03*
X979001Y1288925D03*
X990613Y1324248D03*
Y1327048D03*
X993413Y1324248D03*
Y1327048D03*
X990501Y1320756D03*
X981857Y1360945D03*
X988784Y1361974D03*
X980501Y1369685D03*
X983501D03*
X980139Y1381496D03*
X980166Y1373622D03*
X980203Y1377559D03*
X980047Y1397245D03*
X985448Y1398271D03*
X980092Y1389370D03*
X980139Y1393308D03*
X978944Y1413859D03*
X981944D03*
X984136Y1401636D03*
X987136D03*
X986949Y1430997D03*
Y1427997D03*
X983949D03*
X989949Y1430997D03*
Y1427997D03*
X983949Y1430997D03*
X992949Y1427997D03*
Y1430997D03*
X986949Y1433997D03*
X983949D03*
X989949D03*
X992949D03*
X986949Y1436997D03*
X983949D03*
X986949Y1439997D03*
X983949D03*
X989949Y1436997D03*
Y1439997D03*
X992949Y1436997D03*
Y1439997D03*
X978934Y1444392D03*
X979538Y1464039D03*
Y1461039D03*
Y1458039D03*
Y1455039D03*
Y1467039D03*
Y1469802D03*
X978987Y1489832D03*
X982241Y1489637D03*
X979267Y1509515D03*
X984467D03*
X981867D03*
X985567Y1512115D03*
Y1506915D03*
X980367D03*
X982967D03*
Y1512115D03*
X980367D03*
X989667Y1509515D03*
X992267D03*
X987067D03*
X988167Y1512115D03*
X990767D03*
Y1506915D03*
X988167D03*
X984140Y1514693D03*
X981540D03*
X978940D03*
X986740D03*
X989340D03*
X986773Y1546081D03*
X983773D03*
X980773D03*
X991457Y1639797D03*
X1005256Y-48539D03*
X1002003D03*
X1005241Y-46024D03*
X1001988D03*
X1008281Y-47219D03*
X1002000Y-40834D03*
X1005256Y-38239D03*
X1002003Y-38225D03*
X1002000Y-43334D03*
X1005241Y-35724D03*
X1002000Y-32720D03*
X1001988Y-35710D03*
X1002000Y-30120D03*
X1008281Y-36919D03*
X1011187Y-33526D03*
Y-30126D03*
X1005256Y-25113D03*
X1002003Y-25027D03*
X1005241Y-27628D03*
X1001988Y-27542D03*
X1008281Y-26433D03*
X1007508Y3000D03*
X1011284Y68581D03*
X1000631Y84140D03*
Y76140D03*
Y80140D03*
X1011297Y80581D03*
X1003379Y72615D03*
Y76587D03*
X995563Y94017D03*
X1004818Y100625D03*
X997837Y97475D03*
X1013480Y103621D03*
X1006000D03*
X1003076Y117557D03*
X998084D03*
X997768Y106186D03*
X1009191Y112083D03*
X1000580Y121735D03*
Y118335D03*
Y132509D03*
X1003076Y122513D03*
Y131731D03*
X998084Y122513D03*
Y131731D03*
X1000580Y135909D03*
X1001175Y146461D03*
X1003076Y136687D03*
X998084D03*
X1005397Y141247D03*
X1009884Y143518D03*
X1008984Y152373D03*
X1000077Y152367D03*
X1001777Y180572D03*
X1006460Y180527D03*
X1012936Y178560D03*
X997929Y168697D03*
X1012826Y183834D03*
X1012999Y172665D03*
X1010183Y192421D03*
X1001777Y185165D03*
X1006415Y185121D03*
X995745Y184619D03*
X999017Y191941D03*
X1003029Y192300D03*
X1012346Y190185D03*
X1007071Y192490D03*
X1013116Y200864D03*
X997725Y206760D03*
X1003526Y206767D03*
X1006026D03*
X1001026D03*
X1010291Y199582D03*
X1013139Y207037D03*
X1013205Y212455D03*
X1002271Y228221D03*
Y231021D03*
X1010506Y221642D03*
X1003656Y221708D03*
X1006156D03*
X1000571Y224421D03*
X1001156Y221708D03*
X1002822Y236189D03*
X1005322D03*
X1007822D03*
X998939Y256535D03*
X1002763Y248765D03*
X1005263D03*
X1007763D03*
X999714Y266114D03*
X999826Y278734D03*
X1004061Y280808D03*
X1008260Y268195D03*
X1005460D03*
X1002960D03*
X1008260Y270695D03*
X1002960D03*
X1005460D03*
X1008563Y293645D03*
X1006063D03*
Y290845D03*
Y288345D03*
X1008563Y290845D03*
Y288345D03*
X997992Y290755D03*
X1004635Y300276D03*
X1008635D03*
X1000698D03*
X1002580Y309619D03*
X1010499Y309062D03*
X998667Y322239D03*
X1004544Y318050D03*
X1004933Y314535D03*
X1003181Y323057D03*
X1001105Y318006D03*
X997921Y333654D03*
X1009770Y344486D03*
X997020Y345354D03*
X1003076Y332496D03*
X1000420Y348954D03*
Y353954D03*
X996024Y352132D03*
X1001825Y581659D03*
X998332Y578986D03*
X997857Y596729D03*
Y605443D03*
X995913Y619758D03*
Y616958D03*
Y614158D03*
X1001857Y605443D03*
X995913Y633450D03*
Y636250D03*
X1003900Y628700D03*
X1001605Y627605D03*
X1005800Y637600D03*
X1002883Y622521D03*
X995913Y639050D03*
X1001676Y678015D03*
X1011185Y724519D03*
X1009562Y722438D03*
X1008342Y761735D03*
X1003539Y762632D03*
X1003990Y765899D03*
X1007990D03*
X1002751Y757169D03*
X999990Y764566D03*
X1013151Y756726D03*
X1002834Y777394D03*
X1012695Y776728D03*
X999990Y774671D03*
X1013319Y785929D03*
X1006053Y787745D03*
X1007027Y792973D03*
X998376Y810970D03*
X1006054Y810969D03*
X1010699Y803454D03*
X999825Y819488D03*
X1002699Y819475D03*
X1002887Y834342D03*
X1000369D03*
X1011144Y844340D03*
X1010977Y841737D03*
X1012703Y837659D03*
X1001187Y850084D03*
X1004577Y853679D03*
X1005607Y874859D03*
Y877859D03*
X1004713Y871389D03*
X998313Y888295D03*
X1002930Y906785D03*
X1005413Y905295D03*
X1004953Y923995D03*
X1008935Y924007D03*
X1010119Y933822D03*
X1006619D03*
X1004994Y955372D03*
X1007919Y948822D03*
X1011019D03*
X1004719D03*
X1012219Y954222D03*
X1006222Y980337D03*
X1009564Y988874D03*
X1010009Y998100D03*
X1005301Y1006560D03*
X999879Y998507D03*
X1001805Y1007522D03*
X1008571Y1006648D03*
X999700Y1018400D03*
X1008759Y1023900D03*
X1002180Y1013678D03*
X1002652Y1023731D03*
X1005938Y1018307D03*
X995317Y1137378D03*
X996213Y1324248D03*
Y1327048D03*
X1009333Y1346693D03*
Y1343293D03*
X1008312Y1363533D03*
X998600Y1369200D03*
X1008452Y1376752D03*
X1008483Y1372734D03*
X1008387Y1380797D03*
X998600Y1373400D03*
X997401Y1381200D03*
X999283Y1377400D03*
X1007850Y1368835D03*
X1006211Y1397662D03*
X1009338Y1391597D03*
Y1388597D03*
X998643Y1398271D03*
X1008138Y1407186D03*
Y1409986D03*
X1005338Y1407186D03*
Y1409986D03*
X1008138Y1415586D03*
Y1412786D03*
X1005338Y1415586D03*
Y1412786D03*
X1008138Y1418386D03*
X1005338D03*
X998949Y1427997D03*
Y1430997D03*
X995949D03*
Y1427997D03*
X1009981Y1431097D03*
Y1428097D03*
X1006981D03*
Y1431097D03*
X998949Y1433997D03*
X995949D03*
X998949Y1436997D03*
X995949D03*
X998949Y1439997D03*
X995949D03*
X1009981Y1434097D03*
X1006981D03*
X1009981Y1437097D03*
X1006981D03*
X1009981Y1440097D03*
X1006981D03*
X1002194Y1444392D03*
X1002538Y1463939D03*
Y1460939D03*
Y1457939D03*
Y1454939D03*
Y1466939D03*
Y1469702D03*
X1008549Y1509815D03*
X1007049Y1507215D03*
X1011149Y1509815D03*
X1009649Y1507215D03*
Y1512415D03*
X1007049D03*
X1008222Y1514993D03*
X1005622D03*
X1010822D03*
X1010606Y1547824D03*
X1007611Y1561247D03*
Y1558247D03*
Y1555247D03*
Y1552247D03*
X1004611Y1561247D03*
Y1558247D03*
Y1555247D03*
Y1552247D03*
X1010659Y1568771D03*
Y1565771D03*
X1010653Y1571669D03*
X1013683Y-44304D03*
Y-39348D03*
Y-29348D03*
Y-34304D03*
X1027508Y3000D03*
X1023373Y60922D03*
X1018209Y55513D03*
X1015059D03*
X1020519Y60438D03*
X1017659Y60513D03*
X1026200Y86012D03*
X1017787Y85731D03*
X1020254Y97068D03*
X1015402Y91951D03*
X1026200Y94374D03*
X1015427Y88801D03*
X1022293Y94279D03*
X1018344Y94351D03*
X1021341Y86046D03*
X1014006Y117261D03*
X1021537Y113394D03*
X1025755Y102249D03*
X1024186Y110784D03*
X1021537Y116594D03*
X1027480Y110784D03*
X1024289Y130898D03*
X1021537Y119594D03*
X1021971Y124283D03*
X1027037Y124879D03*
X1025927Y134579D03*
X1020378Y161306D03*
X1012134Y152562D03*
X1017629Y157370D03*
X1021713Y180665D03*
Y172665D03*
Y176665D03*
Y168665D03*
X1027055Y195176D03*
X1013812Y186629D03*
X1021713Y196665D03*
X1021826Y186778D03*
X1021713Y192665D03*
X1026915Y203393D03*
X1021745Y212864D03*
Y200864D03*
Y204864D03*
Y208864D03*
Y221864D03*
Y216864D03*
X1026794Y218085D03*
X1017386Y219379D03*
X1018014Y228631D03*
X1023502Y252371D03*
Y248371D03*
X1014420Y265897D03*
X1011920D03*
X1027216Y289440D03*
X1022604Y290262D03*
X1016635Y300276D03*
X1012635D03*
X1025749D03*
X1020635D03*
X1022435Y312865D03*
X1021848Y310396D03*
X1013354Y323362D03*
X1021451Y322879D03*
X1026032Y322906D03*
X1013327Y327453D03*
X1013318Y333190D03*
X1022845Y340944D03*
X1013313Y339909D03*
X1020406Y350772D03*
X1015195Y428305D03*
X1012188Y443421D03*
X1018238Y678647D03*
X1018155Y684132D03*
X1015659Y679654D03*
Y683054D03*
X1025116Y698332D03*
X1021885Y698974D03*
X1022937Y691421D03*
X1024932Y717856D03*
X1014641Y724436D03*
X1012851Y722417D03*
X1026916Y719769D03*
X1018015Y751565D03*
X1013486Y750773D03*
X1015804Y760454D03*
X1024684Y756485D03*
X1026090Y770943D03*
X1021895Y771974D03*
X1019375Y783056D03*
X1017664Y779101D03*
X1018044Y793592D03*
X1014064Y793660D03*
X1018071Y798490D03*
X1015800Y807535D03*
X1014587Y802788D03*
X1025859Y802275D03*
X1013821Y813520D03*
X1014781Y810319D03*
X1017955Y812097D03*
X1016320Y828481D03*
X1021895Y818974D03*
X1020703Y833659D03*
X1021221Y848712D03*
X1025219Y842155D03*
X1025239Y845070D03*
X1020703Y837659D03*
X1013918Y851306D03*
X1017800Y867065D03*
X1016973Y877196D03*
X1016574Y874537D03*
X1016798Y890299D03*
X1021408Y895008D03*
X1024913Y884000D03*
X1012842Y910685D03*
X1026340Y917761D03*
X1022346Y917669D03*
X1029570Y917718D03*
X1018419Y917575D03*
X1019519Y937922D03*
X1023319D03*
X1017619Y932122D03*
X1014719Y938322D03*
X1027319D03*
X1023519Y951522D03*
X1018919D03*
X1027719Y958822D03*
X1014009Y980356D03*
X1018009D03*
X1014009Y988813D03*
X1018009D03*
X1021924Y980456D03*
X1026009Y988813D03*
X1022009D03*
Y997860D03*
X1018009D03*
X1026009D03*
X1025448Y1008262D03*
X1014009Y997860D03*
X1017998Y1009655D03*
X1015198D03*
X1025448Y1011762D03*
X1024570Y1024003D03*
X1011782Y1016591D03*
X1014767Y1035088D03*
X1022594Y1035114D03*
X1022143Y1030672D03*
X1019143D03*
X1016143D03*
X1025143D03*
X1017297Y1102091D03*
X1026606Y1102591D03*
X1023106Y1102091D03*
X1023144Y1109564D03*
X1017297Y1114691D03*
X1023106D03*
X1026606D03*
X1017297Y1109564D03*
X1023144Y1122164D03*
X1017297D03*
X1023106Y1127291D03*
X1026606D03*
X1017297Y1139891D03*
X1023106D03*
X1026606D03*
X1017297Y1127291D03*
X1023144Y1134764D03*
X1017297D03*
X1026606Y1152491D03*
X1017297D03*
X1023106D03*
X1023144Y1147364D03*
X1017297D03*
Y1165091D03*
X1023106D03*
X1026606D03*
X1023144Y1159964D03*
X1017297D03*
Y1172564D03*
Y1177691D03*
X1023106D03*
X1026606D03*
X1023162Y1174445D03*
X1023139Y1184856D03*
X1017297Y1185164D03*
X1020434Y1205579D03*
X1022420Y1203204D03*
X1026221Y1214372D03*
X1021976Y1218169D03*
X1026968Y1223749D03*
X1025434Y1320606D03*
X1011829Y1347471D03*
Y1342515D03*
X1015286Y1344924D03*
X1023358Y1363921D03*
X1013991Y1360842D03*
X1021623Y1373216D03*
X1019391Y1377061D03*
X1012338Y1388597D03*
Y1391597D03*
X1015338D03*
Y1388597D03*
X1021338D03*
Y1391597D03*
X1018338D03*
Y1388597D03*
X1027338D03*
Y1391597D03*
X1024338D03*
Y1388597D03*
X1012981Y1431097D03*
Y1428097D03*
X1015981D03*
Y1431097D03*
X1021981Y1428097D03*
Y1431097D03*
X1018981D03*
Y1428097D03*
X1012981Y1434097D03*
X1015981D03*
X1012981Y1437097D03*
Y1440097D03*
X1015981Y1437097D03*
Y1440097D03*
X1021981Y1434097D03*
X1018981D03*
X1021981Y1437097D03*
X1018981D03*
X1021981Y1440097D03*
X1018981D03*
X1025615Y1444492D03*
X1025138Y1463839D03*
Y1460839D03*
Y1457839D03*
Y1454839D03*
Y1466839D03*
Y1469602D03*
X1020023Y1489637D03*
X1016769Y1489832D03*
X1013749Y1509815D03*
X1016349D03*
X1021549D03*
X1018949D03*
X1024149D03*
X1022649Y1507215D03*
X1025249D03*
X1017449D03*
X1020049D03*
X1014849D03*
X1012249D03*
X1026749Y1509815D03*
X1012249Y1512415D03*
X1014849D03*
X1025249D03*
X1022649D03*
X1020049D03*
X1017449D03*
X1013422Y1514993D03*
X1023822D03*
X1021222D03*
X1018622D03*
X1016022D03*
X1026422D03*
X1013606Y1547824D03*
X1016606D03*
X1019606D03*
X1013659Y1568771D03*
X1016659D03*
X1019659D03*
X1013659Y1565771D03*
X1016659D03*
X1019659D03*
X1013653Y1571669D03*
X1016653D03*
X1019653D03*
X1011457Y1639797D03*
X1043492Y4469D03*
X1033755Y102249D03*
X1043123Y97667D03*
X1036772Y109172D03*
X1039772D03*
X1038779Y106495D03*
X1029755Y102249D03*
X1042523Y116497D03*
X1033506Y116594D03*
X1038779Y102495D03*
X1032480Y110784D03*
X1031780Y133298D03*
X1042523Y130670D03*
Y123584D03*
X1033506Y119594D03*
X1037040Y125107D03*
X1032059Y124663D03*
X1038513Y146012D03*
X1040419Y141228D03*
X1042523Y137757D03*
X1038513Y142862D03*
X1045654Y143762D03*
X1039554Y148717D03*
X1033403Y138838D03*
X1043307Y150847D03*
X1032055Y195176D03*
X1031674Y198883D03*
X1029555Y195176D03*
X1034855D03*
X1042102D03*
X1033103Y206838D03*
X1035603D03*
X1029415Y203393D03*
X1031674Y201683D03*
X1042183Y210509D03*
X1029594Y218085D03*
X1036107Y221970D03*
X1036173Y226320D03*
X1036107Y219470D03*
Y216970D03*
X1033394Y216385D03*
X1043875Y230556D03*
X1039134Y228646D03*
X1038065Y236121D03*
X1035099Y238589D03*
X1042860Y242078D03*
X1038091Y232971D03*
X1034741Y244571D03*
X1032121Y249108D03*
X1037984Y253198D03*
X1042084Y256394D03*
X1030184Y288709D03*
X1037290Y296293D03*
X1033890D03*
X1038068Y298789D03*
X1033112D03*
X1041496Y300276D03*
X1045650Y300093D03*
X1029639Y300141D03*
X1031354Y325901D03*
Y322905D03*
X1041783Y321114D03*
X1030220Y313554D03*
X1031382Y340947D03*
X1031310Y337888D03*
X1031377Y333671D03*
X1031362Y329268D03*
X1042948Y333696D03*
X1043106Y340230D03*
X1031259Y350427D03*
X1029885Y711762D03*
X1030753Y732213D03*
X1033200Y731700D03*
X1038796Y763272D03*
X1035619Y755809D03*
X1038344Y756476D03*
X1043016Y782161D03*
X1038678Y776750D03*
X1042880Y794924D03*
X1039251Y812340D03*
X1042414Y801443D03*
X1043425Y830800D03*
X1043626Y836563D03*
X1041100Y838500D03*
X1037527Y836486D03*
X1031813Y850273D03*
X1046045Y841217D03*
X1040822Y841339D03*
X1044390Y861210D03*
X1035185Y862793D03*
X1037685Y862789D03*
X1028155Y879413D03*
X1030300Y881400D03*
X1038363Y875288D03*
X1037709Y886209D03*
X1043252Y902501D03*
X1038010Y902565D03*
X1033019Y933022D03*
Y935822D03*
X1030819Y938422D03*
X1031219Y949922D03*
X1033370Y953994D03*
X1038009Y988813D03*
X1030009D03*
X1042009D03*
X1034009D03*
X1030009Y997860D03*
X1034009D03*
X1038252Y1009354D03*
X1034752D03*
X1028943D03*
X1042009Y997860D03*
X1038009D03*
X1034752Y1021954D03*
X1038252D03*
X1028943Y1016827D03*
X1034790D03*
X1043553Y1035384D03*
X1028943Y1029427D03*
X1034790D03*
X1039499Y1098758D03*
X1039053Y1105091D03*
X1044553D03*
X1039098Y1102091D03*
X1039053Y1117691D03*
X1044553D03*
X1039098Y1114691D03*
Y1127291D03*
X1039053Y1130291D03*
X1044553D03*
Y1142891D03*
X1039098Y1139891D03*
X1039053Y1142891D03*
Y1155491D03*
X1044553D03*
X1039098Y1152491D03*
X1044553Y1168091D03*
X1039053D03*
X1039098Y1165091D03*
X1044553Y1180691D03*
X1039053D03*
X1039098Y1177691D03*
X1032831Y1207950D03*
X1040600Y1210600D03*
X1035384Y1215195D03*
X1029797Y1220921D03*
X1040606Y1230407D03*
X1043588Y1227300D03*
X1034513Y1333665D03*
X1042586Y1345824D03*
X1030338Y1391597D03*
Y1388597D03*
X1032867Y1431213D03*
Y1428213D03*
X1029867D03*
X1035867Y1431213D03*
Y1428213D03*
X1029867Y1431213D03*
X1038867Y1428213D03*
Y1431213D03*
X1041867D03*
Y1428213D03*
X1032867Y1434213D03*
X1029867D03*
X1035867D03*
X1038867D03*
X1032867Y1437213D03*
X1029867D03*
X1032867Y1440213D03*
X1029867D03*
X1035867Y1437213D03*
Y1440213D03*
X1038867Y1437213D03*
Y1440213D03*
X1041867Y1434213D03*
Y1437213D03*
Y1440213D03*
X1029349Y1509815D03*
X1027849Y1507215D03*
Y1512415D03*
X1031457Y1639797D03*
X1044853Y24773D03*
Y44773D03*
X1052174Y53597D03*
X1051583Y103411D03*
X1051977Y97667D03*
X1047373Y95111D03*
X1049823Y109410D03*
X1054523Y116496D03*
Y109410D03*
Y102323D03*
X1049823Y116497D03*
X1047323D03*
X1052223Y111255D03*
Y114655D03*
X1051742Y106561D03*
X1049823Y130670D03*
X1047323D03*
Y123584D03*
X1049823Y123583D03*
X1054523Y130670D03*
Y123583D03*
X1044923Y118342D03*
X1052223Y125428D03*
Y128828D03*
X1044923Y132515D03*
Y121742D03*
X1054523Y137756D03*
X1047323Y137757D03*
X1044923Y135915D03*
X1047102Y195176D03*
X1046120Y199248D03*
X1044602Y195176D03*
X1049120Y199248D03*
X1049602Y195176D03*
X1051055Y213539D03*
X1046120Y201748D03*
X1049120Y202048D03*
X1044683Y210509D03*
X1046456Y206806D03*
X1043956D03*
X1052720Y230117D03*
X1048130Y227824D03*
X1044501Y238689D03*
X1045275Y247292D03*
X1052736Y238714D03*
X1048736D03*
X1048217Y246874D03*
X1050437Y244297D03*
X1048695Y280161D03*
X1045364Y279895D03*
X1051796Y279965D03*
X1050164Y302748D03*
X1050076Y305512D03*
X1046674Y340031D03*
X1061387Y343509D03*
X1045966Y346808D03*
X1060679Y356151D03*
X1052367Y402291D03*
X1057359D03*
X1052367Y397335D03*
X1057359D03*
X1054863Y401513D03*
Y398113D03*
X1054959Y411509D03*
X1049967Y416465D03*
Y411509D03*
X1054959Y425682D03*
X1049967D03*
X1054959Y416465D03*
X1052463Y412287D03*
Y415687D03*
Y426460D03*
X1049967Y439855D03*
X1054959Y430638D03*
X1049967D03*
X1054959Y439855D03*
X1052463Y440633D03*
Y429860D03*
X1049967Y444811D03*
X1050777Y450750D03*
X1054959Y444811D03*
X1052463Y444033D03*
X1059549Y458711D03*
X1049967Y468609D03*
X1054959D03*
X1049967Y473565D03*
X1054959D03*
X1052463Y469387D03*
Y472787D03*
X1049967Y487738D03*
X1054959D03*
X1049967Y482782D03*
X1054959D03*
X1052463Y486960D03*
Y483560D03*
X1054959Y517699D03*
X1049967Y512743D03*
X1054959D03*
X1049967Y517699D03*
X1052463Y513521D03*
Y516921D03*
X1049967Y526916D03*
X1054959Y531872D03*
X1049967D03*
X1054959Y526916D03*
X1054876Y536382D03*
X1052463Y531094D03*
Y527694D03*
X1055885Y554555D03*
X1059843Y597580D03*
X1059782Y594668D03*
X1062098Y615600D03*
X1044112Y778835D03*
X1046068Y792742D03*
X1046930Y796557D03*
X1045744Y800835D03*
X1048328Y808166D03*
X1048314Y833102D03*
X1053392Y832788D03*
X1051550Y823146D03*
X1055700Y840900D03*
X1053913Y837718D03*
X1050358Y837793D03*
X1052500Y841200D03*
X1049087Y856033D03*
X1053909Y855472D03*
X1045300Y872352D03*
X1054900Y879321D03*
X1058155Y887635D03*
X1050295Y891100D03*
X1057961Y931919D03*
X1054009Y988813D03*
X1046009D03*
X1050009D03*
X1058009D03*
X1046009Y997860D03*
X1054009D03*
X1050009D03*
X1058009D03*
X1056199Y1012354D03*
X1050744Y1009354D03*
X1059689Y1012354D03*
Y1024954D03*
X1056199D03*
X1050699D03*
Y1012354D03*
X1050744Y1021954D03*
X1046485Y1034538D03*
X1057212Y1040356D03*
X1048043Y1105091D03*
Y1117691D03*
Y1130291D03*
Y1155491D03*
Y1142891D03*
Y1168091D03*
Y1180691D03*
X1049930Y1221407D03*
X1050605Y1224472D03*
X1049770Y1229402D03*
X1049720Y1234921D03*
X1051249Y1290288D03*
X1052660Y1293257D03*
X1050002Y1293283D03*
X1052221Y1336984D03*
X1049204Y1337377D03*
X1049670Y1347462D03*
X1046075Y1350650D03*
X1049493Y1350694D03*
X1044867Y1428213D03*
Y1431213D03*
Y1434213D03*
Y1437213D03*
Y1440213D03*
X1048403Y1444608D03*
X1051457Y1639797D03*
X1075256Y-77419D03*
X1072003Y-77405D03*
X1071988Y-85290D03*
X1075241D03*
X1072000Y-82600D03*
X1072003Y-87805D03*
X1075256D03*
X1072000Y-80100D03*
Y-72000D03*
Y-69400D03*
X1071988Y-66722D03*
X1075241Y-66808D03*
X1072003Y-64207D03*
X1075256Y-64293D03*
X1075241Y-74904D03*
X1071988Y-74890D03*
X1072174Y53597D03*
X1062985Y82984D03*
Y75184D03*
Y77784D03*
Y80384D03*
X1065539Y92849D03*
X1062985Y85584D03*
X1062773Y90650D03*
X1068085Y90615D03*
X1072456Y95236D03*
X1072406Y99961D03*
X1062523Y95236D03*
X1072499Y103037D03*
X1062523Y102323D03*
X1062775Y109410D03*
Y116496D03*
X1072633D03*
Y109410D03*
X1062947Y124576D03*
X1072633Y130670D03*
Y123583D03*
X1064000Y130670D03*
X1069224Y137756D03*
X1063995D03*
X1071268Y207978D03*
Y212978D03*
Y215478D03*
Y210478D03*
Y226226D03*
Y223726D03*
Y228726D03*
Y231226D03*
X1074597Y264180D03*
X1074522Y258880D03*
X1074814Y293796D03*
X1076571Y310574D03*
X1061325Y339509D03*
X1060679Y360151D03*
Y364276D03*
Y368276D03*
X1060369Y390223D03*
X1065361D03*
X1062865Y391001D03*
X1062234Y378600D03*
Y382600D03*
X1060369Y395179D03*
Y404396D03*
Y409352D03*
X1065361Y395179D03*
Y404396D03*
Y409352D03*
X1062865Y408574D03*
Y405174D03*
Y394401D03*
X1060369Y418569D03*
Y423525D03*
X1065361D03*
Y418569D03*
X1062865Y422747D03*
Y419347D03*
X1060369Y432743D03*
Y437699D03*
X1065361Y432743D03*
Y437699D03*
X1062865Y436921D03*
Y433521D03*
X1062349Y458711D03*
X1064876Y453682D03*
X1063113Y455921D03*
X1061693Y463600D03*
X1065361Y489895D03*
X1060369D03*
Y480677D03*
Y475721D03*
X1065361Y480677D03*
Y475721D03*
X1062865Y476499D03*
Y479899D03*
Y490673D03*
X1060369Y494851D03*
X1065361D03*
X1062865Y494073D03*
X1060369Y519855D03*
X1065361D03*
X1062865Y520633D03*
Y524033D03*
X1065361Y524811D03*
X1060369D03*
Y538984D03*
Y534028D03*
X1065361Y538984D03*
Y534028D03*
X1062865Y534806D03*
Y538206D03*
X1071548Y555234D03*
X1071263Y562003D03*
X1062066Y599588D03*
X1061328Y589556D03*
X1061267Y592354D03*
X1062069Y596095D03*
X1062098Y603600D03*
X1062066Y607588D03*
X1061342Y610269D03*
X1061496Y612786D03*
X1062098Y619600D03*
X1066559Y634946D03*
X1063642Y634190D03*
X1062098Y623600D03*
X1066931Y645389D03*
X1060698Y931619D03*
X1069685Y933391D03*
X1066878Y931909D03*
X1070009Y988813D03*
X1069607Y980131D03*
X1066009Y980330D03*
X1062009Y988813D03*
X1065823Y988773D03*
X1074009Y988813D03*
X1066009Y997860D03*
X1062009D03*
X1074009D03*
X1070009D03*
X1070778Y1012252D03*
X1073525Y1012428D03*
X1066933Y1040567D03*
X1076110Y1029535D03*
X1065079Y1036920D03*
X1076577Y1041332D03*
X1071641Y1058029D03*
X1060172Y1050481D03*
X1071348Y1050503D03*
X1074232Y1055836D03*
X1067866Y1051037D03*
X1060768Y1053457D03*
X1074650Y1070006D03*
X1069642Y1445541D03*
X1068861Y1451311D03*
X1071457Y1639797D03*
X1078281Y-86399D03*
X1083683Y-78528D03*
Y-83484D03*
X1078281Y-65613D03*
Y-76099D03*
X1083683Y-73484D03*
Y-68528D03*
X1081187Y-72706D03*
Y-69306D03*
X1090280Y44773D03*
X1081320Y85193D03*
Y82593D03*
Y79993D03*
Y77393D03*
Y74793D03*
X1089916Y94017D03*
X1085916D03*
X1089645Y101701D03*
Y98551D03*
X1081364Y92874D03*
X1092540Y111223D03*
X1090044Y110445D03*
Y115401D03*
X1080633Y102323D03*
Y116496D03*
Y109410D03*
X1092540Y114623D03*
X1083391Y104249D03*
Y107649D03*
X1092540Y128796D03*
X1080633Y130670D03*
Y123583D03*
X1090044Y124618D03*
Y129574D03*
X1092540Y125396D03*
X1080633Y137756D03*
X1087957Y147540D03*
X1091729Y141247D03*
X1087957Y151540D03*
X1083013Y162368D03*
X1090113Y165393D03*
Y162793D03*
X1080413Y162368D03*
X1090113Y170493D03*
Y167993D03*
X1092321Y181366D03*
X1089110Y181426D03*
X1091607Y191941D03*
X1091474Y188727D03*
X1091935Y184012D03*
X1089318Y184221D03*
X1081724Y208213D03*
X1085796Y208695D03*
Y211695D03*
X1081724Y210713D03*
Y213213D03*
X1088596Y208695D03*
X1088296Y211695D03*
X1085431Y226141D03*
X1081724Y226461D03*
X1088231Y226141D03*
X1081724Y223661D03*
X1089693Y229286D03*
X1081724Y231461D03*
Y228961D03*
Y215713D03*
X1089693Y231786D03*
X1085674Y236611D03*
X1088174D03*
X1090674D03*
X1090376Y248891D03*
X1087876D03*
X1085376D03*
X1077097Y264180D03*
X1091973Y265701D03*
X1083491Y267526D03*
X1088791D03*
X1086291D03*
X1083491Y270026D03*
X1086291D03*
X1088791D03*
X1093608Y281716D03*
X1088128Y285690D03*
Y288190D03*
X1085328D03*
X1082828Y285690D03*
X1085328D03*
X1082828Y288190D03*
X1077314Y293796D03*
X1092354Y290755D03*
X1077855Y327478D03*
X1077252Y323521D03*
Y318565D03*
X1077602Y314060D03*
X1080351Y328256D03*
X1079748Y322743D03*
Y319343D03*
X1077855Y332434D03*
X1080351Y331656D03*
X1082297Y340770D03*
X1092554Y340318D03*
X1085615Y339815D03*
X1079863Y345660D03*
X1092561Y353374D03*
X1082787Y348501D03*
X1091031Y374810D03*
X1091542Y389154D03*
Y410413D03*
Y396240D03*
Y403327D03*
Y417500D03*
Y424587D03*
Y431673D03*
Y438760D03*
Y445847D03*
Y467539D03*
Y474626D03*
Y488799D03*
Y481713D03*
Y495886D03*
Y511673D03*
Y518760D03*
Y525847D03*
Y532933D03*
Y540020D03*
Y547106D03*
X1089788Y550907D03*
X1087288D03*
X1089788Y553407D03*
X1087288D03*
X1089096Y541863D03*
Y545263D03*
X1091558Y566929D03*
X1091272Y569426D03*
X1088949Y568475D03*
X1089206Y570962D03*
X1086859Y569928D03*
X1085512Y572070D03*
X1090823Y602197D03*
X1091287Y595108D03*
X1078920Y856700D03*
X1090375Y899047D03*
X1076800Y1012900D03*
X1079809Y1034386D03*
X1078755Y1031518D03*
X1079178Y1037884D03*
X1076868Y1047293D03*
X1079910Y1045264D03*
X1079822Y1151870D03*
X1083562Y1155610D03*
X1079822Y1159350D03*
X1083483Y1523433D03*
X1083283Y1526583D03*
X1084000Y1529600D03*
X1091529Y1528718D03*
X1091525Y1546300D03*
X1090876Y1554183D03*
X1091569Y1561300D03*
X1092527Y1579422D03*
X1086469Y1588435D03*
X1090469D03*
X1083900Y1593206D03*
X1082176Y1600598D03*
X1090904Y1599047D03*
X1088021Y1606949D03*
X1093778Y1599574D03*
X1086904Y1599004D03*
X1090747Y1617415D03*
X1090093Y1628297D03*
X1085474Y1629028D03*
X1089474Y1638213D03*
X1092000Y1644980D03*
X1102993Y84140D03*
Y76140D03*
Y80140D03*
X1105741Y76587D03*
Y72615D03*
X1097925Y94017D03*
X1093916D03*
X1100199Y97475D03*
X1107180Y100625D03*
X1100446Y117557D03*
X1095036Y115401D03*
Y110445D03*
X1105438Y117557D03*
X1097195Y103783D03*
X1108362Y103621D03*
X1100130Y106186D03*
X1093195Y103783D03*
X1102942Y118335D03*
Y132509D03*
Y121735D03*
X1095036Y129574D03*
Y124618D03*
X1105438Y131731D03*
Y122513D03*
X1100446Y131731D03*
Y122513D03*
X1102942Y135909D03*
X1103537Y146461D03*
X1100446Y136687D03*
X1105438D03*
X1107759Y141247D03*
X1099196Y143740D03*
X1096576Y148277D03*
X1102439Y152367D03*
X1104139Y180572D03*
X1108822Y180527D03*
X1095116Y181009D03*
X1100291Y168697D03*
X1097618Y172190D03*
X1109903Y171523D03*
X1097037Y177616D03*
X1104139Y185165D03*
X1108777Y185121D03*
X1098107Y184619D03*
X1101379Y191941D03*
X1109433Y192490D03*
X1100087Y206760D03*
X1105888Y206767D03*
X1108388D03*
X1103388D03*
X1093354Y213859D03*
Y211359D03*
X1097057Y213132D03*
X1093386Y224712D03*
Y222212D03*
X1104633Y228221D03*
X1106018Y221708D03*
X1108518D03*
X1102933Y224421D03*
X1103518Y221708D03*
X1104633Y231021D03*
X1097057Y215632D03*
X1105184Y236189D03*
X1107684D03*
X1101301Y256535D03*
X1093301D03*
X1105125Y248765D03*
X1107625D03*
X1097301Y256303D03*
X1102076Y266114D03*
X1097060Y265896D03*
X1102331Y279208D03*
X1106435Y281307D03*
X1107822Y268195D03*
X1105322D03*
Y270695D03*
X1107822D03*
X1099549Y281982D03*
X1108425Y293645D03*
Y290845D03*
Y288345D03*
X1096354Y290755D03*
X1100354D03*
X1093478Y310305D03*
X1108779Y327705D03*
X1100703Y340560D03*
X1103432Y340544D03*
X1097976Y340477D03*
X1101999Y353495D03*
X1105012Y353504D03*
X1098845Y353404D03*
X1093994Y374003D03*
X1093841Y371335D03*
X1099342Y389154D03*
X1106161D03*
X1099342Y396240D03*
X1100621Y404911D03*
X1104691Y396240D03*
X1099575Y412571D03*
X1108776Y422864D03*
X1100762Y426299D03*
X1108846Y429832D03*
X1108451Y436447D03*
X1101073Y445847D03*
X1099342Y467539D03*
Y474626D03*
X1108395Y472772D03*
X1099603Y480828D03*
X1101553Y498834D03*
X1105002Y516841D03*
X1108253Y510565D03*
X1099342Y518760D03*
Y511673D03*
Y525847D03*
X1099949Y550123D03*
X1099827Y552872D03*
X1099501Y545528D03*
X1101581Y572334D03*
X1099272Y562443D03*
X1101040Y560675D03*
X1099813Y574102D03*
X1108236Y577716D03*
X1105298Y598400D03*
Y602400D03*
Y594400D03*
Y614400D03*
Y606400D03*
Y610400D03*
X1104448Y653161D03*
X1108045Y668153D03*
Y677843D03*
X1092769Y936975D03*
X1095080Y1513398D03*
X1096780Y1526700D03*
X1101402Y1531702D03*
X1099900Y1535700D03*
X1095250Y1531600D03*
X1098617Y1546183D03*
X1096780Y1535400D03*
X1096264Y1562285D03*
X1100876Y1554183D03*
X1099371Y1561153D03*
X1100476Y1579318D03*
X1102904Y1566668D03*
X1093713Y1585583D03*
X1093682Y1582433D03*
X1098498Y1590435D03*
X1104233Y1587983D03*
X1100233Y1588000D03*
X1107620Y1606752D03*
Y1603602D03*
X1098904Y1602138D03*
X1101946Y1614709D03*
X1096941Y1627905D03*
X1105474Y1629450D03*
X1101474Y1637820D03*
X1093474Y1638213D03*
X1105474Y1638426D03*
X1097474Y1637753D03*
X1123052Y57511D03*
X1114781Y58013D03*
X1113646Y68581D03*
X1120021Y60513D03*
X1122881Y60438D03*
X1113659Y80581D03*
X1120149Y85731D03*
X1122613Y97042D03*
X1117764Y91951D03*
X1117789Y88801D03*
X1123703Y86046D03*
X1120706Y94351D03*
X1124655Y94279D03*
X1115842Y103621D03*
X1116368Y117261D03*
X1123899Y113394D03*
Y116594D03*
X1111553Y112083D03*
X1123899Y119594D03*
X1124333Y124283D03*
X1112246Y143518D03*
X1111346Y152373D03*
X1122740Y161306D03*
X1114496Y152562D03*
X1119991Y157370D03*
X1124075Y180665D03*
Y172665D03*
Y168665D03*
Y176665D03*
X1115188Y183834D03*
X1115298Y178560D03*
X1115361Y172665D03*
X1112545Y192421D03*
X1116174Y186629D03*
X1124075Y192665D03*
Y196665D03*
X1115478Y200864D03*
X1114708Y190185D03*
X1124188Y186778D03*
X1124107Y200864D03*
Y212864D03*
Y204864D03*
X1115501Y207037D03*
X1115567Y212455D03*
X1124107Y208864D03*
Y216864D03*
Y221864D03*
X1112868Y221642D03*
X1119748Y219379D03*
X1120376Y228631D03*
X1110184Y236189D03*
X1110125Y248765D03*
X1116782Y265897D03*
X1114282D03*
X1110622Y268195D03*
Y270695D03*
X1110925Y293645D03*
Y290845D03*
Y288345D03*
X1123500Y329000D03*
X1115000D03*
X1123500Y339000D03*
Y334000D03*
X1115000D03*
Y339000D03*
X1117453Y389154D03*
X1124753Y389153D03*
X1118848Y382109D03*
X1122253Y396240D03*
X1124753D03*
X1122253Y403327D03*
X1124753Y403326D03*
X1122253Y410413D03*
X1124753D03*
X1117453Y396240D03*
Y403327D03*
Y410413D03*
X1119853Y398082D03*
Y401482D03*
X1109468Y414823D03*
X1122253Y424586D03*
X1124753D03*
X1117453Y417500D03*
Y424586D03*
X1122253Y417500D03*
X1124753Y417499D03*
X1119853Y412255D03*
Y426428D03*
Y415655D03*
X1122253Y438760D03*
X1124753D03*
Y431673D03*
X1117453D03*
Y438760D03*
X1122253Y431673D03*
X1119853Y440602D03*
Y429828D03*
X1110486Y447953D03*
X1122253Y445847D03*
X1117453D03*
X1119853Y444002D03*
X1109653Y467539D03*
X1124753D03*
X1117453D03*
X1122253Y474626D03*
X1124753D03*
X1117453D03*
X1122253Y488799D03*
X1124753D03*
X1117453D03*
X1109129Y487711D03*
X1109242Y479104D03*
X1124753Y481712D03*
X1122253D03*
X1117453Y481713D03*
X1119853Y490641D03*
Y476468D03*
Y479868D03*
X1122253Y495886D03*
X1117453D03*
X1109653D03*
X1119853Y494041D03*
X1124753Y518760D03*
X1122253D03*
X1124753Y511673D03*
X1117453D03*
Y518760D03*
X1119853Y524002D03*
Y520602D03*
X1124753Y532933D03*
X1122253D03*
Y540020D03*
Y525846D03*
X1124753D03*
X1117453Y525847D03*
Y532933D03*
Y540020D03*
X1119853Y538175D03*
Y534775D03*
X1117453Y554193D03*
Y547106D03*
X1118847Y551683D03*
X1117913Y565414D03*
Y567914D03*
Y570414D03*
X1118847Y561420D03*
Y558917D03*
X1117913Y572914D03*
Y575414D03*
X1122705Y588515D03*
X1114668Y577937D03*
X1117453Y602205D03*
Y595118D03*
X1122718Y598857D03*
X1117673Y606929D03*
X1122673Y595500D03*
X1122173Y604567D03*
X1122705Y591015D03*
X1121191Y612555D03*
X1120512Y617332D03*
X1121022Y607750D03*
X1123331Y610072D03*
X1123267Y616317D03*
X1117633Y618400D03*
X1117914Y612592D03*
X1115151Y650119D03*
X1115320Y646449D03*
X1118863Y662981D03*
X1112839Y668885D03*
X1115054Y662981D03*
X1113244Y691851D03*
X1116296D03*
X1111785Y686971D03*
X1118855Y705043D03*
X1118105Y707592D03*
X1112000Y1644980D03*
X1125735Y60922D03*
X1128562Y86012D03*
X1136117Y102249D03*
X1128562Y94374D03*
X1139134Y109172D03*
X1141141Y106495D03*
X1132117Y102249D03*
X1128117D03*
X1126548Y110784D03*
X1135868Y116594D03*
X1141141Y102495D03*
X1129842Y110784D03*
X1134842D03*
X1134142Y133298D03*
X1126142D03*
X1135868Y119594D03*
X1139402Y125107D03*
X1129399Y124879D03*
X1134421Y124663D03*
X1140875Y146012D03*
X1128289Y134579D03*
X1140875Y142862D03*
X1141916Y148717D03*
X1135765Y138838D03*
X1134036Y198883D03*
X1134417Y195176D03*
X1131917D03*
X1137217D03*
X1129417D03*
X1137965Y206838D03*
X1134036Y201683D03*
X1131777Y203393D03*
X1129277D03*
X1135465Y206838D03*
X1129156Y218085D03*
X1131956D03*
X1138469Y221970D03*
X1138535Y226320D03*
X1138469Y219470D03*
Y216970D03*
X1135756Y216385D03*
X1141496Y228646D03*
X1137461Y238589D03*
X1140427Y236121D03*
X1140453Y232971D03*
X1137103Y244571D03*
X1134483Y249108D03*
X1140346Y253198D03*
X1125864Y252371D03*
Y248371D03*
X1137830Y336230D03*
X1129553Y389153D03*
X1127153Y390995D03*
X1129553Y396240D03*
Y403326D03*
Y410413D03*
X1142440Y404718D03*
X1127153Y408568D03*
Y405168D03*
Y394395D03*
X1129553Y424586D03*
Y417499D03*
X1142440Y412718D03*
X1127153Y422741D03*
Y419341D03*
X1129553Y431673D03*
Y438760D03*
X1127153Y436915D03*
Y433515D03*
X1126931Y453564D03*
X1130355Y453483D03*
X1135548Y455804D03*
X1129553Y467539D03*
X1125178Y459792D03*
X1129553Y474626D03*
X1127153Y472781D03*
Y469381D03*
X1134629Y465551D03*
X1129553Y488799D03*
Y481712D03*
X1127153Y486954D03*
Y483554D03*
X1126622Y506256D03*
X1129553Y518760D03*
Y511673D03*
X1127153Y516915D03*
Y513515D03*
X1129553Y532933D03*
Y525846D03*
X1138166Y534759D03*
X1127153Y527688D03*
Y531088D03*
X1139673Y530000D03*
X1138098Y543925D03*
X1138673Y555000D03*
X1139173Y540500D03*
X1138373Y549800D03*
X1138173Y547075D03*
X1126633Y560500D03*
X1137673Y568000D03*
X1138213Y558800D03*
X1138277Y562800D03*
X1125287Y592897D03*
X1129471Y732571D03*
X1129637Y1465913D03*
Y1461182D03*
Y1456451D03*
X1138298Y1465513D03*
Y1460782D03*
X1129637Y1476536D03*
Y1481267D03*
X1138298Y1476136D03*
Y1470244D03*
Y1480867D03*
X1129637Y1471805D03*
Y1496621D03*
X1138298Y1491490D03*
Y1485598D03*
Y1496221D03*
X1129637Y1491890D03*
Y1487159D03*
X1138298Y1500952D03*
Y1511576D03*
X1129637Y1507245D03*
Y1502514D03*
Y1511976D03*
X1138298Y1506845D03*
Y1516307D03*
X1129637Y1563544D03*
Y1558813D03*
X1138298Y1563144D03*
Y1572606D03*
X1129637Y1568275D03*
Y1578898D03*
Y1574167D03*
X1138298Y1567875D03*
Y1578498D03*
X1129637Y1583629D03*
Y1594253D03*
Y1589522D03*
X1138298Y1583229D03*
Y1593853D03*
Y1587960D03*
Y1598584D03*
Y1603315D03*
X1129637Y1609607D03*
Y1598984D03*
Y1604876D03*
X1138298Y1609207D03*
X1129637Y1614338D03*
X1138298Y1613938D03*
Y1618669D03*
X1132000Y1644980D03*
X1147214Y44773D03*
X1154535Y53597D03*
X1153945Y103411D03*
X1145485Y97667D03*
X1154339D03*
X1149735Y95111D03*
X1142134Y109172D03*
X1156885Y116496D03*
Y102323D03*
Y109410D03*
X1152185D03*
Y116497D03*
X1149685D03*
X1144885D03*
X1154585Y114655D03*
Y111255D03*
X1154104Y106561D03*
X1152185Y130670D03*
X1149685D03*
Y123584D03*
X1152185Y123583D03*
X1144885Y130670D03*
Y123584D03*
X1156885Y130670D03*
Y123583D03*
X1154585Y128828D03*
X1147285Y118342D03*
Y121742D03*
Y132515D03*
X1154585Y125428D03*
X1142781Y141228D03*
X1156885Y137756D03*
X1149685Y137757D03*
X1144885D03*
X1147285Y135915D03*
X1148016Y143762D03*
X1145669Y150847D03*
X1149464Y195176D03*
X1148482Y199248D03*
X1151482D03*
X1144464Y195176D03*
X1146964D03*
X1151964D03*
X1153417Y213539D03*
X1151482Y202048D03*
X1146318Y206806D03*
X1144545Y210509D03*
X1147045D03*
X1148818Y206806D03*
X1148482Y201748D03*
X1146237Y230556D03*
X1155082Y230117D03*
X1150492Y227824D03*
X1146863Y238689D03*
X1155098Y238714D03*
X1147637Y247292D03*
X1151098Y238714D03*
X1145222Y242078D03*
X1150579Y246874D03*
X1152799Y244297D03*
X1147590Y253198D03*
X1145761Y324148D03*
X1145587Y339148D03*
X1142440Y392718D03*
Y400718D03*
Y408718D03*
Y396718D03*
X1157451Y618288D03*
X1157251Y636842D03*
X1156275Y656321D03*
X1156023Y678462D03*
X1155146Y699491D03*
X1149437Y728541D03*
X1152512Y728543D03*
X1152316Y746625D03*
X1148962Y747253D03*
X1152485Y764552D03*
X1147468Y766093D03*
X1149345Y771517D03*
X1145910Y794217D03*
X1151277Y790996D03*
X1154652Y791056D03*
X1149627Y813323D03*
X1146985Y812642D03*
X1145910Y803642D03*
X1153485Y813142D03*
X1154985Y802897D03*
X1152510Y844642D03*
X1153229Y848581D03*
X1146960Y1465913D03*
Y1461182D03*
X1155621Y1465513D03*
Y1460782D03*
X1146960Y1456451D03*
X1155621Y1480867D03*
X1146960Y1471805D03*
Y1476536D03*
Y1481267D03*
X1155621Y1476136D03*
Y1470244D03*
Y1491490D03*
Y1485598D03*
Y1496221D03*
X1146960Y1487159D03*
Y1491890D03*
Y1496621D03*
Y1507245D03*
Y1502514D03*
X1155621Y1506845D03*
Y1500952D03*
Y1511576D03*
X1146960Y1511976D03*
X1155621Y1516307D03*
X1146960Y1563544D03*
X1155621Y1563144D03*
X1146960Y1558813D03*
X1155621Y1572606D03*
X1146960Y1568275D03*
X1155621Y1567875D03*
X1146960Y1574167D03*
Y1578898D03*
X1155621Y1578498D03*
X1146960Y1594253D03*
X1155621Y1593853D03*
Y1587960D03*
X1146960Y1583629D03*
X1155621Y1583229D03*
X1146960Y1589522D03*
Y1609607D03*
Y1604876D03*
Y1598984D03*
X1155621Y1609207D03*
Y1598584D03*
Y1603315D03*
X1146960Y1614338D03*
X1155621Y1613938D03*
Y1618669D03*
X1152000Y1644980D03*
X1165347Y82984D03*
Y75184D03*
Y77784D03*
Y80384D03*
X1167756Y92734D03*
X1165347Y85584D03*
X1170447Y90615D03*
X1165135Y90650D03*
X1174768Y99961D03*
X1164885Y95236D03*
Y102323D03*
X1165137Y109410D03*
Y116496D03*
X1165309Y124576D03*
X1166362Y130670D03*
X1171586Y137756D03*
X1166357D03*
X1173630Y207978D03*
Y210478D03*
Y212978D03*
Y215478D03*
Y226226D03*
Y223726D03*
Y228726D03*
Y231226D03*
X1173559Y304948D03*
X1171445Y422088D03*
X1166868Y442956D03*
X1168902Y431029D03*
X1167931Y435029D03*
X1169173Y427017D03*
X1168685Y438323D03*
X1168851Y449873D03*
X1171255Y456287D03*
X1168398Y456309D03*
X1168851Y445873D03*
X1173278Y472579D03*
X1168478D03*
X1163298Y465874D03*
X1170878Y474424D03*
X1173278Y479666D03*
X1168478D03*
Y486752D03*
X1173278D03*
X1170878Y477824D03*
Y488597D03*
X1168478Y493839D03*
X1173278D03*
X1170878Y491997D03*
X1168478Y523800D03*
Y516713D03*
X1173278D03*
Y523800D03*
X1170878Y518558D03*
Y521958D03*
X1173278Y537973D03*
X1168478D03*
X1173278Y530886D03*
X1168478D03*
X1170878Y532731D03*
Y536131D03*
X1161274Y550462D03*
X1159535Y546712D03*
Y542712D03*
X1165400Y553300D03*
X1167900D03*
X1173278Y566752D03*
X1168478D03*
X1170878Y571997D03*
Y568597D03*
X1168478Y580926D03*
X1173278D03*
Y588013D03*
X1168478D03*
X1173278Y573839D03*
X1168478D03*
X1170878Y586171D03*
Y582771D03*
X1168478Y602186D03*
X1173278D03*
Y595099D03*
X1168478D03*
X1170878Y596944D03*
Y600344D03*
X1173278Y609272D03*
X1168478D03*
Y616359D03*
X1173278D03*
X1170878Y614517D03*
Y611117D03*
X1161451Y618288D03*
X1163157Y638125D03*
X1160756Y665140D03*
X1160275Y656321D03*
X1164275D03*
X1162863Y678519D03*
X1159173Y678462D03*
X1170465Y677836D03*
X1157646Y699491D03*
X1162646D03*
X1160146D03*
X1169256Y694983D03*
X1170603Y715281D03*
X1163774Y713347D03*
X1166115Y718469D03*
X1163751Y719498D03*
X1168577Y733812D03*
X1171934Y733857D03*
X1173034Y765060D03*
X1157985Y791142D03*
X1161291Y791662D03*
X1173697Y791911D03*
X1169697Y791935D03*
X1164925Y791607D03*
X1164732Y802269D03*
X1160516Y800900D03*
X1169266Y800799D03*
X1173122Y802759D03*
X1163579Y850774D03*
X1161535Y844167D03*
X1159887Y869106D03*
X1174461Y914515D03*
X1164283Y1465913D03*
Y1456451D03*
Y1461182D03*
X1172944Y1465513D03*
Y1460782D03*
Y1470244D03*
Y1480867D03*
X1164283Y1471805D03*
Y1476536D03*
Y1481267D03*
X1172944Y1476136D03*
X1164283Y1487159D03*
Y1491890D03*
Y1496621D03*
X1172944Y1491490D03*
Y1485598D03*
Y1496221D03*
X1164283Y1507245D03*
Y1502514D03*
X1172944Y1506845D03*
Y1500952D03*
Y1511576D03*
X1164283Y1511976D03*
X1172944Y1516307D03*
X1164283Y1558813D03*
Y1563544D03*
X1172944Y1563144D03*
Y1567875D03*
X1164283Y1574167D03*
Y1578898D03*
X1172944Y1578498D03*
Y1572606D03*
X1164283Y1568275D03*
Y1583629D03*
X1172944Y1583229D03*
X1164283Y1589522D03*
Y1594253D03*
X1172944Y1593853D03*
Y1587960D03*
Y1598584D03*
Y1603315D03*
X1164283Y1609607D03*
Y1604876D03*
Y1598984D03*
X1172944Y1609207D03*
X1164283Y1614338D03*
X1172944Y1613938D03*
Y1618669D03*
X1172000Y1644980D03*
X1174535Y53597D03*
X1183682Y85193D03*
Y82593D03*
Y74793D03*
Y79993D03*
Y77393D03*
X1188278Y94017D03*
X1183726Y92874D03*
X1174818Y95236D03*
X1174861Y103037D03*
X1174995Y116496D03*
Y109410D03*
X1182995Y116496D03*
Y109410D03*
Y102323D03*
X1185753Y107649D03*
Y104249D03*
X1174995Y130670D03*
Y123583D03*
X1182995Y130670D03*
Y123583D03*
Y137756D03*
X1182775Y162368D03*
X1185375D03*
X1188158Y211695D03*
X1184086Y210713D03*
Y213213D03*
Y208213D03*
X1190958Y208695D03*
X1188158D03*
X1184086Y231461D03*
Y228961D03*
X1187793Y226141D03*
X1184086Y226461D03*
X1190593Y226141D03*
X1184086Y223661D03*
Y215713D03*
X1188036Y236611D03*
X1187738Y248891D03*
X1176959Y264180D03*
X1179459D03*
X1177035Y257919D03*
X1185853Y267526D03*
X1188653D03*
X1185853Y270026D03*
X1188653D03*
X1179676Y293796D03*
X1187690Y288190D03*
X1185190Y285690D03*
X1187690D03*
X1185190Y288190D03*
X1177176Y293796D03*
X1176858Y306534D03*
X1179901Y306366D03*
X1181706Y310131D03*
X1178045Y312193D03*
X1181379Y316049D03*
X1174929Y319167D03*
X1182911Y336516D03*
X1177036Y334148D03*
X1179761Y336380D03*
X1187996Y331992D03*
X1188598Y390500D03*
X1191748Y392676D03*
X1188598Y381500D03*
X1179184Y410394D03*
Y403307D03*
X1180118Y430098D03*
Y440098D03*
Y437598D03*
Y435098D03*
Y432598D03*
X1178083Y442856D03*
X1189122Y442606D03*
X1180578Y458406D03*
Y451319D03*
X1176699Y451108D03*
X1176138Y458455D03*
X1179184Y453881D03*
Y446595D03*
X1188739Y446606D03*
X1188378Y466027D03*
X1180402Y462264D03*
X1175778Y465492D03*
X1180578D03*
X1188520Y475262D03*
X1175778Y472579D03*
X1180578D03*
X1178178Y467337D03*
Y470737D03*
X1190046Y463479D03*
X1188520Y489435D03*
Y482666D03*
X1175778Y479666D03*
X1180578Y479665D03*
Y486752D03*
X1175778D03*
X1178178Y484910D03*
Y481510D03*
X1180578Y493839D03*
X1188336Y495088D03*
X1175778Y509626D03*
X1180578Y523799D03*
Y516713D03*
Y509626D03*
X1175778Y516713D03*
Y523800D03*
X1189071Y514608D03*
X1188993Y522134D03*
X1188378Y509626D03*
X1178178Y511471D03*
Y514871D03*
X1180578Y537973D03*
X1175778Y530886D03*
X1180578D03*
X1189475Y535677D03*
X1189636Y529136D03*
X1178178Y529044D03*
Y525644D03*
X1180578Y559665D03*
Y566752D03*
X1175778D03*
Y559665D03*
X1188378D03*
X1188759Y565574D03*
X1178178Y564910D03*
Y561510D03*
X1175778Y580926D03*
X1180578D03*
Y588012D03*
X1175778D03*
X1180578Y573839D03*
X1175778D03*
X1188406Y574338D03*
X1178178Y579084D03*
Y575684D03*
X1175778Y602185D03*
X1180578D03*
X1175778Y595099D03*
X1180578D03*
X1178178Y604030D03*
Y593257D03*
Y589857D03*
X1175778Y609272D03*
X1180578Y616358D03*
Y609272D03*
X1188505Y616358D03*
X1178178Y607430D03*
X1177745Y771744D03*
X1177566Y778539D03*
X1174595Y771744D03*
X1176500Y784933D03*
X1190062Y844378D03*
X1185516Y844248D03*
X1190968Y848703D03*
X1184340Y851072D03*
X1187703Y849734D03*
X1186742Y855466D03*
X1183012Y856553D03*
X1190213Y856816D03*
X1183431Y868340D03*
X1187431D03*
X1180239Y868430D03*
X1177775Y894053D03*
X1176577Y885974D03*
X1179858Y883455D03*
X1179727Y886197D03*
X1181654Y894671D03*
X1185058Y883475D03*
X1178480Y915220D03*
X1187151Y921000D03*
X1178000Y936500D03*
X1188431Y936568D03*
X1182000Y936500D03*
X1189219Y940703D03*
X1187200Y963400D03*
X1181605Y1465913D03*
Y1456451D03*
Y1461182D03*
Y1471805D03*
Y1476536D03*
Y1481267D03*
Y1487159D03*
Y1491890D03*
Y1496621D03*
Y1507245D03*
Y1502514D03*
Y1511976D03*
Y1558813D03*
Y1563544D03*
Y1568275D03*
Y1574167D03*
Y1578898D03*
Y1583629D03*
Y1589522D03*
Y1594253D03*
Y1598984D03*
Y1609607D03*
Y1604876D03*
Y1614338D03*
X1193330Y5374D03*
X1192643Y24773D03*
Y44773D03*
X1205355Y84140D03*
Y76140D03*
Y80140D03*
X1196278Y94017D03*
X1200287D03*
X1192278D03*
X1192007Y101701D03*
Y98551D03*
X1202561Y97475D03*
X1194902Y114623D03*
Y111223D03*
X1202808Y117557D03*
X1197398Y110445D03*
Y115401D03*
X1192406Y110445D03*
Y115401D03*
X1199557Y103783D03*
X1195557D03*
X1202492Y106186D03*
X1205304Y118335D03*
Y121735D03*
X1194902Y128796D03*
X1205304Y132509D03*
X1197398Y129574D03*
Y124618D03*
X1192406D03*
Y129574D03*
X1202808Y122513D03*
Y131731D03*
X1194902Y125396D03*
X1205304Y135909D03*
X1205899Y146461D03*
X1202808Y136687D03*
X1190319Y147540D03*
X1194091Y141247D03*
X1201558Y143740D03*
X1198938Y148277D03*
X1204801Y152367D03*
X1190319Y151540D03*
X1192475Y165393D03*
Y162793D03*
Y167993D03*
Y170493D03*
X1199980Y172190D03*
X1194683Y181366D03*
X1191472Y181426D03*
X1197478Y181009D03*
X1202653Y168697D03*
X1199399Y177616D03*
X1200469Y184619D03*
X1193969Y191941D03*
X1193836Y188727D03*
X1203741Y191941D03*
X1194297Y184012D03*
X1191680Y184221D03*
X1202449Y206760D03*
X1205750Y206767D03*
X1195716Y211359D03*
Y213859D03*
X1199419Y213132D03*
X1190658Y211695D03*
X1192055Y229286D03*
X1195748Y224712D03*
Y222212D03*
X1205295Y224421D03*
X1205880Y221708D03*
X1199419Y215632D03*
X1192055Y231786D03*
X1190536Y236611D03*
X1193036D03*
X1192738Y248891D03*
X1190238D03*
X1203663Y256535D03*
X1195663D03*
X1199663Y256303D03*
X1199422Y265896D03*
X1204438Y266114D03*
X1194335Y265701D03*
X1204693Y279208D03*
X1191153Y267526D03*
Y270026D03*
X1201911Y281982D03*
X1195970Y281716D03*
X1194716Y290755D03*
X1202716D03*
X1190490Y285690D03*
Y288190D03*
X1198716Y290755D03*
X1192500Y322400D03*
X1201113Y315039D03*
X1190127Y324142D03*
X1195800Y324000D03*
X1198248Y381500D03*
X1206531Y393858D03*
X1208173Y398583D03*
X1198468Y430760D03*
X1198489Y433570D03*
X1198305Y437072D03*
X1198346Y439963D03*
X1192702Y440489D03*
X1192957Y435158D03*
X1198552Y452018D03*
X1198590Y443180D03*
X1198610Y454744D03*
X1193000Y444841D03*
X1192686Y449961D03*
X1196403Y458572D03*
X1198689Y465492D03*
X1198655Y460250D03*
X1196420Y470136D03*
X1198689Y472579D03*
Y486752D03*
Y479665D03*
Y493839D03*
Y509626D03*
Y516713D03*
X1195149Y537973D03*
X1197629Y525483D03*
X1197550Y532756D03*
X1198689Y559665D03*
Y566752D03*
X1198539Y579978D03*
X1198689Y573839D03*
X1198753Y608117D03*
X1198997Y790610D03*
X1192431Y868620D03*
X1192152Y884399D03*
X1192367Y903785D03*
X1190210Y900909D03*
X1192990Y914873D03*
X1195118Y936296D03*
X1191151D03*
X1193219Y940703D03*
X1197173Y940645D03*
X1199615Y950670D03*
X1196352Y951033D03*
X1191219Y967757D03*
X1201794Y985289D03*
X1191928Y987314D03*
X1198644Y985289D03*
X1195757Y988131D03*
X1198845Y998504D03*
X1203419Y1011161D03*
X1200008D03*
X1196300Y998600D03*
X1202028Y998349D03*
X1204919Y1021860D03*
X1202268Y1013551D03*
X1199700Y1013661D03*
X1201800Y1019431D03*
X1190267Y1465513D03*
Y1460782D03*
X1198928Y1465914D03*
Y1456452D03*
Y1461183D03*
Y1481268D03*
X1190267Y1476136D03*
Y1470244D03*
Y1480867D03*
X1198928Y1476537D03*
Y1471806D03*
X1190267Y1485598D03*
Y1496221D03*
X1198928Y1491891D03*
Y1487160D03*
Y1496622D03*
X1190267Y1491490D03*
Y1506845D03*
Y1500952D03*
Y1511576D03*
X1198928Y1507246D03*
Y1502515D03*
Y1511977D03*
X1190267Y1516307D03*
X1198928Y1558813D03*
X1190267Y1563144D03*
X1198928Y1563544D03*
X1190267Y1567875D03*
X1198928Y1568275D03*
X1190267Y1578498D03*
Y1572606D03*
X1198928Y1578898D03*
Y1574167D03*
X1190267Y1583229D03*
X1198928Y1583629D03*
X1190267Y1593853D03*
Y1587960D03*
X1198928Y1594253D03*
Y1589522D03*
X1190267Y1609207D03*
Y1598584D03*
Y1603315D03*
X1198928Y1609607D03*
Y1598984D03*
Y1604876D03*
X1190267Y1613938D03*
Y1618669D03*
X1198928Y1614338D03*
X1192000Y1644980D03*
X1212232Y3000D03*
X1219783Y55513D03*
X1216008Y68581D03*
X1222383Y60513D03*
X1216021Y80581D03*
X1208103Y72615D03*
Y76587D03*
X1222511Y85731D03*
X1220126Y91951D03*
X1220151Y88801D03*
X1218204Y103621D03*
X1209542Y100625D03*
X1218730Y117261D03*
X1207800Y117557D03*
X1210724Y103621D03*
X1213915Y112083D03*
X1207800Y122513D03*
Y131731D03*
Y136687D03*
X1210121Y141247D03*
X1214608Y143518D03*
X1213708Y152373D03*
X1216858Y152562D03*
X1222353Y157370D03*
X1206501Y180572D03*
X1211184Y180527D03*
X1217550Y183834D03*
X1212265Y171523D03*
X1217723Y172665D03*
X1217660Y178560D03*
X1214907Y192421D03*
X1206501Y185165D03*
X1211139Y185121D03*
X1218536Y186629D03*
X1211795Y192490D03*
X1210268Y198671D03*
X1217840Y200864D03*
X1217070Y190185D03*
X1207753Y192300D03*
X1208250Y206767D03*
X1210750D03*
X1217863Y207037D03*
X1217929Y212455D03*
X1215230Y221642D03*
X1206995Y228221D03*
X1208380Y221708D03*
X1210880D03*
X1206995Y231021D03*
X1222110Y219379D03*
X1222738Y228631D03*
X1207546Y236189D03*
X1210046D03*
X1212546D03*
X1207487Y248765D03*
X1209987D03*
X1212487D03*
X1208797Y281307D03*
X1219144Y265897D03*
X1216644D03*
X1212984Y268195D03*
X1210184D03*
X1207684D03*
X1212984Y270695D03*
X1207684D03*
X1210184D03*
X1213287Y293645D03*
Y290845D03*
Y288345D03*
X1210787Y293645D03*
Y290845D03*
Y288345D03*
X1217139Y324139D03*
X1220723Y324466D03*
X1221337Y332017D03*
X1220985Y342319D03*
X1211892Y339559D03*
X1215776Y331072D03*
X1213173Y377912D03*
X1217177Y369925D03*
X1206693Y384410D03*
X1213173Y386500D03*
X1209872Y382047D03*
X1212173Y391496D03*
X1206673Y410394D03*
Y403307D03*
X1213261Y397912D03*
X1210173Y403500D03*
X1212173Y409000D03*
X1209426Y433069D03*
Y430469D03*
Y435669D03*
Y440869D03*
Y438269D03*
X1206626Y433069D03*
Y430469D03*
Y435669D03*
Y440869D03*
Y438269D03*
X1206489Y458406D03*
X1212680Y445908D03*
X1216630Y445787D03*
X1209980Y451677D03*
X1207480Y454177D03*
X1209980D03*
X1207480Y451677D03*
X1206489Y465492D03*
Y472579D03*
X1209184Y463618D03*
Y460218D03*
X1206489Y479665D03*
Y486752D03*
Y493839D03*
Y523799D03*
Y516713D03*
Y509626D03*
Y537973D03*
Y530886D03*
Y566752D03*
Y559665D03*
Y580925D03*
Y588012D03*
Y573839D03*
Y602185D03*
Y595099D03*
Y616358D03*
Y609272D03*
X1212000Y1644980D03*
X1231351Y-77080D03*
X1234592Y-79984D03*
X1234604Y-77094D03*
X1231336Y-87691D03*
X1234589Y-87777D03*
X1231351Y-85176D03*
X1234604Y-85262D03*
X1234592Y-82584D03*
X1228311Y-86371D03*
X1222909Y-83456D03*
Y-78500D03*
X1234592Y-71970D03*
X1231336Y-74565D03*
X1234589Y-74579D03*
X1231336Y-64265D03*
X1234589D03*
X1234592Y-69470D03*
X1231351Y-66780D03*
X1234604D03*
X1228311Y-65585D03*
Y-75885D03*
X1222909Y-68500D03*
Y-73456D03*
X1225405Y-72678D03*
Y-69278D03*
X1236692Y-48727D03*
X1236707Y-46212D03*
X1233667Y-47421D03*
X1228265Y-44406D03*
X1236692Y-35515D03*
X1236707Y-38030D03*
X1233667Y-36835D03*
X1228265Y-39450D03*
Y-29450D03*
Y-34406D03*
X1230761Y-33628D03*
Y-30228D03*
X1236692Y-25215D03*
X1236707Y-27730D03*
X1233667Y-26535D03*
X1232232Y3000D03*
X1222933Y55513D03*
X1228097Y60922D03*
X1225243Y60438D03*
X1230924Y86012D03*
X1225041Y97080D03*
X1238479Y102249D03*
X1230924Y94374D03*
X1226065Y86046D03*
X1227017Y94279D03*
X1223068Y94351D03*
X1230479Y102249D03*
X1234479D03*
X1228910Y110784D03*
X1226261Y113394D03*
X1238230Y116594D03*
X1226261D03*
X1232204Y110784D03*
X1237204D03*
X1229195Y130898D03*
X1236504Y133298D03*
X1238230Y119594D03*
X1226261D03*
X1236783Y124663D03*
X1226695Y124283D03*
X1231761Y124879D03*
X1230651Y134579D03*
X1238127Y138838D03*
X1225102Y161306D03*
X1226437Y180665D03*
Y172665D03*
Y176665D03*
Y168665D03*
X1236779Y195176D03*
X1236398Y198883D03*
X1234279Y195176D03*
X1239579D03*
X1231779D03*
X1226437Y192665D03*
X1226550Y186778D03*
X1236398Y201683D03*
X1234139Y203393D03*
X1231639D03*
X1226469Y200864D03*
Y212864D03*
X1237827Y206838D03*
X1226469Y204864D03*
Y208864D03*
Y216864D03*
Y221864D03*
X1231518Y218085D03*
X1234318D03*
X1238118Y216385D03*
X1239465Y244571D03*
X1236845Y249108D03*
X1228226Y252371D03*
Y248371D03*
X1238055Y303839D03*
X1229252Y314890D03*
X1229028Y311740D03*
X1234100Y322924D03*
X1224186Y316731D03*
X1226436Y324518D03*
X1229922Y324550D03*
X1234904Y316942D03*
X1232197Y316964D03*
X1238293Y317296D03*
X1230077Y336324D03*
X1229438Y332584D03*
X1234656Y353506D03*
X1235589Y348015D03*
X1229942Y347937D03*
X1231506Y353470D03*
X1223431Y377912D03*
X1225755Y369391D03*
X1229122Y369355D03*
X1222601Y369251D03*
X1223431Y393924D03*
Y389912D03*
Y385912D03*
Y381912D03*
Y409924D03*
Y405924D03*
Y401924D03*
Y397912D03*
X1232670Y466528D03*
X1237662D03*
X1232670Y471484D03*
X1237662D03*
X1235166Y470706D03*
Y467306D03*
X1237662Y480701D03*
X1232670D03*
Y485657D03*
X1237662D03*
X1235166Y484879D03*
Y481479D03*
X1232670Y515617D03*
X1237662D03*
X1232670Y510661D03*
X1237662D03*
X1235166Y514839D03*
Y511439D03*
X1237662Y524835D03*
Y529791D03*
X1232670Y524835D03*
Y529791D03*
X1235166Y529013D03*
Y525613D03*
X1232833Y539315D03*
X1232149Y550137D03*
X1234941D03*
X1232670Y565657D03*
Y560701D03*
X1237662Y565657D03*
Y560701D03*
X1235166Y564879D03*
Y561479D03*
X1232670Y579830D03*
X1237662Y589047D03*
X1232670D03*
X1237662Y574874D03*
X1232670D03*
X1237662Y579830D03*
X1235166Y575652D03*
Y579052D03*
X1237662Y603221D03*
X1232670D03*
Y594003D03*
X1237662D03*
X1235166Y593225D03*
Y603999D03*
Y589825D03*
X1237662Y608177D03*
X1232670D03*
X1235166Y607399D03*
X1235930Y626229D03*
X1235292Y622912D03*
X1237500Y632405D03*
X1238034Y629961D03*
X1238695Y627313D03*
X1232000Y1644980D03*
X1239945Y-48727D03*
X1239960Y-46212D03*
X1239948Y-32920D03*
X1239945Y-35529D03*
X1239948Y-30420D03*
Y-40934D03*
X1239960Y-38044D03*
X1239948Y-43534D03*
X1239945Y-25215D03*
X1239960Y-27730D03*
X1248216Y4469D03*
X1249577Y24773D03*
Y44773D03*
X1256307Y103411D03*
X1247847Y97667D03*
X1256701D03*
X1252097Y95111D03*
X1243503Y106495D03*
X1244496Y109172D03*
X1241496D03*
X1247247Y116497D03*
X1254547Y109410D03*
Y116497D03*
X1252047D03*
X1243503Y102495D03*
X1247247Y123584D03*
Y130670D03*
X1252047Y123584D03*
X1254547Y123583D03*
Y130670D03*
X1252047D03*
X1249647Y118342D03*
Y132515D03*
Y121742D03*
X1241764Y125107D03*
X1243237Y146012D03*
X1245143Y141228D03*
X1247247Y137757D03*
X1252047D03*
X1250307Y140296D03*
X1249647Y135915D03*
X1243237Y142862D03*
X1250378Y143762D03*
X1244278Y148717D03*
X1248031Y150847D03*
X1251826Y195176D03*
X1254326D03*
X1253844Y199248D03*
X1249326Y195176D03*
X1250844Y199248D03*
X1246826Y195176D03*
X1240327Y206838D03*
X1249407Y210509D03*
X1253844Y202048D03*
X1250844Y201748D03*
X1251180Y206806D03*
X1248680D03*
X1246907Y210509D03*
X1240831Y221970D03*
X1240897Y226320D03*
X1240831Y219470D03*
Y216970D03*
X1248599Y230556D03*
X1252854Y227824D03*
X1243858Y228646D03*
X1249999Y247292D03*
X1239823Y238589D03*
X1242789Y236121D03*
X1253460Y238714D03*
X1247584Y242078D03*
X1252941Y246874D03*
X1242815Y232971D03*
X1242708Y253198D03*
X1246808Y256394D03*
X1241205Y303962D03*
X1253245Y416888D03*
Y419488D03*
Y422088D03*
X1243072Y473640D03*
X1248064D03*
X1245568Y474418D03*
X1243072Y487813D03*
X1248064D03*
X1243072Y478596D03*
X1248064D03*
X1245568Y488591D03*
Y477818D03*
X1243072Y492769D03*
X1248064D03*
X1245568Y491991D03*
X1243072Y522730D03*
X1248064Y517774D03*
Y522730D03*
X1243072Y517774D03*
X1245568Y521952D03*
Y518552D03*
X1248064Y531947D03*
Y536903D03*
X1243072D03*
Y531947D03*
X1245568Y536125D03*
Y532725D03*
X1253087Y553101D03*
X1241629Y550065D03*
X1248064Y567813D03*
X1241752Y564843D03*
X1243072Y567813D03*
X1248064Y572769D03*
X1243072D03*
X1245568Y568591D03*
Y571991D03*
X1248064Y581987D03*
Y586943D03*
X1243072D03*
Y581987D03*
X1245568Y582765D03*
Y586165D03*
X1243072Y601116D03*
X1248064D03*
X1243072Y596160D03*
X1248064D03*
X1245568Y596938D03*
Y600338D03*
X1243072Y610333D03*
Y615289D03*
X1248064D03*
Y610333D03*
X1245568Y611111D03*
Y614511D03*
X1246800Y1001600D03*
X1248106Y1004700D03*
X1245400Y1003700D03*
X1249200Y1014000D03*
X1248721Y1025864D03*
X1246000Y1014800D03*
X1252148Y1026223D03*
X1252500Y1014288D03*
X1246300Y1027800D03*
X1253424Y1138130D03*
X1250928Y1142828D03*
X1254200Y1146600D03*
X1249363Y1173065D03*
X1256218Y1175987D03*
X1249363Y1166065D03*
X1255439Y1172008D03*
X1251802Y1186071D03*
X1255628Y1188345D03*
X1253056Y1194917D03*
X1245900Y1528000D03*
X1254275Y1531334D03*
X1249894Y1527805D03*
X1253904Y1519645D03*
X1254275Y1539334D03*
X1250434Y1535334D03*
X1256898Y53597D03*
X1267709Y82984D03*
Y75184D03*
Y77784D03*
Y80384D03*
X1270263Y92849D03*
X1267709Y85584D03*
X1267497Y90650D03*
X1267247Y95236D03*
X1267499Y116496D03*
X1259247D03*
Y102323D03*
Y109410D03*
X1267247Y102323D03*
X1267499Y109410D03*
X1256947Y114655D03*
Y111255D03*
X1256466Y106561D03*
X1267671Y124576D03*
X1268724Y130670D03*
X1259247D03*
Y123583D03*
X1256947Y128828D03*
Y125428D03*
X1268719Y137756D03*
X1259247D03*
X1255779Y213539D03*
X1257444Y230117D03*
X1257460Y238714D03*
X1255161Y244297D03*
X1264481Y300223D03*
X1266962Y302167D03*
X1262665Y302730D03*
X1263328Y309003D03*
X1258925Y324075D03*
X1262075D03*
X1261659Y318258D03*
X1264088Y320382D03*
X1266616Y322456D03*
X1259500Y330000D03*
X1257000Y333500D03*
X1264215Y333215D03*
X1262500Y330655D03*
X1256000Y338000D03*
X1259991Y340691D03*
X1256000Y340500D03*
X1263500Y336000D03*
X1266219Y374300D03*
X1268659Y377173D03*
X1264659D03*
X1267944Y371767D03*
X1261764Y391533D03*
X1263484Y385644D03*
X1268659Y385123D03*
X1268067Y406060D03*
X1261231Y399918D03*
X1264336Y412106D03*
X1268328Y421489D03*
Y418889D03*
Y416289D03*
X1261623Y447486D03*
X1259223Y458334D03*
X1270397Y447081D03*
X1259223Y454334D03*
X1267540Y459330D03*
X1267493Y454214D03*
X1267836Y449045D03*
X1267843Y473571D03*
Y488618D03*
Y491118D03*
Y481071D03*
Y478571D03*
Y476071D03*
Y493618D03*
X1270951Y491870D03*
X1269629Y848124D03*
X1270892Y856343D03*
X1271121Y892513D03*
X1270276Y897062D03*
X1269221Y894760D03*
X1270515Y908277D03*
X1270586Y905324D03*
X1272661Y929858D03*
X1269876Y1132319D03*
X1260539Y1134729D03*
X1267921D03*
X1266718Y1142666D03*
X1263921Y1134729D03*
X1263873Y1148000D03*
X1268593Y1157544D03*
X1266709Y1160168D03*
X1267104Y1167768D03*
X1272123D03*
X1258736Y1188223D03*
X1271246Y1178240D03*
X1271256Y1185205D03*
X1262605Y1187215D03*
X1262298Y1180175D03*
X1260800Y1191096D03*
X1268573Y1193019D03*
X1264573D03*
X1268571Y1201043D03*
X1264575D03*
X1261538Y1199814D03*
X1255296Y1196056D03*
X1263449Y1217228D03*
X1266113Y1219895D03*
X1269388Y1223170D03*
X1263242Y1523458D03*
X1262985Y1519459D03*
X1267333Y1531334D03*
X1262891Y1527334D03*
X1260260Y1546500D03*
X1267183Y1539334D03*
X1262891Y1535334D03*
X1276898Y53597D03*
X1286044Y85539D03*
Y82939D03*
Y75139D03*
Y80339D03*
Y77739D03*
X1286088Y92874D03*
X1272809Y90615D03*
X1277130Y99961D03*
X1277180Y95236D03*
X1277223Y103037D03*
X1277357Y116496D03*
Y109410D03*
X1285357Y116496D03*
Y109410D03*
Y102323D03*
Y123583D03*
X1277357Y130670D03*
Y123583D03*
X1285357Y130670D03*
X1273555Y137756D03*
X1285357D03*
X1285137Y162368D03*
X1275992Y215478D03*
Y212978D03*
Y210478D03*
Y207978D03*
X1286448Y213213D03*
Y210713D03*
Y208213D03*
X1275992Y223726D03*
Y226226D03*
Y231226D03*
Y228726D03*
X1286448Y223661D03*
Y226461D03*
Y228961D03*
Y231461D03*
Y215713D03*
X1281821Y264180D03*
X1279321D03*
X1279246Y258880D03*
X1279538Y293796D03*
X1282038D03*
X1271571Y281185D03*
X1289345Y330655D03*
X1283494Y339495D03*
X1284419Y359377D03*
X1281834Y374839D03*
X1287437Y370010D03*
Y379429D03*
X1280699Y377173D03*
X1284659D03*
X1274436Y377350D03*
X1275940Y392228D03*
X1271346Y392183D03*
X1276659Y385123D03*
X1273659D03*
X1280659D03*
X1284333Y391569D03*
X1275407Y402867D03*
X1271391Y396866D03*
X1275984D03*
X1282760Y409016D03*
X1278724Y409032D03*
X1282760Y401066D03*
X1272421Y403300D03*
X1271828Y405889D03*
Y408489D03*
Y413689D03*
Y411089D03*
Y416289D03*
Y421489D03*
Y418889D03*
Y424089D03*
X1272215Y442518D03*
Y439718D03*
Y432718D03*
Y435518D03*
X1282092Y442118D03*
Y439318D03*
X1271828Y426689D03*
X1279127Y450091D03*
X1282092Y449118D03*
Y446318D03*
X1281737Y452740D03*
X1272927Y450091D03*
X1275927D03*
X1273397Y447081D03*
X1281737Y461034D03*
Y456034D03*
X1283455Y468088D03*
Y465288D03*
X1280616Y472189D03*
X1272927Y462060D03*
X1275927D03*
X1279505Y487570D03*
Y490070D03*
X1286005Y485580D03*
X1280631Y480194D03*
Y477694D03*
X1277897Y478876D03*
Y476376D03*
X1274415Y477053D03*
X1271915D03*
X1276060Y496258D03*
X1273451Y491870D03*
X1276060Y493758D03*
X1284900Y678800D03*
X1283400Y715500D03*
X1278255Y722241D03*
X1283400Y719700D03*
X1282539Y746076D03*
X1279539Y748576D03*
X1282539Y751076D03*
X1279539Y763576D03*
X1282539Y766076D03*
X1279539Y758576D03*
X1282539Y756076D03*
Y761076D03*
X1279539Y753576D03*
Y772576D03*
Y776576D03*
Y768576D03*
Y780576D03*
Y784576D03*
X1285092Y819500D03*
X1285500Y827500D03*
X1281388Y827388D03*
X1281777Y823500D03*
X1285500Y843500D03*
X1281331Y843331D03*
X1281269Y835492D03*
X1285500Y835500D03*
X1283025Y848305D03*
X1274417Y861964D03*
X1271438Y861846D03*
X1285500Y863500D03*
Y859500D03*
Y855500D03*
Y851500D03*
X1279460Y854487D03*
Y859487D03*
Y864487D03*
X1274396Y866896D03*
X1282317Y880193D03*
X1285500Y867500D03*
X1279460Y874487D03*
Y869487D03*
Y879487D03*
X1285302Y877283D03*
X1282285Y865602D03*
X1285493Y892175D03*
X1274264Y898591D03*
X1279460Y884487D03*
X1285302Y885783D03*
X1279299Y898813D03*
X1279460Y889487D03*
X1285302Y881783D03*
X1281075Y911075D03*
X1282184Y898854D03*
X1274400Y914123D03*
X1283494Y907176D03*
X1277039Y916484D03*
X1275493Y929858D03*
X1279493D03*
X1283493D03*
X1279693Y919800D03*
X1274670Y919808D03*
X1284021Y940008D03*
X1281400Y940256D03*
X1289547Y941000D03*
X1281733Y949475D03*
X1275788Y1124088D03*
X1273865Y1132497D03*
X1282421Y1137129D03*
X1271921Y1134729D03*
X1275794D03*
X1282830Y1146937D03*
Y1150087D03*
X1275050Y1157404D03*
X1272120Y1159455D03*
X1280306Y1162817D03*
Y1170767D03*
X1275965Y1187232D03*
X1280602Y1185238D03*
X1280395Y1180235D03*
X1276573Y1193019D03*
X1280573D03*
X1272573D03*
X1272541Y1201043D03*
X1276575Y1201039D03*
X1280575Y1200969D03*
X1277108Y1211664D03*
X1279402Y1213958D03*
X1275032Y1209589D03*
X1284198Y1218754D03*
X1280694Y1208993D03*
X1274446Y1228226D03*
X1272235Y1226016D03*
X1291756Y-48669D03*
X1288503D03*
X1291741Y-46154D03*
X1288488D03*
X1294781Y-47349D03*
X1300183Y-44434D03*
X1288500Y-40964D03*
X1291756Y-38369D03*
X1288503Y-38355D03*
X1288500Y-43464D03*
X1291741Y-35854D03*
X1288500Y-32950D03*
X1288488Y-35840D03*
X1288500Y-30350D03*
X1294781Y-37049D03*
X1300183Y-29478D03*
Y-34434D03*
Y-39478D03*
X1297687Y-33656D03*
Y-30256D03*
X1291756Y-25143D03*
X1288503Y-25157D03*
X1291741Y-27658D03*
X1288488Y-27672D03*
X1294781Y-26463D03*
X1302232Y3000D03*
X1295692Y5374D03*
X1303229Y23274D03*
X1295005Y24773D03*
X1297785Y30618D03*
Y33768D03*
X1302139Y26325D03*
X1302785Y31168D03*
X1295005Y44773D03*
X1302649Y94017D03*
X1298640D03*
X1290640D03*
X1294369Y101701D03*
X1294640Y94017D03*
X1294369Y98551D03*
X1304923Y97475D03*
X1297264Y114623D03*
Y111223D03*
X1301919Y103783D03*
X1299760Y110445D03*
Y115401D03*
X1294768Y110445D03*
Y115401D03*
X1297919Y103783D03*
X1288115Y104249D03*
Y107649D03*
X1297264Y128796D03*
Y125396D03*
X1294768Y129574D03*
X1299760D03*
Y124618D03*
X1294768D03*
X1294837Y162793D03*
X1287737Y162368D03*
X1294837Y165393D03*
Y167993D03*
Y170493D03*
X1301761Y177616D03*
X1302342Y172190D03*
X1299840Y181009D03*
X1293834Y181426D03*
X1297045Y181366D03*
X1296331Y191941D03*
X1302831Y184619D03*
X1296198Y188727D03*
X1294042Y184221D03*
X1296659Y184012D03*
X1301781Y213132D03*
X1298078Y211359D03*
Y213859D03*
X1290520Y211695D03*
X1293020D03*
X1290520Y208695D03*
X1293320D03*
X1292955Y226141D03*
X1290155D03*
X1294417Y229286D03*
X1298110Y222212D03*
Y224712D03*
X1301781Y215632D03*
X1290398Y236611D03*
X1295398D03*
X1292898D03*
X1294417Y231786D03*
X1298025Y256535D03*
X1290100Y248891D03*
X1292600D03*
X1295100D03*
X1302025Y256303D03*
X1296697Y265701D03*
X1301784Y265896D03*
X1293515Y270026D03*
X1291015D03*
X1288215D03*
Y267526D03*
X1293515D03*
X1291015D03*
X1304273Y281982D03*
X1298332Y281716D03*
X1290052Y288190D03*
X1292852D03*
Y285690D03*
X1305078Y290755D03*
X1297078D03*
X1301078D03*
X1287552Y288190D03*
X1290052Y285690D03*
X1287552D03*
X1301500Y329000D03*
X1294425Y321425D03*
X1294000Y324000D03*
X1303000Y326692D03*
X1292731Y331820D03*
X1300400Y339619D03*
Y344575D03*
X1293000Y338500D03*
X1303000Y331000D03*
X1302896Y343797D03*
Y340397D03*
X1292500Y335000D03*
X1299959Y351454D03*
Y356954D03*
X1294080Y349820D03*
X1303158Y371043D03*
X1299410Y370976D03*
X1291410Y371060D03*
X1295410Y371076D03*
X1293048Y379088D03*
X1298346Y379028D03*
X1291165Y395248D03*
X1293100Y409539D03*
X1296100D03*
X1293100Y406739D03*
X1296100Y407039D03*
X1295764Y401981D03*
X1298264D03*
X1300037Y398278D03*
X1297537D03*
X1292618Y413611D03*
X1295118D03*
X1300118D03*
X1297618D03*
X1292383Y424067D03*
X1294883D03*
X1299883D03*
X1297383D03*
X1299757Y438293D03*
Y441093D03*
X1290092Y442118D03*
Y439318D03*
Y449118D03*
Y446318D03*
X1299757Y450041D03*
Y452841D03*
Y455641D03*
X1290272Y458309D03*
Y454309D03*
X1299757Y443893D03*
X1290272Y462309D03*
X1287719Y470001D03*
X1290219D03*
X1299867Y477318D03*
X1299466Y466409D03*
X1299807Y472020D03*
X1288144Y489036D03*
X1291005Y485580D03*
X1288505D03*
X1301314Y484882D03*
X1299304Y487382D03*
X1290380Y495636D03*
Y492836D03*
X1296783Y511956D03*
X1300817Y568635D03*
X1301194Y565518D03*
X1305836Y660009D03*
X1298963Y659609D03*
X1289811Y677612D03*
X1289317Y706932D03*
X1303520Y748403D03*
X1291604Y781576D03*
Y776576D03*
Y771435D03*
X1295491Y798821D03*
X1298720Y798975D03*
X1290066Y804246D03*
X1289730Y806845D03*
X1302140Y812625D03*
X1300516Y832047D03*
X1302501Y824747D03*
X1297667Y832150D03*
X1293500Y827500D03*
X1300504Y835985D03*
X1293500Y843500D03*
Y835500D03*
X1296687Y839500D03*
X1300204Y859088D03*
X1300097Y851193D03*
X1300091Y854824D03*
X1293500Y851500D03*
X1294000Y863500D03*
X1293500Y879800D03*
Y871800D03*
Y875800D03*
X1288164Y892354D03*
X1296866Y894993D03*
X1305250Y889250D03*
X1293272Y887800D03*
X1293500Y883800D03*
X1291129Y892267D03*
X1291955Y901295D03*
X1294264Y905595D03*
X1301657Y899129D03*
X1288500Y901254D03*
X1298966Y899610D03*
X1296466D03*
X1289547Y928047D03*
X1298000Y917000D03*
X1294075D03*
X1304949Y928546D03*
X1292500Y928000D03*
X1295453Y928047D03*
X1291059Y917000D03*
X1302000D03*
X1298090Y940852D03*
X1295453Y940953D03*
X1302500Y939500D03*
X1300882Y937144D03*
X1296500Y961500D03*
X1289500Y949500D03*
X1300500Y960000D03*
X1290792Y961363D03*
X1300500Y970187D03*
X1297558Y970216D03*
X1292836Y975244D03*
X1292631Y979845D03*
X1299717Y1024136D03*
X1297852Y1014475D03*
X1295815Y1124943D03*
X1295893Y1122182D03*
X1302866Y1461182D03*
Y1456451D03*
Y1465913D03*
Y1476536D03*
Y1471805D03*
Y1481267D03*
Y1491890D03*
Y1487159D03*
Y1496621D03*
Y1507245D03*
Y1502514D03*
Y1511976D03*
Y1558813D03*
Y1563544D03*
Y1578898D03*
Y1574167D03*
Y1568275D03*
Y1594253D03*
Y1589522D03*
Y1583629D03*
Y1609607D03*
Y1598984D03*
Y1604876D03*
Y1614338D03*
X1292000Y1644980D03*
X1310853Y37543D03*
X1314887Y45448D03*
X1318859D03*
X1307717Y84140D03*
Y76140D03*
Y80140D03*
X1311904Y100625D03*
X1320566Y103621D03*
X1310162Y117557D03*
X1305170D03*
X1313086Y103621D03*
X1304854Y106186D03*
X1316277Y112083D03*
X1307666Y118335D03*
Y132509D03*
Y121735D03*
X1310162Y122513D03*
Y131731D03*
X1305170Y122513D03*
Y131731D03*
X1307666Y135909D03*
X1310162Y136687D03*
X1305170D03*
X1313546Y180527D03*
X1308863Y180572D03*
X1305015Y168697D03*
X1319912Y183834D03*
X1314627Y171523D03*
X1320085Y172665D03*
X1320022Y178560D03*
X1308863Y185165D03*
X1317269Y192421D03*
X1313501Y185121D03*
X1306103Y191941D03*
X1319432Y190185D03*
X1314157Y192490D03*
X1320202Y200864D03*
X1310115Y192300D03*
X1304811Y206760D03*
X1308112Y206767D03*
X1313112D03*
X1310612D03*
X1320225Y207037D03*
X1320291Y212455D03*
X1313242Y221708D03*
X1310742D03*
X1309357Y231021D03*
Y228221D03*
X1317592Y221642D03*
X1308242Y221708D03*
X1307657Y224421D03*
X1309908Y236189D03*
X1314908D03*
X1312408D03*
X1306025Y256535D03*
X1312349Y248765D03*
X1309849D03*
X1314849D03*
X1306800Y266114D03*
X1307055Y279208D03*
X1311159Y281307D03*
X1310046Y268195D03*
X1312546D03*
X1315346D03*
X1319006Y265897D03*
X1312546Y270695D03*
X1310046D03*
X1315346D03*
X1313149Y288345D03*
Y290845D03*
Y293645D03*
X1315649Y288345D03*
Y290845D03*
Y293645D03*
X1318362Y310562D03*
X1314569Y318013D03*
X1312069D03*
X1317584Y313058D03*
X1305928Y318250D03*
X1308428D03*
X1315256Y336510D03*
X1313103Y339606D03*
X1312240Y334681D03*
X1315397Y333709D03*
X1316017Y349889D03*
X1308012Y348109D03*
X1308410Y370899D03*
X1305910Y377581D03*
X1310172Y367956D03*
X1308410Y379591D03*
X1311283Y370801D03*
X1308826Y389402D03*
X1306113Y383817D03*
X1312626Y387702D03*
X1315426D03*
X1306113Y386317D03*
Y388817D03*
X1313691Y402642D03*
X1316191D03*
X1310546Y409904D03*
Y407104D03*
X1309117Y398949D03*
X1306617Y401949D03*
X1308066Y413611D03*
X1310866D03*
X1313366D03*
X1315866D03*
X1315806Y423944D03*
X1313306D03*
X1310806D03*
X1308006D03*
X1309750Y438293D03*
Y441093D03*
Y455641D03*
Y450041D03*
Y452841D03*
Y443893D03*
X1308010Y466409D03*
X1311488Y471560D03*
X1307819Y474382D03*
X1307835Y470382D03*
X1319474Y467560D03*
X1319974Y475560D03*
X1307996Y487382D03*
X1311488Y479560D03*
X1307919Y478382D03*
X1307825Y482382D03*
X1311488Y475560D03*
X1318160Y520053D03*
X1317945Y523058D03*
X1319000Y566500D03*
Y562500D03*
Y558500D03*
Y582500D03*
Y586500D03*
Y574500D03*
Y578500D03*
Y605000D03*
Y590500D03*
X1319323Y598454D03*
X1319000Y613000D03*
Y621000D03*
Y609000D03*
Y629000D03*
Y633000D03*
Y625000D03*
Y637000D03*
Y653500D03*
Y649500D03*
Y641000D03*
Y657500D03*
Y669500D03*
Y665500D03*
Y673500D03*
Y681500D03*
Y677500D03*
X1313979Y677726D03*
X1319000Y685500D03*
Y696500D03*
Y700500D03*
Y704500D03*
Y712500D03*
Y716500D03*
Y720500D03*
Y724500D03*
Y728500D03*
Y732500D03*
X1305412Y799061D03*
X1321000Y796000D03*
X1313000D03*
X1317000Y799000D03*
Y788000D03*
X1313000D03*
X1305134Y812065D03*
X1315000Y811620D03*
X1319000D03*
X1317000Y804000D03*
X1313000D03*
X1321000D03*
X1310715Y820491D03*
Y822991D03*
Y817991D03*
X1310687Y830206D03*
Y832706D03*
Y827706D03*
X1308857Y836076D03*
X1310971Y842319D03*
X1305786Y867704D03*
X1310994Y866859D03*
X1309753Y877589D03*
X1305740Y877534D03*
X1310535Y870775D03*
X1308220Y889253D03*
X1311061Y889361D03*
X1314500Y911500D03*
X1319500Y901500D03*
X1314500Y905000D03*
X1305356Y902597D03*
X1319500Y905000D03*
X1316893Y925603D03*
X1309103Y917000D03*
X1313867Y925605D03*
X1311325Y928918D03*
X1319554Y925585D03*
X1318375Y943951D03*
X1309103Y936559D03*
X1306500Y936500D03*
X1315779Y943743D03*
X1313152Y936605D03*
X1312575Y943974D03*
X1321256Y943815D03*
X1303907Y960093D03*
X1311000Y961500D03*
X1307000Y960500D03*
X1315441Y960000D03*
X1307000Y970000D03*
X1311000Y970124D03*
X1307707Y979870D03*
X1307580Y990314D03*
X1317254Y990777D03*
X1317053Y988111D03*
X1319874Y989856D03*
X1307561Y986951D03*
X1304664Y1023462D03*
X1309937Y1037038D03*
X1319326Y1040723D03*
X1315606Y1042825D03*
X1315756Y1039344D03*
X1312873Y1036543D03*
X1306385Y1036646D03*
X1319221Y1058097D03*
Y1060697D03*
X1313459Y1081599D03*
X1310589Y1097278D03*
X1313089D03*
X1316869Y1107997D03*
X1319069Y1112397D03*
X1318969Y1109397D03*
X1316869Y1113797D03*
Y1110897D03*
X1317437Y1152684D03*
Y1160834D03*
X1318178Y1198321D03*
Y1200821D03*
Y1192621D03*
Y1190121D03*
X1319237Y1221428D03*
X1311237D03*
X1315237D03*
X1311237Y1233428D03*
Y1229428D03*
Y1225428D03*
X1315237Y1237428D03*
Y1233428D03*
Y1229428D03*
Y1225428D03*
X1319237Y1237428D03*
Y1233428D03*
Y1229428D03*
Y1225428D03*
X1307167Y1245696D03*
X1315237Y1241428D03*
X1319237D03*
X1308276Y1276446D03*
X1308107Y1283395D03*
X1310773Y1282411D03*
X1303900Y1288000D03*
X1318287Y1295381D03*
Y1291381D03*
X1311527Y1465513D03*
Y1460782D03*
Y1480867D03*
Y1476136D03*
Y1470244D03*
Y1491490D03*
Y1485598D03*
Y1496221D03*
Y1506845D03*
Y1500952D03*
Y1511576D03*
Y1516307D03*
Y1563144D03*
Y1567875D03*
Y1578498D03*
Y1572606D03*
Y1583229D03*
Y1593853D03*
Y1587960D03*
Y1609207D03*
Y1598584D03*
Y1603315D03*
Y1613938D03*
Y1618669D03*
X1312000Y1644980D03*
X1328500Y-80100D03*
X1331756Y-77419D03*
X1328503Y-77405D03*
X1331756Y-87805D03*
X1328503D03*
X1328500Y-82600D03*
X1331741Y-85290D03*
X1328488D03*
X1334781Y-86499D03*
X1331741Y-74904D03*
X1328500Y-72000D03*
X1328488Y-74890D03*
X1331756Y-64193D03*
X1328503Y-64207D03*
X1331741Y-66708D03*
X1328488Y-66722D03*
X1328500Y-69400D03*
X1334781Y-76099D03*
Y-65513D03*
X1322232Y3000D03*
X1324120Y22742D03*
X1334223Y33425D03*
X1331073Y33400D03*
X1328003Y32403D03*
X1328318Y27333D03*
X1336623Y30483D03*
X1322853Y37530D03*
X1321092Y117261D03*
X1328799Y172665D03*
Y180665D03*
Y168665D03*
Y176665D03*
X1320898Y186629D03*
X1328799Y192665D03*
Y196665D03*
X1328912Y186778D03*
X1328831Y212864D03*
Y200864D03*
Y204864D03*
Y208864D03*
Y221864D03*
Y216864D03*
X1324472Y219379D03*
X1325100Y228631D03*
X1321506Y265897D03*
X1330414Y310058D03*
X1325458D03*
X1334110Y310562D03*
X1321762D03*
X1329636Y307562D03*
X1326236D03*
X1322540Y313058D03*
X1333332D03*
X1332563Y326356D03*
X1325573Y326719D03*
X1332359Y322685D03*
X1331085Y334347D03*
X1323816D03*
Y341615D03*
X1331085Y348868D03*
X1323816D03*
X1326489Y356945D03*
X1331005Y356670D03*
X1331922Y359836D03*
X1320903Y370995D03*
X1333331Y370905D03*
X1329064Y370951D03*
X1325007D03*
X1334109Y373401D03*
X1334285Y386567D03*
X1331606D03*
X1328896D03*
X1320594Y387151D03*
Y382151D03*
Y384651D03*
X1333049Y399268D03*
Y401768D03*
Y396768D03*
X1321016Y399161D03*
Y401661D03*
Y396661D03*
X1325941Y408240D03*
X1328441D03*
X1323441D03*
X1326059Y420393D03*
X1326020Y424240D03*
X1323559Y420393D03*
X1328559D03*
X1326020Y426740D03*
X1329097Y435321D03*
Y438121D03*
X1326297Y435321D03*
Y438121D03*
X1329097Y440921D03*
X1326297D03*
X1329626Y455039D03*
X1329097Y443721D03*
X1326297D03*
X1335440Y452799D03*
X1329083Y448931D03*
X1332927Y468607D03*
X1325927Y474513D03*
X1329606Y459170D03*
X1332974Y474513D03*
X1326912Y493153D03*
X1325630Y513238D03*
X1321450Y520268D03*
X1321164Y523130D03*
X1326993Y556788D03*
X1331096Y549931D03*
X1327043Y573346D03*
X1327000Y562500D03*
X1326946Y567906D03*
X1338000Y562500D03*
X1335000Y590500D03*
Y586500D03*
X1327000Y578500D03*
Y583826D03*
X1335000Y594500D03*
X1327000Y605000D03*
Y594500D03*
Y609000D03*
X1333224Y615484D03*
X1327000Y613000D03*
Y621000D03*
X1335532Y622260D03*
X1338000Y609000D03*
X1335000Y633000D03*
Y637000D03*
X1327000Y629000D03*
X1327003Y623940D03*
X1335000Y641000D03*
X1338000Y653500D03*
X1327000Y641000D03*
X1327011Y646064D03*
X1327000Y657500D03*
X1335000Y677500D03*
Y681500D03*
Y685500D03*
X1327000D03*
Y695500D03*
Y700500D03*
X1338000D03*
X1327000Y711500D03*
Y716500D03*
X1335000Y724500D03*
Y728500D03*
Y732500D03*
X1327000D03*
X1330295Y746328D03*
X1326970Y736464D03*
X1336661Y753675D03*
Y745675D03*
Y737675D03*
X1330295Y751328D03*
X1330086Y763758D03*
X1324217Y780595D03*
X1330324Y779030D03*
X1336746Y781675D03*
X1329000Y796000D03*
X1325000Y799000D03*
X1337000Y796000D03*
X1333000Y799000D03*
Y788000D03*
X1329000D03*
X1321000D03*
X1325000D03*
X1331000Y811620D03*
X1327000D03*
X1329000Y804000D03*
X1325000D03*
X1333000D03*
X1323000Y811620D03*
X1335000D03*
X1335803Y826500D03*
X1331056Y904557D03*
X1336096Y905042D03*
X1336000Y900500D03*
X1324000Y901000D03*
X1331078Y900500D03*
X1330500Y925500D03*
X1334500D03*
X1326500D03*
X1333425Y930925D03*
X1324000D03*
X1333132Y933781D03*
X1336000Y943500D03*
X1329199Y933825D03*
X1323000Y934075D03*
X1326500Y943500D03*
X1328457Y959986D03*
X1335343Y961727D03*
X1321028Y961749D03*
X1332500Y961500D03*
X1325550Y960445D03*
X1321104Y964398D03*
X1323554Y967623D03*
X1332000Y969500D03*
X1327000D03*
X1329503Y991088D03*
X1334909Y990340D03*
X1332404Y988215D03*
X1329834Y988132D03*
X1324735Y989966D03*
X1327267Y988271D03*
X1322427Y988221D03*
X1333974Y1033483D03*
X1320549Y1037876D03*
X1322773Y1040599D03*
X1331890Y1051919D03*
X1329221Y1058097D03*
X1321721D03*
X1324221D03*
X1326721D03*
Y1060697D03*
X1329221D03*
X1321721D03*
X1324221D03*
X1326163Y1082501D03*
X1326189Y1085205D03*
X1329163Y1082501D03*
X1329189Y1085205D03*
X1326189Y1088205D03*
X1326471Y1091227D03*
X1329189Y1088205D03*
X1323189Y1085205D03*
Y1087705D03*
X1323163Y1082501D03*
X1323021Y1090956D03*
X1331359Y1098898D03*
X1334161Y1098518D03*
X1337514Y1104335D03*
X1334956Y1105552D03*
X1321069Y1107997D03*
X1323021Y1093956D03*
X1331162Y1104792D03*
X1332669Y1106867D03*
X1333905Y1123101D03*
X1331405D03*
X1323405D03*
X1321169Y1110597D03*
X1321954Y1113648D03*
X1326254D03*
X1328754D03*
X1323405Y1118801D03*
Y1116101D03*
X1320279Y1131935D03*
Y1134435D03*
Y1136935D03*
Y1139435D03*
X1334305Y1129301D03*
X1331805D03*
X1329305D03*
X1326805D03*
X1324305D03*
X1321805D03*
X1334305Y1125801D03*
X1331805D03*
X1323405D03*
X1320279Y1141935D03*
Y1146935D03*
Y1144435D03*
X1326269Y1152713D03*
Y1155213D03*
X1325635Y1172384D03*
Y1162384D03*
Y1164884D03*
Y1167384D03*
Y1169884D03*
X1323135Y1172384D03*
Y1162384D03*
Y1164884D03*
Y1167384D03*
Y1169884D03*
X1334793Y1179421D03*
Y1181921D03*
Y1184421D03*
Y1186921D03*
X1320493Y1186709D03*
Y1184209D03*
Y1181709D03*
Y1179209D03*
X1325635Y1174884D03*
X1323135D03*
X1320493Y1204405D03*
X1334793Y1204617D03*
X1331643Y1200821D03*
Y1198321D03*
Y1192621D03*
Y1190121D03*
X1320493Y1206905D03*
Y1211905D03*
Y1209405D03*
X1334793Y1207117D03*
Y1209617D03*
Y1212117D03*
X1327237Y1221428D03*
X1331237D03*
X1335237D03*
X1323237D03*
X1327237Y1237428D03*
Y1233428D03*
Y1229428D03*
Y1225428D03*
X1331237Y1237428D03*
Y1233428D03*
Y1229428D03*
Y1225428D03*
X1335237Y1237428D03*
Y1233428D03*
Y1229428D03*
Y1225428D03*
X1323237Y1237428D03*
Y1233428D03*
Y1229428D03*
Y1225428D03*
X1335237Y1241428D03*
X1323237Y1245428D03*
Y1241428D03*
X1327237Y1245428D03*
Y1241428D03*
X1331237Y1245428D03*
Y1241428D03*
X1335237Y1245428D03*
X1333876Y1257160D03*
Y1260160D03*
X1330070Y1297498D03*
X1335470D03*
X1328850Y1465513D03*
Y1460782D03*
X1320189Y1465913D03*
Y1456451D03*
Y1461182D03*
X1328850Y1476136D03*
Y1470244D03*
X1320189Y1481267D03*
X1328850Y1480867D03*
X1320189Y1471805D03*
Y1476536D03*
X1328850Y1491490D03*
Y1485598D03*
X1320189Y1496621D03*
X1328850Y1496221D03*
X1320189Y1487159D03*
Y1491890D03*
Y1502514D03*
X1328850Y1506845D03*
Y1500952D03*
Y1511576D03*
X1320189Y1511976D03*
Y1507245D03*
X1328850Y1516307D03*
X1320189Y1558813D03*
Y1563544D03*
X1328850Y1563144D03*
Y1567875D03*
X1320189Y1574167D03*
Y1578898D03*
X1328850Y1578498D03*
Y1572606D03*
X1320189Y1568275D03*
X1328850Y1583229D03*
X1320189Y1589522D03*
Y1594253D03*
X1328850Y1593853D03*
Y1587960D03*
X1320189Y1583629D03*
X1328850Y1603315D03*
X1320189Y1609607D03*
Y1604876D03*
Y1598984D03*
X1328850Y1609207D03*
Y1598584D03*
Y1613938D03*
Y1618669D03*
X1320189Y1614338D03*
X1332000Y1644980D03*
X1340183Y-83484D03*
Y-78528D03*
Y-68528D03*
Y-73484D03*
X1337687Y-69306D03*
Y-72706D03*
X1342232Y3000D03*
X1336646Y22627D03*
X1336551Y26534D03*
X1340320Y147540D03*
X1344092Y141247D03*
X1351559Y143740D03*
X1348939Y148277D03*
X1340320Y151540D03*
X1348419Y265222D03*
X1340104Y279117D03*
X1344007Y279054D03*
X1337510Y310562D03*
X1338288Y313058D03*
X1347990Y322539D03*
X1341169Y325926D03*
X1338378Y334347D03*
X1338275Y341603D03*
X1346009Y336080D03*
X1346093Y340805D03*
X1349636Y340862D03*
X1338378Y348830D03*
X1346065Y347106D03*
X1338471Y356959D03*
X1338287Y370905D03*
X1337509Y373401D03*
X1349763Y371908D03*
X1342810Y408104D03*
X1345610D03*
X1348410D03*
X1336388Y424939D03*
X1342527Y420375D03*
X1345327D03*
X1348127D03*
X1347897Y433975D03*
X1346483Y436164D03*
X1336388Y427439D03*
X1346443Y431112D03*
X1352008Y435101D03*
X1352271Y442114D03*
X1346613Y440101D03*
X1352251Y447121D03*
X1346248Y452718D03*
X1340820Y452987D03*
X1352259Y452601D03*
X1347846Y461607D03*
X1339846D03*
X1339049Y471334D03*
X1343846Y461607D03*
X1346738Y564492D03*
X1339289Y568461D03*
X1342053Y579339D03*
X1346533Y576780D03*
X1340522Y586133D03*
X1343000Y590458D03*
X1346533Y581898D03*
X1344129Y606914D03*
X1344433Y601201D03*
X1339289Y614961D03*
X1344680Y619085D03*
X1346738Y611192D03*
X1346533Y628398D03*
X1346378Y623734D03*
X1342053Y625839D03*
X1340522Y632633D03*
X1343000Y636958D03*
X1346738Y655492D03*
X1339289Y659461D03*
X1346533Y667780D03*
X1342053Y670339D03*
X1346533Y672898D03*
X1340522Y677133D03*
X1343000Y681458D03*
X1350929Y687043D03*
X1340299Y686243D03*
X1345451Y699032D03*
X1346738Y702492D03*
X1346533Y719898D03*
X1339289Y706461D03*
X1342053Y717339D03*
X1346533Y714780D03*
X1340522Y724133D03*
X1343000Y728458D03*
X1344768Y737675D03*
Y741675D03*
Y745675D03*
Y749675D03*
Y769675D03*
Y753675D03*
Y761675D03*
Y757675D03*
X1336450Y765675D03*
X1347136Y780040D03*
X1344768Y773675D03*
Y781350D03*
X1345226Y777675D03*
X1341000Y799000D03*
X1345000Y796000D03*
X1341000Y788000D03*
X1345000D03*
X1337000D03*
X1348917Y796000D03*
Y788000D03*
X1352817Y796000D03*
X1349000Y804000D03*
X1351000Y811620D03*
X1347000D03*
X1343000D03*
X1337000Y804000D03*
X1345000D03*
X1341000D03*
X1349976Y829000D03*
X1350000Y825500D03*
X1340000Y900000D03*
X1351500Y903000D03*
Y906500D03*
X1340000Y906000D03*
Y903000D03*
X1351511Y900000D03*
X1350500Y925500D03*
X1338500D03*
X1342500D03*
X1346500D03*
X1353948Y943603D03*
X1345948D03*
X1349848Y936755D03*
X1338500Y930500D03*
X1350500D03*
X1342500D03*
X1346500D03*
X1341820Y947407D03*
X1337514Y988259D03*
X1343465Y1026123D03*
X1340665D03*
X1343465Y1028923D03*
X1340665D03*
X1347380Y1057998D03*
Y1055498D03*
X1344880D03*
Y1057998D03*
X1347380Y1060498D03*
Y1062998D03*
X1344880D03*
Y1060498D03*
X1347552Y1091816D03*
Y1089316D03*
X1345052Y1081816D03*
Y1084316D03*
Y1086816D03*
X1347552D03*
Y1084316D03*
X1350418Y1090288D03*
X1347552Y1081816D03*
X1339349Y1098767D03*
X1344241Y1106298D03*
X1348997Y1107997D03*
X1350418Y1093088D03*
X1339234Y1101917D03*
X1339169Y1106897D03*
X1341984Y1110092D03*
X1345650Y1115896D03*
X1348997Y1113797D03*
Y1110897D03*
X1351197Y1112397D03*
X1351097Y1109397D03*
X1345650Y1118396D03*
X1339305Y1129301D03*
X1336805D03*
X1339305Y1125801D03*
X1336805D03*
X1343505Y1136935D03*
Y1134435D03*
Y1139435D03*
Y1131935D03*
X1349907D03*
Y1134435D03*
Y1136935D03*
Y1139435D03*
X1352407Y1131935D03*
Y1134435D03*
Y1136935D03*
Y1139435D03*
X1347300Y1128332D03*
X1343725Y1128738D03*
X1343505Y1146935D03*
Y1144435D03*
Y1141935D03*
X1349907D03*
Y1146935D03*
Y1144435D03*
X1352407Y1141935D03*
Y1146935D03*
Y1144435D03*
X1336669Y1152713D03*
Y1155213D03*
X1351405Y1154902D03*
Y1152402D03*
X1343905Y1162384D03*
Y1164884D03*
Y1167384D03*
Y1169884D03*
Y1172384D03*
X1341405D03*
Y1169884D03*
Y1167384D03*
Y1164884D03*
Y1162384D03*
X1350963Y1172384D03*
Y1169884D03*
Y1167384D03*
Y1164884D03*
Y1162384D03*
X1351149Y1158200D03*
X1347423Y1186709D03*
Y1184209D03*
Y1181709D03*
Y1179209D03*
X1343905Y1174884D03*
X1341405D03*
X1350963D03*
X1347423Y1204405D03*
X1337108Y1200821D03*
Y1198321D03*
X1345108Y1200821D03*
Y1198321D03*
X1337108Y1192621D03*
Y1190121D03*
X1345108D03*
Y1192621D03*
X1347423Y1209405D03*
Y1211905D03*
Y1206905D03*
X1347237Y1221428D03*
X1343237D03*
X1339237D03*
X1347237Y1237428D03*
Y1233428D03*
Y1229428D03*
X1343237D03*
Y1233428D03*
Y1237428D03*
X1339237D03*
Y1233428D03*
Y1229428D03*
Y1225428D03*
X1347237Y1245428D03*
Y1241428D03*
X1343237D03*
Y1245428D03*
X1339237D03*
Y1241428D03*
X1339876Y1257160D03*
X1342876D03*
X1345876Y1260160D03*
Y1257160D03*
X1348876Y1260160D03*
Y1257160D03*
X1351876Y1260160D03*
Y1257160D03*
X1336876Y1260160D03*
Y1257160D03*
X1342876Y1260160D03*
X1339876D03*
X1340870Y1297498D03*
X1346270D03*
X1351670D03*
X1337512Y1461182D03*
X1346173Y1465513D03*
Y1460782D03*
X1337512Y1465913D03*
Y1456451D03*
X1346173Y1476136D03*
Y1470244D03*
X1337512Y1481267D03*
X1346173Y1480867D03*
X1337512Y1471805D03*
Y1476536D03*
X1346173Y1485598D03*
Y1491490D03*
X1337512Y1487159D03*
Y1491890D03*
Y1496621D03*
X1346173Y1496221D03*
X1337512Y1507245D03*
Y1502514D03*
X1346173Y1506845D03*
Y1500952D03*
Y1511576D03*
X1337512Y1511976D03*
X1346173Y1516307D03*
X1337512Y1558813D03*
Y1563544D03*
X1346173Y1563144D03*
X1337512Y1574167D03*
Y1578898D03*
X1346173Y1578498D03*
Y1572606D03*
X1337512Y1568275D03*
X1346173Y1567875D03*
X1337512Y1583629D03*
X1346173Y1583229D03*
X1337512Y1589522D03*
Y1594253D03*
X1346173Y1593853D03*
Y1587960D03*
X1337512Y1609607D03*
Y1604876D03*
Y1598984D03*
X1346173Y1609207D03*
Y1598584D03*
Y1603315D03*
X1337512Y1614338D03*
X1346173Y1613938D03*
Y1618669D03*
X1352000Y1644980D03*
X1362232Y3000D03*
X1355900Y146461D03*
X1360122Y141247D03*
X1364609Y143518D03*
X1363709Y152373D03*
X1354802Y152367D03*
X1366859Y152562D03*
X1361039Y327099D03*
X1363535Y327877D03*
X1361039Y332055D03*
X1364039Y334973D03*
Y339929D03*
X1361039Y342847D03*
X1366535Y335751D03*
Y339151D03*
X1363535Y331277D03*
Y343625D03*
X1364039Y350721D03*
X1361039Y347803D03*
X1364039Y355677D03*
X1366535Y354899D03*
Y351499D03*
X1363535Y347025D03*
X1360719Y424601D03*
X1360352Y447101D03*
X1355255Y561032D03*
Y607532D03*
Y652032D03*
X1352817Y788000D03*
X1367000Y811620D03*
X1365000Y804000D03*
X1355000Y811620D03*
X1363000D03*
X1353000Y804000D03*
X1359000Y811620D03*
X1357000Y804000D03*
X1361000D03*
X1354185Y906498D03*
X1367000Y904500D03*
X1363000Y900500D03*
X1367000D03*
X1354500Y925500D03*
X1366500D03*
X1358500D03*
X1362500D03*
X1365948Y939475D03*
X1357948Y938842D03*
X1361948Y943603D03*
X1369948D03*
X1362500Y930500D03*
X1366500D03*
X1354500D03*
X1358500D03*
X1363173Y994483D03*
X1363905Y1000855D03*
X1366493Y1000828D03*
X1364765Y1004766D03*
X1367444Y1003763D03*
X1367884Y1018825D03*
X1357265Y1022766D03*
X1357765Y1019766D03*
X1361265D03*
X1365049Y1028416D03*
X1365314Y1021793D03*
X1357265Y1026266D03*
X1364237Y1043140D03*
X1357265Y1030266D03*
Y1034266D03*
X1366265Y1039880D03*
X1363941Y1047047D03*
X1364418Y1090568D03*
Y1093068D03*
X1366289Y1098518D03*
X1361037Y1098428D03*
X1369642Y1104335D03*
X1367084Y1105552D03*
X1353197Y1107997D03*
X1363290Y1104792D03*
X1364797Y1106867D03*
X1355533Y1123101D03*
X1363533D03*
X1366033D03*
X1353297Y1110597D03*
X1354082Y1113648D03*
X1355533Y1116101D03*
Y1118801D03*
X1360882Y1113648D03*
X1358382D03*
X1366433Y1129301D03*
X1355533Y1125801D03*
X1363933D03*
X1366433D03*
X1353933Y1129301D03*
X1356433D03*
X1358933D03*
X1361433D03*
X1363933D03*
X1357397Y1155213D03*
Y1152713D03*
X1366797D03*
Y1155213D03*
X1353463Y1172384D03*
Y1169884D03*
Y1167384D03*
Y1164884D03*
Y1162384D03*
X1361723Y1179421D03*
Y1181921D03*
Y1184421D03*
Y1186921D03*
X1353463Y1174884D03*
X1361723Y1204617D03*
X1364038Y1198321D03*
Y1200821D03*
Y1190121D03*
Y1192621D03*
X1361723Y1212117D03*
Y1209617D03*
Y1207117D03*
X1363876Y1260160D03*
Y1257160D03*
X1354876Y1260160D03*
X1357876D03*
X1360876D03*
Y1257160D03*
X1357876D03*
X1354876D03*
X1366876Y1260160D03*
Y1257160D03*
X1357070Y1297498D03*
X1354834Y1465913D03*
Y1456451D03*
Y1461182D03*
X1363496Y1465513D03*
Y1460782D03*
X1354834Y1481267D03*
X1363496Y1476136D03*
Y1470244D03*
Y1480867D03*
X1354834Y1471805D03*
Y1476536D03*
Y1487159D03*
Y1496621D03*
X1363496Y1485598D03*
Y1491490D03*
Y1496221D03*
X1354834Y1491890D03*
Y1502514D03*
Y1511976D03*
X1363496Y1511576D03*
Y1506845D03*
Y1500952D03*
X1354834Y1507245D03*
X1363496Y1516307D03*
X1354834Y1558813D03*
Y1563544D03*
X1363496Y1563144D03*
Y1572606D03*
X1354834Y1568275D03*
Y1574167D03*
Y1578898D03*
X1363496Y1567875D03*
Y1578498D03*
X1354834Y1583629D03*
Y1589522D03*
Y1594253D03*
X1363496Y1583229D03*
Y1593853D03*
Y1587960D03*
X1354834Y1609607D03*
Y1604876D03*
Y1598984D03*
X1363496Y1609207D03*
Y1598584D03*
Y1603315D03*
X1354834Y1614338D03*
X1363496Y1613938D03*
Y1618669D03*
X1382232Y3000D03*
X1376262Y113394D03*
X1378911Y110784D03*
X1380480Y102249D03*
X1384480D03*
X1376262Y116594D03*
X1382205Y110784D03*
X1387205D03*
X1378505Y133298D03*
X1376262Y119594D03*
X1386784Y124663D03*
X1376696Y124283D03*
X1381762Y124879D03*
X1380652Y134579D03*
X1375103Y161306D03*
X1372354Y157370D03*
X1384280Y195176D03*
X1381780D03*
X1384140Y203393D03*
X1381640D03*
X1386399Y201683D03*
X1384319Y218085D03*
X1381519D03*
X1386846Y249108D03*
X1378227Y252371D03*
Y248371D03*
X1384265Y320871D03*
Y325371D03*
X1383551Y337808D03*
X1384265Y329871D03*
X1383634Y342766D03*
X1384265Y334371D03*
X1384253Y346826D03*
X1384447Y356871D03*
X1375073D03*
Y361371D03*
X1383505Y349437D03*
X1384265Y352371D03*
X1372232Y361298D03*
X1384174Y362641D03*
X1383963Y366675D03*
X1373748Y397758D03*
X1377024Y397713D03*
X1375108Y420838D03*
X1375171Y424741D03*
X1375375Y428995D03*
X1375400Y435192D03*
X1375360Y432234D03*
X1383343Y508228D03*
X1383907Y516591D03*
X1383556Y554388D03*
X1378415Y558795D03*
X1383556Y558338D03*
X1383608Y571927D03*
X1378415Y563984D03*
Y569776D03*
X1383184Y587653D03*
X1378957Y584457D03*
X1383000Y584500D03*
X1382997Y581317D03*
X1383425Y593575D03*
X1383556Y604838D03*
X1383425Y590425D03*
X1378415Y605295D03*
X1383608Y618427D03*
X1378415Y610484D03*
Y616276D03*
X1381118Y634033D03*
X1383425Y636925D03*
X1378957Y630957D03*
X1384657Y631620D03*
X1378957Y627988D03*
X1383425Y640075D03*
X1378415Y649795D03*
Y654984D03*
Y660776D03*
X1386289Y672488D03*
X1381244Y673623D03*
X1383425Y684140D03*
Y681425D03*
X1378957Y675457D03*
X1383000Y675500D03*
X1378415Y696795D03*
Y701984D03*
X1378957Y719488D03*
X1378415Y707776D03*
X1381932Y722547D03*
X1383425Y731575D03*
Y728425D03*
X1378957Y722457D03*
X1385290Y722400D03*
X1371000Y811620D03*
X1381000Y804000D03*
X1373000D03*
X1369000D03*
X1385360Y811757D03*
X1381428Y812287D03*
X1375193Y811724D03*
X1376708Y901000D03*
X1378500Y925500D03*
X1374369Y925499D03*
X1370500Y925500D03*
X1382500D03*
X1382775Y930281D03*
X1373948Y940103D03*
X1374500Y930500D03*
X1370500D03*
X1378500D03*
X1371379Y986717D03*
X1381519Y996280D03*
X1383162Y991829D03*
X1370384Y1004680D03*
X1383669Y1011303D03*
X1373534Y1012325D03*
Y1004680D03*
X1378938Y1000586D03*
X1383669Y1017303D03*
Y1023303D03*
X1374034Y1015825D03*
X1374059Y1018860D03*
X1376359Y1016825D03*
X1376601Y1030218D03*
X1378559Y1038534D03*
X1384784Y1033783D03*
X1385929Y1038665D03*
X1373874Y1032266D03*
Y1035716D03*
X1385152Y1046591D03*
X1374451Y1090568D03*
Y1093068D03*
X1371477Y1098767D03*
X1377087Y1106365D03*
X1371362Y1101917D03*
X1371297Y1106897D03*
X1382456Y1107997D03*
X1374112Y1110092D03*
X1377778Y1115896D03*
X1384656Y1112397D03*
X1382456Y1110897D03*
Y1113797D03*
X1384556Y1109397D03*
X1377778Y1118396D03*
X1375633Y1136935D03*
Y1134435D03*
Y1139435D03*
Y1131935D03*
X1383366D03*
Y1134435D03*
Y1136935D03*
Y1139435D03*
X1368933Y1125801D03*
X1371433D03*
X1368933Y1129301D03*
X1371433D03*
X1383024Y1152684D03*
X1376861D03*
X1375633Y1146935D03*
Y1144435D03*
Y1141935D03*
X1383366D03*
Y1146935D03*
Y1144435D03*
X1369233Y1169884D03*
Y1172384D03*
X1371733D03*
Y1169884D03*
Y1167384D03*
Y1164884D03*
Y1162384D03*
X1369233D03*
Y1164884D03*
Y1167384D03*
X1376861Y1160834D03*
X1383024D03*
X1369233Y1174884D03*
X1371733D03*
X1375459Y1197471D03*
Y1193471D03*
X1379959Y1197471D03*
Y1193471D03*
X1377390Y1244055D03*
Y1250760D03*
Y1254164D03*
X1372300Y1422900D03*
X1372157Y1461183D03*
Y1456452D03*
Y1465914D03*
Y1471806D03*
Y1476537D03*
Y1481268D03*
Y1487160D03*
Y1491891D03*
Y1496622D03*
Y1502515D03*
Y1507246D03*
Y1511977D03*
Y1558813D03*
Y1563544D03*
Y1568275D03*
Y1574167D03*
Y1578898D03*
Y1583629D03*
Y1589522D03*
Y1594253D03*
Y1604876D03*
Y1598984D03*
Y1609607D03*
Y1614338D03*
X1372000Y1644980D03*
X1398216Y4469D03*
X1399577Y24773D03*
Y44773D03*
X1388480Y102249D03*
X1397848Y97667D03*
X1391497Y109172D03*
X1394497D03*
X1393504Y106495D03*
X1397248Y116497D03*
X1388231Y116594D03*
X1393504Y102495D03*
X1386505Y133298D03*
X1397248Y130670D03*
Y123584D03*
X1388231Y119594D03*
X1399648Y132515D03*
Y121742D03*
Y118342D03*
X1391765Y125107D03*
X1393238Y146012D03*
X1395144Y141228D03*
X1397248Y137757D03*
X1399648Y135915D03*
X1393238Y142862D03*
X1400379Y143762D03*
X1394279Y148717D03*
X1388128Y138838D03*
X1398032Y150847D03*
X1389580Y195176D03*
X1386399Y198883D03*
X1386780Y195176D03*
X1399327D03*
X1396827D03*
X1400845Y199248D03*
X1390328Y206838D03*
X1387828D03*
X1400845Y201748D03*
X1398681Y206806D03*
X1401181D03*
X1399408Y210509D03*
X1396908D03*
X1390832Y216970D03*
Y219470D03*
X1390898Y226320D03*
X1390832Y221970D03*
X1388119Y216385D03*
X1402855Y227824D03*
X1398600Y230556D03*
X1393859Y228646D03*
X1400000Y247292D03*
X1399226Y238689D03*
X1392790Y236121D03*
X1389824Y238589D03*
X1397585Y242078D03*
X1392816Y232971D03*
X1389466Y244571D03*
X1392709Y253198D03*
X1396809Y256394D03*
X1385943Y323222D03*
X1385971Y327688D03*
X1395726Y320529D03*
X1395568Y325529D03*
X1395726Y330529D03*
X1386143Y331982D03*
X1386057Y341200D03*
X1385971Y336791D03*
X1395736Y335529D03*
X1395726Y340529D03*
Y345529D03*
X1386286Y350218D03*
X1395726Y360529D03*
Y350529D03*
Y355529D03*
X1391896Y365529D03*
X1399884Y367165D03*
X1387847Y366710D03*
X1397550Y390484D03*
X1400231Y390256D03*
X1387814Y397136D03*
X1389295Y408443D03*
X1396528Y397454D03*
X1399571Y397418D03*
X1393575Y397310D03*
X1390553Y397436D03*
X1391623Y409900D03*
X1386809Y414173D03*
X1387125Y417312D03*
X1393177Y424804D03*
X1389557Y424678D03*
X1389431Y421593D03*
X1390271Y417578D03*
X1388788Y428348D03*
X1393208Y428109D03*
X1393336Y431100D03*
X1403085Y460565D03*
X1393944Y507856D03*
X1394044Y510990D03*
X1397079Y531726D03*
Y536726D03*
Y527726D03*
Y552726D03*
Y540726D03*
Y548726D03*
Y544726D03*
X1395605Y556217D03*
X1390741Y561000D03*
Y569000D03*
Y565000D03*
X1391086Y577192D03*
X1400912Y581222D03*
X1391087Y581317D03*
X1400912Y591215D03*
X1398946Y621311D03*
X1390741Y611500D03*
Y607500D03*
Y615500D03*
X1391587Y627817D03*
X1391586Y623692D03*
X1398946Y629311D03*
Y625311D03*
X1397000Y652000D03*
Y656000D03*
Y660000D03*
X1388414Y675000D03*
X1397000Y699000D03*
Y707000D03*
Y703000D03*
X1388241Y722000D03*
X1391040Y812027D03*
X1386335Y803704D03*
X1390537Y803679D03*
X1394537Y803653D03*
X1398530Y811717D03*
X1402417Y811692D03*
X1400069Y827515D03*
X1401300Y820485D03*
X1395955Y832697D03*
X1402000Y840000D03*
Y848000D03*
X1399872Y845109D03*
X1396916Y862829D03*
X1402000Y864000D03*
X1391316Y857849D03*
X1388488Y857822D03*
X1395561Y876204D03*
X1396163Y868597D03*
X1402000Y876000D03*
X1390182Y873460D03*
X1387582Y873487D03*
X1402000Y884000D03*
Y892000D03*
X1388479Y892923D03*
X1385979D03*
X1390979D03*
X1402000Y900000D03*
X1387520Y905307D03*
X1387753Y912629D03*
X1394891Y914783D03*
X1402187Y908270D03*
X1387504Y899931D03*
X1390541Y900086D03*
X1398247Y926261D03*
X1388980Y921075D03*
X1401000Y925789D03*
X1396869Y958707D03*
X1402064Y965913D03*
X1389192Y992568D03*
X1398854Y987277D03*
X1395669Y1011303D03*
X1389669D03*
X1394885Y999941D03*
X1392031Y1004375D03*
X1395669Y1017303D03*
Y1023303D03*
X1389669D03*
X1385732Y1029482D03*
X1389762Y1043055D03*
X1387813Y1030952D03*
X1399807Y1036155D03*
X1399852Y1039779D03*
X1390322Y1057998D03*
Y1055498D03*
X1392822D03*
Y1057998D03*
X1390322Y1060498D03*
Y1062998D03*
X1392822D03*
Y1060498D03*
X1388523Y1090090D03*
X1392691Y1089224D03*
X1392086Y1092743D03*
X1392691Y1086724D03*
Y1084224D03*
Y1081724D03*
X1390191D03*
Y1084224D03*
Y1086724D03*
X1399748Y1098518D03*
X1394496Y1098428D03*
X1403101Y1104335D03*
X1400543Y1105552D03*
X1396749Y1104792D03*
X1388451Y1093048D03*
X1386656Y1107997D03*
X1398256Y1106867D03*
X1388992Y1123101D03*
X1396992D03*
X1399492D03*
X1386756Y1110597D03*
X1394341Y1113648D03*
X1388992Y1118801D03*
Y1116101D03*
X1387541Y1113648D03*
X1391841D03*
X1385866Y1131935D03*
Y1134435D03*
Y1136935D03*
Y1139435D03*
X1388992Y1125801D03*
X1397392D03*
X1399892D03*
X1387392Y1129301D03*
X1389892D03*
X1392392D03*
X1394892D03*
X1397392D03*
X1399892D03*
X1391856Y1155213D03*
Y1152713D03*
X1385866Y1141935D03*
Y1146935D03*
Y1144435D03*
X1388722Y1162384D03*
Y1164884D03*
Y1167384D03*
Y1169884D03*
Y1172384D03*
X1391222Y1162384D03*
Y1164884D03*
Y1167384D03*
Y1169884D03*
Y1172384D03*
X1388722Y1174884D03*
X1391222D03*
X1393695Y1186709D03*
Y1184209D03*
Y1181709D03*
Y1179209D03*
Y1204405D03*
X1391380Y1200821D03*
Y1198321D03*
Y1190121D03*
Y1192621D03*
X1393695Y1206905D03*
Y1211905D03*
Y1209405D03*
X1385821Y1260160D03*
X1391821Y1257160D03*
X1394821D03*
X1385821D03*
X1388821D03*
X1397821Y1260160D03*
Y1257160D03*
X1400821Y1260160D03*
Y1257160D03*
X1388821Y1260160D03*
X1394821D03*
X1391821D03*
X1385992Y1285466D03*
X1390492D03*
X1385052Y1303139D03*
X1389052D03*
X1392000Y1644980D03*
X1406898Y53597D03*
X1406308Y103411D03*
X1406702Y97667D03*
X1417498Y90650D03*
X1417248Y95236D03*
X1402098Y95111D03*
X1417248Y102323D03*
X1409248Y109410D03*
Y102323D03*
X1404548Y116497D03*
X1402048D03*
X1404548Y109410D03*
X1409248Y116496D03*
X1406948Y111255D03*
Y114655D03*
X1406467Y106561D03*
X1402048Y130670D03*
Y123584D03*
X1404548Y123583D03*
X1409248Y130670D03*
Y123583D03*
X1404548Y130670D03*
X1406948Y128828D03*
Y125428D03*
X1409248Y137756D03*
X1402048Y137757D03*
X1403845Y199248D03*
X1401827Y195176D03*
X1404327D03*
X1405780Y213539D03*
X1403845Y202048D03*
X1407445Y230117D03*
X1407461Y238714D03*
X1403461D03*
X1402942Y246874D03*
X1405162Y244297D03*
X1408666Y324733D03*
X1402921Y322403D03*
X1409830Y347649D03*
X1404690Y362209D03*
X1416347Y384373D03*
X1416912Y386903D03*
X1408854Y381207D03*
X1416470Y381397D03*
X1402968Y390177D03*
X1416830Y407134D03*
X1411400Y398032D03*
X1414369Y398056D03*
X1408254Y398041D03*
X1407844Y411033D03*
X1413889Y415642D03*
X1415610Y417644D03*
X1415674Y421278D03*
X1411950Y448466D03*
X1417856Y448419D03*
X1414903Y469905D03*
X1410903Y470419D03*
Y461919D03*
X1418903Y461419D03*
X1406910Y487982D03*
Y478982D03*
Y483982D03*
X1411269Y481467D03*
X1415623Y492268D03*
X1415823Y482165D03*
X1406910Y499982D03*
X1416061Y504825D03*
X1413561D03*
X1411061D03*
X1415064Y500202D03*
X1406910Y495982D03*
X1416413Y495649D03*
X1406910Y491982D03*
X1416002Y517401D03*
X1413502D03*
X1411002D03*
X1416553Y522569D03*
Y525369D03*
X1415168Y531882D03*
X1412668D03*
X1409618Y531948D03*
X1401438Y534211D03*
X1405992Y534909D03*
X1405619Y541135D03*
X1408103Y555194D03*
X1410903D03*
X1405685Y546553D03*
X1405708Y552726D03*
X1415103Y555194D03*
X1408103Y563194D03*
X1410903D03*
X1408103Y571194D03*
X1410903D03*
X1415103Y563194D03*
Y571194D03*
X1406512Y581222D03*
X1403712D03*
X1416660D03*
X1403712Y591215D03*
X1406512D03*
X1416660D03*
X1405514Y611091D03*
X1401383Y611071D03*
X1416832Y610562D03*
Y607762D03*
X1411622Y610548D03*
X1407566Y622285D03*
X1407754Y616905D03*
X1418439Y633736D03*
X1407952Y633724D03*
X1413432Y633716D03*
X1407835Y627713D03*
X1413452Y641817D03*
X1407952D03*
X1405229Y652028D03*
X1405000Y656000D03*
Y660000D03*
X1410000Y685000D03*
Y681000D03*
X1404500Y675000D03*
X1405000Y699000D03*
X1410000Y689000D03*
Y701000D03*
Y697000D03*
X1418000Y696000D03*
Y701000D03*
X1410000Y705000D03*
Y709000D03*
Y713000D03*
X1405000Y707000D03*
Y703000D03*
X1418000Y717000D03*
X1410000D03*
Y733000D03*
X1404500Y722000D03*
X1410000Y729000D03*
Y725000D03*
X1418000Y724000D03*
Y729000D03*
X1404249Y735858D03*
X1410000Y749000D03*
Y745000D03*
Y741000D03*
X1418000Y740000D03*
Y745000D03*
X1407482Y750853D03*
X1410000Y757000D03*
Y753000D03*
Y761000D03*
X1418000D03*
X1406867Y783273D03*
X1409115Y773520D03*
X1414597Y792375D03*
X1406483Y811717D03*
X1413500Y832000D03*
Y828000D03*
X1413449Y823934D03*
X1405402Y819917D03*
X1405500Y844000D03*
Y836000D03*
X1413500Y848000D03*
Y840000D03*
Y836000D03*
Y844000D03*
X1405500Y860000D03*
X1413500Y864000D03*
Y860000D03*
Y856000D03*
Y852000D03*
X1405500Y880000D03*
Y868000D03*
X1413500Y876000D03*
X1417797Y879501D03*
X1413500Y872000D03*
Y868000D03*
X1405500Y888000D03*
Y896000D03*
X1417081D03*
X1413500Y892000D03*
Y884000D03*
Y888000D03*
X1404689Y910897D03*
X1413733Y911137D03*
X1412376Y907848D03*
X1414876D03*
X1417376D03*
X1409876D03*
X1405500Y904000D03*
X1404760Y915186D03*
X1413500Y904000D03*
Y900000D03*
X1417284Y911009D03*
X1413575Y915186D03*
X1416802Y936845D03*
X1416244Y942285D03*
X1419337D03*
X1413322Y958908D03*
X1405214Y965074D03*
X1419446Y977192D03*
X1404317Y989436D03*
X1411038Y985379D03*
X1416618Y992307D03*
X1401265Y989465D03*
X1407265D03*
X1414143Y985486D03*
X1412698Y997590D03*
X1412609Y1008766D03*
X1412759Y1016266D03*
X1402215Y1020440D03*
X1414851Y1058097D03*
X1412351D03*
X1407351D03*
X1409851D03*
X1417351D03*
X1414851Y1060697D03*
X1412351D03*
X1407351D03*
X1409851D03*
X1417351D03*
X1405677Y1086796D03*
X1408177D03*
X1410677D03*
X1413177D03*
X1415677D03*
Y1084296D03*
X1413177D03*
X1410677D03*
X1408177D03*
X1405677D03*
X1416005Y1090288D03*
X1404936Y1098767D03*
X1410546Y1106298D03*
X1404821Y1101917D03*
X1404756Y1106897D03*
X1416005Y1093088D03*
X1414584Y1107997D03*
X1411237Y1115896D03*
X1407571Y1110092D03*
X1414584Y1113797D03*
X1416784Y1112397D03*
X1414584Y1110897D03*
X1416684Y1109397D03*
X1411237Y1118396D03*
X1415494Y1139435D03*
Y1136935D03*
Y1134435D03*
Y1131935D03*
X1409092Y1136935D03*
Y1134435D03*
Y1139435D03*
Y1131935D03*
X1402392Y1125801D03*
X1404892D03*
X1402392Y1129301D03*
X1404892D03*
X1409425Y1129238D03*
X1413177Y1128894D03*
X1409092Y1141935D03*
X1416736Y1152713D03*
Y1155213D03*
X1402256D03*
Y1152713D03*
X1415494Y1144435D03*
Y1146935D03*
Y1141935D03*
X1409092Y1146935D03*
Y1144435D03*
X1409492Y1167384D03*
Y1169884D03*
Y1172384D03*
X1406992D03*
Y1169884D03*
X1416550Y1162384D03*
Y1164884D03*
Y1167384D03*
Y1169884D03*
Y1172384D03*
X1406992Y1167384D03*
Y1164884D03*
Y1162384D03*
X1409492D03*
Y1164884D03*
X1416736Y1158200D03*
X1416550Y1174884D03*
X1409492D03*
X1406992D03*
X1407995Y1179421D03*
Y1181921D03*
Y1184421D03*
Y1186921D03*
Y1204617D03*
X1410310Y1200821D03*
Y1198321D03*
X1404845D03*
Y1200821D03*
X1410310Y1192621D03*
Y1190121D03*
X1404845D03*
Y1192621D03*
X1407995Y1207117D03*
Y1209617D03*
Y1212117D03*
X1408736Y1222194D03*
X1412736D03*
X1416736D03*
X1408736Y1238194D03*
Y1234194D03*
Y1230194D03*
Y1226194D03*
X1412736Y1238194D03*
Y1234194D03*
Y1230194D03*
Y1226194D03*
X1416736Y1238194D03*
Y1234194D03*
Y1230194D03*
Y1226194D03*
X1412736Y1246194D03*
Y1242194D03*
X1416736Y1246194D03*
Y1242194D03*
X1408736D03*
Y1246194D03*
X1409821Y1260160D03*
X1412821D03*
Y1257160D03*
X1409821D03*
X1406821D03*
X1403821D03*
X1415821Y1260160D03*
Y1257160D03*
X1403821Y1260160D03*
X1406821D03*
X1415903Y1282590D03*
X1404019Y1285290D03*
X1414346Y1303020D03*
X1417711Y1301729D03*
X1410817Y1305417D03*
X1407825Y1426975D03*
X1408536Y1536570D03*
X1404239Y1547755D03*
X1407747Y1549054D03*
X1408044Y1559306D03*
X1403747Y1570433D03*
X1407255Y1571732D03*
X1412000Y1644980D03*
X1426898Y53597D03*
X1417710Y82984D03*
Y75184D03*
Y77784D03*
Y80384D03*
X1420264Y92849D03*
X1417710Y85584D03*
X1422810Y90615D03*
X1427131Y99961D03*
X1427181Y95236D03*
X1427224Y103037D03*
X1417500Y109410D03*
Y116496D03*
X1427358D03*
Y109410D03*
X1421700Y122900D03*
X1427358Y130670D03*
Y123583D03*
X1418725Y130670D03*
X1423515Y137756D03*
X1418720D03*
X1425993Y212978D03*
Y207978D03*
Y210478D03*
Y215478D03*
Y231226D03*
Y228726D03*
Y226226D03*
Y223726D03*
X1429322Y264180D03*
X1431822D03*
X1429247Y258880D03*
X1429539Y293796D03*
X1432039D03*
X1434166Y325361D03*
X1434164Y339232D03*
X1434038Y334114D03*
X1435818Y352361D03*
X1421005Y407616D03*
X1431019Y434508D03*
X1427019D03*
X1417903Y439919D03*
X1434997Y442603D03*
X1427117Y443071D03*
X1424196Y446352D03*
X1428782Y445874D03*
X1417856Y455466D03*
X1423427Y456839D03*
X1425927D03*
X1423427Y454339D03*
X1425927D03*
X1432414Y459371D03*
X1427484Y470045D03*
X1422903Y469905D03*
X1423427Y459339D03*
X1425927D03*
X1418903Y469905D03*
X1431484Y470045D03*
X1427484Y462004D03*
X1422499Y485138D03*
X1419650Y485128D03*
X1426384Y478625D03*
X1428084Y482425D03*
X1427499Y485138D03*
X1424999D03*
X1426384Y476125D03*
X1430930Y500086D03*
X1433310Y504699D03*
X1430810D03*
X1433012Y516979D03*
X1430512D03*
X1431493Y521804D03*
X1427800Y528578D03*
X1432955Y527449D03*
X1431493Y524304D03*
X1427800Y531378D03*
X1418253Y529169D03*
X1417668Y531882D03*
X1424129Y537658D03*
X1427832Y539731D03*
X1421099Y546830D03*
X1424129Y540458D03*
X1432590Y544895D03*
X1435390D03*
X1427832Y542231D03*
X1432890Y541895D03*
X1417903Y555194D03*
Y563194D03*
Y571194D03*
X1422260Y581222D03*
X1419460D03*
X1435119Y590801D03*
X1422260Y591215D03*
X1419460D03*
X1431000Y591000D03*
X1434944Y597130D03*
X1433114Y620653D03*
Y617853D03*
X1419632Y607762D03*
X1422432D03*
X1425232Y610562D03*
Y607762D03*
X1422432Y610562D03*
X1419632D03*
X1430944Y605443D03*
X1427233Y628183D03*
X1424389Y627948D03*
X1420452Y628078D03*
X1430175Y627852D03*
X1425452Y633473D03*
X1430481Y658153D03*
X1433529Y660564D03*
X1426615Y674112D03*
X1429000Y685000D03*
X1418000D03*
Y681000D03*
X1425909Y691120D03*
X1433464Y692658D03*
X1418000Y689000D03*
X1433053Y701839D03*
X1426000Y709000D03*
Y713000D03*
Y717000D03*
X1418000Y705000D03*
X1431522Y708633D03*
X1434000Y712958D03*
X1430289Y734961D03*
X1418000Y733000D03*
X1417969Y720894D03*
X1429000Y729000D03*
X1434000Y751958D03*
X1433153Y745839D03*
X1426000Y757000D03*
Y753000D03*
X1427000Y766500D03*
X1426000Y761000D03*
X1435000Y765500D03*
X1434000Y756958D03*
X1418023Y765343D03*
X1427000Y774500D03*
Y781834D03*
Y770500D03*
X1435000D03*
X1427000Y790500D03*
Y794500D03*
X1435000Y802500D03*
X1427000Y810500D03*
Y814500D03*
X1435000D03*
Y809500D03*
X1427000Y802500D03*
Y818500D03*
Y830500D03*
Y826500D03*
X1434975Y830500D03*
X1435000Y825500D03*
X1427000Y834500D03*
Y842500D03*
Y838500D03*
X1435000Y846500D03*
X1427000D03*
X1435043Y874694D03*
X1435082Y869475D03*
X1422813Y910065D03*
X1424126Y900295D03*
X1423190Y905295D03*
X1429059Y908579D03*
X1426085Y910281D03*
X1427553Y939200D03*
X1429907Y936998D03*
X1424897Y936777D03*
X1435516Y936000D03*
X1420699Y958452D03*
X1427473Y965621D03*
X1430839Y965546D03*
X1420740Y1004766D03*
Y1000766D03*
Y1008766D03*
X1428740Y1000766D03*
X1420740Y996766D03*
X1428864D03*
X1420740Y1016266D03*
Y1012266D03*
X1428740Y1016266D03*
X1428823Y1020266D03*
X1420740Y1030766D03*
X1420107Y1052514D03*
X1430005Y1090568D03*
Y1093068D03*
X1431876Y1098518D03*
X1426624Y1098428D03*
X1435229Y1104335D03*
X1432671Y1105552D03*
X1428877Y1104792D03*
X1418784Y1107997D03*
X1430384Y1106867D03*
X1421120Y1123101D03*
X1429120D03*
X1431620D03*
X1418884Y1110597D03*
X1421120Y1116101D03*
Y1118801D03*
X1426469Y1113648D03*
X1423969D03*
X1419669D03*
X1422020Y1129301D03*
X1424520D03*
X1427020D03*
X1429520D03*
X1432020D03*
X1417994Y1139435D03*
Y1136935D03*
Y1134435D03*
Y1131935D03*
X1421120Y1125801D03*
X1429520D03*
X1432020D03*
X1419520Y1129301D03*
X1432384Y1155213D03*
Y1152713D03*
X1422984D03*
Y1155213D03*
X1417994Y1144435D03*
Y1146935D03*
Y1141935D03*
X1419050Y1162384D03*
Y1164884D03*
Y1167384D03*
Y1169884D03*
Y1172384D03*
Y1174884D03*
X1420625Y1186709D03*
Y1184209D03*
Y1181709D03*
Y1179209D03*
Y1204405D03*
X1418310Y1198321D03*
Y1200821D03*
Y1192621D03*
Y1190121D03*
X1420625Y1206905D03*
Y1209405D03*
X1420736Y1222194D03*
X1424736D03*
X1428736D03*
X1432736D03*
X1420736Y1238194D03*
Y1234194D03*
Y1230194D03*
Y1226194D03*
X1424736Y1238194D03*
Y1234194D03*
Y1230194D03*
Y1226194D03*
X1428736Y1238194D03*
Y1234194D03*
Y1230194D03*
Y1226194D03*
X1432736Y1234194D03*
Y1230194D03*
Y1226194D03*
X1420736Y1246194D03*
Y1242194D03*
X1424736Y1246194D03*
Y1242194D03*
X1428736Y1246194D03*
Y1242194D03*
X1421821Y1257160D03*
X1418821D03*
Y1260160D03*
X1421821D03*
X1425652Y1297411D03*
X1431080Y1301702D03*
X1421238Y1301712D03*
X1428009Y1301760D03*
X1424732Y1301603D03*
X1433386Y1343309D03*
X1428840Y1407740D03*
X1432258Y1414600D03*
X1422176Y1491198D03*
X1430374Y1492474D03*
X1420877Y1494706D03*
X1423065Y1508327D03*
X1432499Y1512175D03*
X1421964Y1502813D03*
X1423806Y1524252D03*
X1423930Y1520364D03*
X1429587Y1527450D03*
X1424245Y1543338D03*
X1425558Y1537432D03*
X1433405Y1546001D03*
X1425260Y1558072D03*
X1433558Y1555366D03*
X1423701Y1563978D03*
X1432913Y1568679D03*
X1432000Y1644980D03*
X1445692Y5374D03*
X1445005Y24773D03*
X1449685Y34228D03*
X1445005Y44773D03*
X1436045Y77393D03*
Y74793D03*
Y85193D03*
Y82593D03*
Y79993D03*
X1444641Y94017D03*
X1448641D03*
X1440641D03*
X1444370Y101701D03*
Y98551D03*
X1436089Y92874D03*
X1447265Y111223D03*
Y114623D03*
X1435358Y116496D03*
Y109410D03*
X1449761Y115401D03*
Y110445D03*
X1444769D03*
Y115401D03*
X1435358Y102323D03*
X1447920Y103783D03*
X1438116Y107649D03*
Y104249D03*
X1449761Y124618D03*
X1444769D03*
Y129574D03*
X1435358Y130670D03*
Y123583D03*
X1449761Y129574D03*
X1447265Y125396D03*
Y128796D03*
X1435358Y137756D03*
X1442682Y147540D03*
X1446454Y141247D03*
X1451301Y148277D03*
X1442682Y151540D03*
X1435138Y162368D03*
X1437738D03*
X1444838Y162793D03*
Y165393D03*
Y170493D03*
Y167993D03*
X1451762Y177616D03*
X1449841Y181009D03*
X1447046Y181366D03*
X1443835Y181426D03*
X1446332Y191941D03*
X1446199Y188727D03*
X1444043Y184221D03*
X1446660Y184012D03*
X1448079Y211359D03*
Y213859D03*
X1436449Y213213D03*
Y210713D03*
X1440521Y211695D03*
X1443021D03*
X1440521Y208695D03*
X1443321D03*
X1436449Y208213D03*
Y228961D03*
X1444418Y229286D03*
X1442956Y226141D03*
X1436449Y226461D03*
X1440156Y226141D03*
X1436449Y223661D03*
X1448111Y222212D03*
Y224712D03*
X1436449Y231461D03*
Y215713D03*
X1440399Y236611D03*
X1442899D03*
X1444418Y231786D03*
X1445399Y236611D03*
X1448026Y256535D03*
X1440101Y248891D03*
X1442601D03*
X1445101D03*
X1451785Y265896D03*
X1446698Y265701D03*
X1441016Y267526D03*
Y270026D03*
X1443516D03*
X1438216D03*
X1443516Y267526D03*
X1438216D03*
X1448333Y281716D03*
X1440053Y285690D03*
X1437553D03*
X1440053Y288190D03*
X1442853D03*
Y285690D03*
X1447079Y290755D03*
X1437553Y288190D03*
X1449060Y329861D03*
X1448948Y326448D03*
X1449060Y320861D03*
X1438829Y329861D03*
X1437064Y320861D03*
X1448822Y345324D03*
X1448734Y332910D03*
X1448500Y340575D03*
X1439712Y336673D03*
X1440420Y346833D03*
X1449060Y356861D03*
X1441180Y354909D03*
X1448572Y349441D03*
X1449060Y352361D03*
X1447502Y360785D03*
X1434697Y347125D03*
X1439719Y350387D03*
X1443041Y363648D03*
X1440568Y369566D03*
X1449619Y363290D03*
X1437758Y362584D03*
X1434608D03*
X1438768Y371655D03*
X1442633Y371502D03*
X1445906Y366030D03*
X1438588Y380589D03*
X1440523Y382747D03*
X1435019Y434508D03*
X1435424Y430361D03*
X1437757Y447201D03*
X1437879Y444269D03*
X1440390Y456652D03*
X1442890D03*
X1435484Y470045D03*
X1442890Y459152D03*
Y461652D03*
X1440390Y459152D03*
Y461652D03*
X1436930Y461818D03*
X1442786Y480705D03*
X1437631Y482134D03*
Y484634D03*
X1449293Y476086D03*
X1445586Y480705D03*
X1441076Y475946D03*
Y478446D03*
X1449293Y478586D03*
Y481086D03*
Y483886D03*
X1433960Y491214D03*
X1449293Y491133D03*
X1435810Y504699D03*
X1442721Y495151D03*
X1437663Y492987D03*
X1442421Y498151D03*
X1433960Y493714D03*
X1437663Y495487D03*
X1445221Y498151D03*
X1449293Y493633D03*
Y496133D03*
Y498633D03*
X1445221Y495151D03*
X1447036Y519518D03*
X1435512Y516979D03*
X1439462Y522129D03*
X1444536Y519518D03*
X1439536D03*
X1442036D03*
X1439462Y529929D03*
X1435755Y527449D03*
X1439462Y527129D03*
Y524629D03*
X1443555Y532949D03*
X1446355D03*
X1439462Y537877D03*
X1449393Y553297D03*
Y555897D03*
X1446988Y548418D03*
X1439462Y540377D03*
X1435390Y541895D03*
X1444488Y548418D03*
X1439488D03*
X1441988D03*
X1439462Y542877D03*
Y545377D03*
X1438882Y572842D03*
X1449393Y558497D03*
Y566797D03*
Y563697D03*
Y561097D03*
X1443388Y570686D03*
X1446183Y570478D03*
X1447037Y585507D03*
X1442444D03*
X1442990Y579475D03*
X1435668Y572975D03*
Y582747D03*
X1446600Y576484D03*
X1446243Y573689D03*
X1443597Y573303D03*
X1449993Y578405D03*
X1442488Y590145D03*
X1447082Y590190D03*
X1435241Y593796D03*
X1438944Y597232D03*
X1443775Y596089D03*
X1448994Y596782D03*
X1434049Y608311D03*
X1446944Y605443D03*
X1440930Y613913D03*
Y616713D03*
Y619513D03*
X1434944Y605443D03*
X1438944Y605637D03*
X1437770Y628242D03*
X1440930Y636005D03*
Y633205D03*
X1437790Y625013D03*
X1440930Y638805D03*
X1435952Y642184D03*
X1437784Y683532D03*
X1446323Y673183D03*
X1437738Y686992D03*
X1448991Y694392D03*
X1451976Y693844D03*
X1437533Y704398D03*
Y699280D03*
X1438930Y716363D03*
X1436567Y727532D03*
X1446860Y730735D03*
X1446538Y719548D03*
X1437738Y730992D03*
X1446717Y735536D03*
X1437533Y743280D03*
Y748398D03*
X1447289Y776461D03*
X1446000Y770500D03*
X1443000Y798500D03*
Y794500D03*
X1451000Y793458D03*
Y798458D03*
X1450253Y787339D03*
X1443000Y802500D03*
X1447000Y810500D03*
Y818500D03*
X1435000D03*
X1448000Y834500D03*
X1443000Y842500D03*
Y838500D03*
Y846500D03*
X1435000Y834500D03*
X1449000Y844500D03*
X1435212Y854042D03*
X1448726Y864400D03*
X1438188Y867633D03*
X1443041Y873683D03*
X1437703Y880067D03*
X1439891Y873821D03*
X1449072Y892581D03*
X1435288Y897500D03*
X1445367Y891888D03*
X1441223Y891957D03*
X1435745Y901500D03*
X1443231Y899006D03*
X1439103Y898564D03*
X1447261Y898571D03*
X1446022Y927000D03*
X1444453Y938806D03*
X1448137Y949440D03*
X1439031Y957683D03*
X1441088Y976409D03*
X1439449Y979009D03*
X1433996Y981437D03*
X1440700Y981763D03*
X1435669Y1005366D03*
X1440869Y1010256D03*
X1440610Y1021567D03*
X1435266Y1031522D03*
X1435197Y1028372D03*
X1437064Y1098767D03*
X1442674Y1106365D03*
X1436949Y1101917D03*
X1436884Y1106897D03*
X1439699Y1110092D03*
X1443365Y1115896D03*
Y1118396D03*
X1441220Y1131935D03*
Y1139435D03*
Y1134435D03*
Y1136935D03*
X1434520Y1125801D03*
X1437020D03*
X1434520Y1129301D03*
X1437020D03*
X1441220Y1141935D03*
Y1144435D03*
Y1146935D03*
X1442448Y1152684D03*
Y1160834D03*
X1434820Y1162384D03*
Y1164884D03*
Y1167384D03*
Y1169884D03*
Y1172384D03*
X1437320D03*
Y1169884D03*
Y1167384D03*
Y1164884D03*
Y1162384D03*
X1434925Y1179421D03*
Y1181921D03*
Y1184421D03*
Y1186921D03*
X1434820Y1174884D03*
X1437320D03*
X1434925Y1204617D03*
X1437240Y1200821D03*
Y1198321D03*
Y1192621D03*
Y1190121D03*
X1434925Y1207117D03*
Y1209617D03*
Y1212117D03*
X1436736Y1222194D03*
Y1226194D03*
X1436408Y1303462D03*
X1444438Y1308312D03*
X1439482D03*
X1443660Y1310698D03*
X1440260D03*
X1441286Y1335776D03*
X1446817Y1335846D03*
X1441200Y1338700D03*
X1435900Y1340800D03*
X1439258Y1414600D03*
X1446135Y1530876D03*
X1443103Y1527201D03*
X1437293Y1546125D03*
X1441145Y1540415D03*
X1440153Y1563093D03*
X1443769Y1562173D03*
X1436801Y1568803D03*
X1464594Y3000D03*
X1462675Y14334D03*
X1452717Y34052D03*
X1457347Y31518D03*
X1457829Y26425D03*
X1455013Y43128D03*
X1457718Y84140D03*
Y76140D03*
Y80140D03*
X1460466Y76587D03*
Y72615D03*
X1452650Y94017D03*
X1461905Y100625D03*
X1454924Y97475D03*
X1460163Y117557D03*
X1455171D03*
X1463087Y103621D03*
X1451920Y103783D03*
X1454855Y106186D03*
X1455171Y122513D03*
X1460163Y131731D03*
Y122513D03*
X1455171Y131731D03*
X1457667Y118335D03*
Y121735D03*
Y132509D03*
X1458262Y146461D03*
X1460163Y136687D03*
X1455171D03*
X1457667Y135909D03*
X1462484Y141247D03*
X1466971Y143518D03*
X1453921Y143740D03*
X1466071Y152373D03*
X1457164Y152367D03*
X1463547Y180527D03*
X1458864Y180572D03*
X1455016Y168697D03*
X1452343Y172190D03*
X1464628Y171523D03*
X1458864Y185165D03*
X1463502Y185121D03*
X1452832Y184619D03*
X1456104Y191941D03*
X1464158Y192490D03*
X1454812Y206760D03*
X1458113Y206767D03*
X1463113D03*
X1460613D03*
X1451782Y213132D03*
X1463243Y221708D03*
X1460743D03*
X1458243D03*
X1457658Y224421D03*
X1459358Y231021D03*
Y228221D03*
X1451782Y215632D03*
X1459909Y236189D03*
X1464909D03*
X1462409D03*
X1456026Y256535D03*
X1459850Y248765D03*
X1464850D03*
X1462350D03*
X1452026Y256303D03*
X1456801Y266114D03*
X1457056Y279208D03*
X1461160Y281307D03*
X1460047Y270695D03*
Y268195D03*
X1462547Y270695D03*
Y268195D03*
X1465347Y270695D03*
Y268195D03*
X1454274Y281982D03*
X1465650Y293645D03*
X1455079Y290755D03*
X1451079D03*
X1465650Y288345D03*
Y290845D03*
X1463150Y288345D03*
Y290845D03*
Y293645D03*
X1451215Y323193D03*
X1451330Y327588D03*
X1459060Y320861D03*
Y325361D03*
X1451272Y340971D03*
X1451344Y336620D03*
X1451300Y332225D03*
X1459060Y329861D03*
Y338861D03*
Y343361D03*
Y334361D03*
X1451387Y345609D03*
X1451186Y350447D03*
X1458982Y356861D03*
X1459060Y347861D03*
Y352361D03*
X1455979Y391756D03*
X1459873Y391705D03*
X1463145Y391579D03*
X1458212Y403374D03*
X1458214Y406231D03*
X1464536Y433114D03*
X1458912Y581659D03*
X1455419Y578986D03*
X1454944Y596729D03*
Y605443D03*
X1453000Y614158D03*
Y616958D03*
Y619758D03*
X1450944Y605443D03*
X1458944D03*
X1453000Y633450D03*
Y636250D03*
Y639050D03*
X1461474Y655807D03*
X1455761Y683448D03*
X1468372Y673812D03*
X1460111Y683536D03*
X1451428Y673252D03*
X1460816Y727964D03*
X1455291Y759656D03*
X1455159Y763714D03*
X1453032Y769032D03*
X1454504Y777575D03*
X1454533Y784780D03*
X1454738Y772492D03*
X1454533Y789898D03*
X1453775Y813032D03*
X1453102Y821102D03*
X1454541Y831339D03*
X1453102Y826500D03*
X1452619Y836457D03*
X1461241Y867475D03*
X1462694Y874859D03*
Y877859D03*
X1461113Y871389D03*
X1460472Y885985D03*
X1457218Y888764D03*
X1452641Y888033D03*
X1459420Y899226D03*
X1451286Y898549D03*
X1462500Y905295D03*
X1451005Y931848D03*
X1461888Y936055D03*
X1462819Y949996D03*
X1462000Y960378D03*
Y957000D03*
X1458202Y960288D03*
X1460655Y964253D03*
X1457937Y966712D03*
X1457352Y976277D03*
X1466076Y979746D03*
X1459519Y989432D03*
X1467096Y988813D03*
X1462388Y1006560D03*
X1456966Y998507D03*
X1458892Y1007522D03*
X1465658Y1006648D03*
X1455939Y1018368D03*
X1465846Y1023900D03*
X1463025Y1018307D03*
X1459267Y1013678D03*
X1456280Y1023405D03*
X1459683Y1028377D03*
X1465503Y1030233D03*
X1452000Y1644980D03*
X1479409Y-83456D03*
Y-78500D03*
Y-68500D03*
Y-73456D03*
X1481905Y-69278D03*
Y-72678D03*
X1476822Y40780D03*
X1479972D03*
X1480460Y60922D03*
X1475296Y55513D03*
X1472146D03*
X1468371Y68581D03*
X1474746Y60513D03*
X1477606Y60438D03*
X1468384Y80581D03*
X1474874Y85731D03*
X1483287Y86012D03*
X1472489Y91951D03*
X1472514Y88801D03*
X1478428Y86046D03*
X1475431Y94351D03*
X1479380Y94279D03*
X1470567Y103621D03*
X1471093Y117261D03*
X1478624Y113394D03*
X1481273Y110784D03*
X1478624Y116594D03*
X1466278Y112083D03*
X1484567Y110784D03*
X1481368Y130898D03*
X1478624Y119594D03*
X1479058Y124283D03*
X1484124Y124879D03*
X1477465Y161306D03*
X1469221Y152562D03*
X1474716Y157370D03*
X1478800Y180665D03*
Y172665D03*
Y168665D03*
Y176665D03*
X1469913Y183834D03*
X1470023Y178560D03*
X1470086Y172665D03*
X1467270Y192421D03*
X1470899Y186629D03*
X1469433Y190185D03*
X1478800Y192665D03*
Y196665D03*
X1470203Y200864D03*
X1478913Y186778D03*
X1478832Y200864D03*
Y212864D03*
Y204864D03*
X1470292Y212455D03*
X1470226Y207037D03*
X1478832Y208864D03*
Y216864D03*
Y221864D03*
X1467593Y221642D03*
X1474473Y219379D03*
X1475101Y228631D03*
X1480589Y252371D03*
Y248371D03*
X1471507Y265897D03*
X1469007D03*
X1477549Y327200D03*
Y322700D03*
Y345200D03*
Y340700D03*
Y331700D03*
Y358700D03*
Y349700D03*
Y354200D03*
X1480702Y368516D03*
X1468309Y408861D03*
X1473364Y410724D03*
X1472403Y417338D03*
X1475236Y412482D03*
X1466231Y423671D03*
X1469538Y416795D03*
X1469293Y428815D03*
X1473900Y433100D03*
X1466653Y428582D03*
X1471375Y433115D03*
X1478710Y685630D03*
X1477597Y682997D03*
X1475264Y680933D03*
X1474713Y685247D03*
X1479297Y693630D03*
X1476794Y691447D03*
X1476716Y704398D03*
X1479500Y689630D03*
Y697630D03*
X1473525Y710052D03*
X1479500Y706500D03*
X1474425Y716075D03*
Y712925D03*
X1479759Y720885D03*
X1469957Y706957D03*
X1474000Y707000D03*
X1479794Y709388D03*
X1479962Y727500D03*
X1472000D03*
X1469116Y719055D03*
X1480000Y731500D03*
X1471415Y748629D03*
X1479500Y750500D03*
X1479759Y743500D03*
X1479657Y735500D03*
X1469957Y750957D03*
X1476716Y748398D03*
X1480000Y739500D03*
X1471006Y744818D03*
X1470801Y739280D03*
X1474425Y760075D03*
Y756925D03*
X1479665Y754555D03*
X1474000Y753093D03*
X1476677Y827626D03*
X1473634Y864337D03*
X1473489Y861354D03*
X1474060Y877196D03*
X1473468Y874267D03*
X1482387Y872940D03*
X1474883Y868206D03*
X1473433Y891043D03*
X1473387Y897425D03*
X1482195Y885807D03*
X1481454Y911570D03*
X1474075Y920575D03*
X1470925D03*
X1480343Y914776D03*
X1480109Y943496D03*
X1480144Y946880D03*
X1474349Y949394D03*
X1479441Y961941D03*
X1480414Y952214D03*
X1468500Y974181D03*
X1476500Y974000D03*
X1482237Y966028D03*
X1479196Y970000D03*
X1480414Y975064D03*
X1475096Y980330D03*
X1471096D03*
X1479096Y988813D03*
X1471296D03*
X1475096D03*
X1483096D03*
X1479096Y997860D03*
X1471096D03*
X1475096D03*
X1467096D03*
X1475062Y1008300D03*
Y1002453D03*
X1482535Y1024254D03*
X1468869Y1018469D03*
X1471854Y1035088D03*
X1479624Y1035102D03*
X1468371Y1030701D03*
X1476230Y1030672D03*
X1473230D03*
X1480193Y1102091D03*
X1474384D03*
X1480193Y1114691D03*
X1474384D03*
X1471374Y1118654D03*
X1474384Y1109564D03*
X1480231D03*
X1474384Y1122164D03*
X1480231D03*
X1480193Y1127291D03*
X1474384D03*
X1480193Y1139891D03*
X1474384D03*
Y1134764D03*
X1480231D03*
X1480193Y1152491D03*
X1474384D03*
Y1147364D03*
X1480231D03*
X1480193Y1165091D03*
X1474384D03*
Y1172564D03*
X1480231D03*
X1474384Y1159964D03*
X1480231D03*
X1480193Y1177691D03*
X1474384D03*
Y1185164D03*
X1480231D03*
X1477846Y1204932D03*
X1480675Y1202103D03*
X1483308Y1214372D03*
X1479063Y1218169D03*
X1476094Y1465913D03*
Y1461182D03*
Y1456451D03*
Y1471805D03*
Y1481267D03*
Y1476536D03*
Y1491890D03*
Y1487159D03*
Y1496621D03*
Y1502514D03*
Y1511976D03*
Y1507245D03*
Y1563544D03*
Y1558813D03*
Y1568275D03*
Y1578898D03*
Y1574167D03*
Y1583629D03*
Y1594253D03*
Y1589522D03*
Y1609607D03*
Y1598984D03*
Y1604876D03*
Y1614338D03*
X1472000Y1644980D03*
X1487851Y-77080D03*
X1491092Y-79984D03*
X1491104Y-77094D03*
X1487836Y-87777D03*
X1491089D03*
X1487851Y-85262D03*
X1491104D03*
X1491092Y-82584D03*
X1484811Y-86371D03*
X1491092Y-71970D03*
X1487836Y-74565D03*
X1491089Y-74579D03*
X1487836Y-64265D03*
X1491089D03*
X1491092Y-69470D03*
X1487851Y-66780D03*
X1491104D03*
X1484811Y-65585D03*
Y-75885D03*
X1484594Y3000D03*
X1498621Y15043D03*
Y19043D03*
X1489556Y17645D03*
X1498621Y35043D03*
Y27043D03*
Y31043D03*
Y23043D03*
X1489829Y29424D03*
X1490563Y23043D03*
X1490842Y102249D03*
X1500210Y97667D03*
X1483287Y94374D03*
X1486842Y102249D03*
X1482842D03*
X1493859Y109172D03*
X1496859D03*
X1495866Y106495D03*
X1490593Y116594D03*
X1495866Y102495D03*
X1489567Y110784D03*
X1488867Y133298D03*
X1490593Y119594D03*
X1494127Y125107D03*
X1489146Y124663D03*
X1495600Y146012D03*
X1497506Y141228D03*
X1483014Y134579D03*
X1495600Y142862D03*
X1496641Y148717D03*
X1490490Y138838D03*
X1486642Y195176D03*
X1488761Y198883D03*
X1489142Y195176D03*
X1484142D03*
X1491942D03*
X1488761Y201683D03*
X1492690Y206838D03*
X1490190D03*
X1484002Y203393D03*
X1486502D03*
X1493260Y226320D03*
X1493194Y221970D03*
X1490481Y216385D03*
X1493194Y216970D03*
Y219470D03*
X1486681Y218085D03*
X1483881D03*
X1496221Y228646D03*
X1492186Y238589D03*
X1495152Y236121D03*
X1495178Y232971D03*
X1491828Y244571D03*
X1489208Y249108D03*
X1495071Y253198D03*
X1499171Y256394D03*
X1497446Y295877D03*
X1484796Y320359D03*
X1484968Y325025D03*
X1486860Y327200D03*
X1500659Y330024D03*
X1495605Y322700D03*
X1487318Y318200D03*
X1486360Y322700D03*
X1484876Y329377D03*
X1488255Y342921D03*
X1484682Y338394D03*
X1497760Y336543D03*
X1486360Y345200D03*
X1500386Y344642D03*
X1486913Y340327D03*
X1487152Y331272D03*
X1495689Y332534D03*
X1495521Y340700D03*
X1487926Y347387D03*
X1486360Y358700D03*
Y354200D03*
Y349700D03*
X1495521Y349681D03*
X1495925Y358700D03*
X1499839Y354001D03*
X1483813Y368516D03*
X1486890Y368576D03*
X1494286Y372699D03*
X1488000Y731500D03*
X1495500Y750500D03*
X1488731Y739500D03*
X1496629Y765000D03*
X1496473Y769000D03*
X1496763Y777000D03*
X1493301Y776911D03*
X1496814Y773000D03*
X1497000Y781000D03*
X1491062Y793003D03*
X1496500Y792000D03*
X1496756Y785000D03*
X1491425Y798425D03*
X1499633Y787794D03*
X1493716Y789898D03*
X1486957Y792457D03*
X1495170Y796670D03*
X1491425Y801575D03*
X1496845Y813000D03*
X1487050Y809413D03*
X1496845Y809000D03*
X1496806Y817000D03*
X1496621Y829000D03*
X1496447Y821000D03*
X1486386Y825296D03*
X1493092Y820444D03*
X1493038Y833898D03*
X1495240Y825000D03*
X1491425Y845575D03*
X1496500Y836000D03*
X1489650Y836985D03*
X1491425Y842425D03*
X1486957Y836457D03*
X1492625Y837324D03*
X1489805Y866386D03*
X1497488Y873839D03*
X1491414Y875383D03*
X1488138Y878339D03*
Y872839D03*
X1494000Y884000D03*
X1498084Y894825D03*
X1492101Y894860D03*
X1482566Y882154D03*
X1494954Y895264D03*
X1498446Y912370D03*
X1496383Y898023D03*
X1497208Y909740D03*
X1496500Y919000D03*
X1496000Y922000D03*
X1487075Y920925D03*
X1484824Y927324D03*
X1487240Y924453D03*
X1485100Y943900D03*
X1496425Y943075D03*
X1497063Y934000D03*
X1496072Y940201D03*
X1483324Y939324D03*
X1482921Y931324D03*
X1485500Y932500D03*
X1496072Y950044D03*
X1482591Y961909D03*
X1486500Y947000D03*
X1497075Y961000D03*
X1487240Y952012D03*
X1496072Y953981D03*
X1485226Y973886D03*
X1492560Y974654D03*
X1495500Y972500D03*
X1489500D03*
X1487096Y988813D03*
X1491096D03*
X1495096D03*
X1499096D03*
X1482535Y1008262D03*
Y1002453D03*
X1495339Y1009354D03*
X1491839D03*
X1486030D03*
X1491096Y997860D03*
X1483096D03*
X1495096D03*
X1487096D03*
X1490235Y1004816D03*
X1487266Y1002046D03*
X1482535Y1011762D03*
X1495339Y1021954D03*
X1491839D03*
X1486030D03*
Y1016827D03*
X1491877D03*
X1486030Y1029427D03*
X1491877D03*
X1483693Y1102091D03*
X1496140Y1105091D03*
X1496185Y1102091D03*
X1483693Y1114691D03*
X1496140Y1117691D03*
X1496185Y1114691D03*
Y1127291D03*
X1483693D03*
Y1139891D03*
X1496140Y1130291D03*
X1496185Y1139891D03*
X1483693Y1152491D03*
X1496140Y1155491D03*
Y1142891D03*
X1496185Y1152491D03*
X1483693Y1165091D03*
X1496140Y1168091D03*
X1496185Y1165091D03*
X1483693Y1177691D03*
X1496140Y1180691D03*
X1496185Y1177691D03*
X1482705Y1200001D03*
X1489793Y1207737D03*
X1498197Y1209607D03*
X1492471Y1215195D03*
X1484055Y1223749D03*
X1497693Y1230407D03*
X1484755Y1465513D03*
Y1460782D03*
X1493417Y1465913D03*
Y1456451D03*
Y1461182D03*
Y1471805D03*
Y1476536D03*
Y1481267D03*
X1484755Y1476136D03*
Y1470244D03*
Y1480867D03*
Y1496221D03*
X1493417Y1487159D03*
Y1491890D03*
Y1496621D03*
X1484755Y1491490D03*
Y1485598D03*
Y1506845D03*
Y1500952D03*
Y1511576D03*
X1493417Y1507245D03*
Y1502514D03*
Y1511976D03*
X1484755Y1516307D03*
Y1563144D03*
X1493417Y1558813D03*
Y1563544D03*
Y1578898D03*
X1484755Y1567875D03*
Y1578498D03*
Y1572606D03*
X1493417Y1568275D03*
Y1574167D03*
X1484755Y1583229D03*
Y1593853D03*
Y1587960D03*
X1493417Y1583629D03*
Y1589522D03*
Y1594253D03*
X1484755Y1609207D03*
Y1598584D03*
Y1603315D03*
X1493417Y1609607D03*
Y1604876D03*
Y1598984D03*
X1484755Y1613938D03*
Y1618669D03*
X1493417Y1614338D03*
X1492000Y1644980D03*
X1514765Y-44536D03*
Y-39580D03*
Y-29580D03*
Y-34536D03*
X1500578Y4469D03*
X1501939Y24773D03*
Y44773D03*
X1509260Y53597D03*
X1508670Y103411D03*
X1509064Y97667D03*
X1504460Y95111D03*
X1511610Y116496D03*
Y109410D03*
Y102323D03*
X1499610Y116497D03*
X1506910D03*
X1504410D03*
X1506910Y109410D03*
X1509310Y114655D03*
Y111255D03*
X1508829Y106561D03*
X1511610Y123583D03*
X1499610Y130670D03*
Y123584D03*
X1506910Y130670D03*
X1504410D03*
Y123584D03*
X1506910Y123583D03*
X1511610Y130670D03*
X1502010Y121742D03*
X1509310Y125428D03*
Y128828D03*
X1502010Y118342D03*
Y132515D03*
X1511610Y137756D03*
X1499610Y137757D03*
X1504410D03*
X1502010Y135915D03*
X1502741Y143762D03*
X1500394Y150847D03*
X1506689Y195176D03*
X1506207Y199248D03*
X1501689Y195176D03*
X1503207Y199248D03*
X1499189Y195176D03*
X1504189D03*
X1508142Y213539D03*
X1506207Y202048D03*
X1503207Y201748D03*
X1499270Y210509D03*
X1501043Y206806D03*
X1501770Y210509D03*
X1503543Y206806D03*
X1509807Y230117D03*
X1500962Y230556D03*
X1505217Y227824D03*
X1509823Y238714D03*
X1502362Y247292D03*
X1501588Y238689D03*
X1505823Y238714D03*
X1499947Y242078D03*
X1505304Y246874D03*
X1507524Y244297D03*
X1500480Y295727D03*
X1503884Y295549D03*
X1501807Y323766D03*
X1501500Y321000D03*
X1501000Y317500D03*
X1501684Y336561D03*
X1516838Y347422D03*
X1515909Y354601D03*
X1509454Y402291D03*
X1514446D03*
X1509454Y397335D03*
X1514446D03*
X1511950Y401513D03*
Y398113D03*
X1509550Y412287D03*
X1512046Y411509D03*
X1507054Y416465D03*
Y411509D03*
X1512046Y425682D03*
X1507054D03*
X1512046Y416465D03*
X1509550Y415687D03*
Y426460D03*
X1512046Y439855D03*
X1507054D03*
X1512046Y430638D03*
X1507054D03*
X1509550Y440633D03*
Y429860D03*
X1512046Y444811D03*
X1507054D03*
X1507864Y450750D03*
X1509550Y444033D03*
X1516636Y458711D03*
X1509550Y472787D03*
X1507054Y468609D03*
X1512046D03*
X1507054Y473565D03*
X1512046D03*
X1509550Y469387D03*
X1507054Y487738D03*
X1512046D03*
X1507054Y482782D03*
X1512046D03*
X1509550Y483560D03*
Y486960D03*
X1507054Y517699D03*
X1512046D03*
X1507054Y512743D03*
X1512046D03*
X1509550Y516921D03*
Y513521D03*
Y527694D03*
X1511963Y536382D03*
X1507054Y526916D03*
X1512046Y531872D03*
X1507054D03*
X1512046Y526916D03*
X1509550Y531094D03*
X1513284Y552466D03*
X1504495Y796844D03*
X1510527Y833500D03*
X1504938Y859711D03*
X1500353Y859855D03*
X1500638Y873839D03*
X1512712Y867418D03*
X1507034Y888133D03*
X1502158Y899479D03*
X1507358Y909740D03*
X1507305Y912262D03*
X1510280Y899732D03*
X1510527Y908951D03*
X1513927D03*
X1504208Y909740D03*
X1509274Y921226D03*
X1505337Y921240D03*
X1514354Y938811D03*
X1510500Y931500D03*
X1509500Y937000D03*
Y944138D03*
X1516500Y947500D03*
X1501812Y938397D03*
X1513955Y950396D03*
X1512161Y957541D03*
X1509500Y950500D03*
X1505888Y965964D03*
X1501400Y966000D03*
X1514000Y968739D03*
X1510740Y973740D03*
X1498973Y975443D03*
X1511000Y970500D03*
X1511096Y988813D03*
X1507096D03*
X1503096D03*
X1515096D03*
X1507096Y997860D03*
X1503096D03*
X1511096D03*
X1499096D03*
X1513286Y1012354D03*
X1507831Y1009354D03*
X1507786Y1012354D03*
Y1024954D03*
X1513286D03*
X1507831Y1021954D03*
X1503572Y1034538D03*
X1505130Y1105091D03*
X1501640D03*
X1505130Y1117691D03*
X1501640D03*
X1505130Y1130291D03*
X1501640D03*
Y1142891D03*
X1505130D03*
Y1155491D03*
X1501640D03*
X1505130Y1168091D03*
X1501640D03*
X1505130Y1180691D03*
X1501640D03*
X1508356Y1220068D03*
X1500675Y1227300D03*
X1506807Y1234921D03*
X1507692Y1224472D03*
X1507058Y1229402D03*
X1502078Y1465513D03*
Y1460782D03*
X1510740Y1465913D03*
Y1456451D03*
Y1461182D03*
X1502078Y1470244D03*
Y1480867D03*
X1510740Y1471805D03*
Y1476536D03*
Y1481267D03*
X1502078Y1476136D03*
Y1491490D03*
Y1485598D03*
Y1496221D03*
X1510740Y1487159D03*
Y1491890D03*
Y1496621D03*
Y1507245D03*
Y1502514D03*
Y1511976D03*
X1502078Y1506845D03*
Y1500952D03*
Y1511576D03*
Y1516307D03*
X1510740Y1563544D03*
X1502078Y1563144D03*
X1510740Y1558813D03*
Y1578898D03*
X1502078Y1567875D03*
Y1578498D03*
Y1572606D03*
X1510740Y1568275D03*
Y1574167D03*
X1502078Y1583229D03*
Y1593853D03*
Y1587960D03*
X1510740Y1583629D03*
Y1589522D03*
Y1594253D03*
X1502078Y1609207D03*
Y1598584D03*
Y1603315D03*
X1510740Y1609607D03*
Y1604876D03*
Y1598984D03*
X1502078Y1613938D03*
Y1618669D03*
X1510740Y1614338D03*
X1512000Y1644980D03*
X1523192Y-48857D03*
X1526445D03*
X1523207Y-46342D03*
X1526460D03*
X1520167Y-47451D03*
X1526448Y-33050D03*
X1523192Y-35645D03*
X1526445Y-35659D03*
X1526448Y-30550D03*
X1523207Y-38160D03*
X1526448Y-41064D03*
X1526460Y-38174D03*
X1526448Y-43664D03*
X1520167Y-36965D03*
X1517261Y-33758D03*
Y-30358D03*
X1523192Y-25345D03*
X1526445D03*
X1523207Y-27860D03*
X1526460D03*
X1520167Y-26665D03*
X1529260Y53597D03*
X1520072Y82984D03*
Y75184D03*
Y77784D03*
Y80384D03*
X1522626Y92849D03*
X1520072Y85584D03*
X1525172Y90615D03*
X1519860Y90650D03*
X1529493Y99961D03*
X1529543Y95236D03*
X1519610D03*
X1529586Y103037D03*
X1519610Y102323D03*
X1519862Y109410D03*
Y116496D03*
X1529720D03*
Y109410D03*
X1520034Y124576D03*
X1529720Y130670D03*
Y123583D03*
X1521087Y130670D03*
X1526311Y137756D03*
X1521082D03*
X1528355Y210478D03*
Y215478D03*
Y212978D03*
Y207978D03*
Y228726D03*
Y223726D03*
Y226226D03*
Y231226D03*
X1515779Y351594D03*
X1519321Y378600D03*
X1517456Y390223D03*
X1522448D03*
X1519952Y391001D03*
X1519321Y382600D03*
X1519952Y394401D03*
X1517456Y395179D03*
Y404396D03*
Y409352D03*
X1522448Y395179D03*
Y404396D03*
Y409352D03*
X1519952Y408574D03*
Y405174D03*
Y422747D03*
X1517456Y418569D03*
Y423525D03*
X1522448D03*
Y418569D03*
X1519952Y419347D03*
Y436921D03*
X1522448Y437699D03*
X1517456Y432743D03*
Y437699D03*
X1522448Y432743D03*
X1519952Y433521D03*
X1519436Y458711D03*
X1521963Y453682D03*
X1520200Y455921D03*
X1518780Y463600D03*
X1519952Y479899D03*
X1517456Y489895D03*
X1522448D03*
X1517456Y480677D03*
Y475721D03*
X1522448Y480677D03*
Y475721D03*
X1519952Y476499D03*
Y490673D03*
Y494073D03*
X1517456Y494851D03*
X1522448D03*
X1517456Y519855D03*
X1522448D03*
X1519952Y520633D03*
Y524033D03*
Y534806D03*
X1522448Y538984D03*
X1517456D03*
Y524811D03*
Y534028D03*
X1522448D03*
Y524811D03*
X1519952Y538206D03*
X1528635Y555234D03*
X1528350Y562003D03*
X1519156Y596095D03*
X1516869Y594668D03*
X1518354Y592354D03*
X1518415Y589556D03*
X1519153Y599588D03*
X1516930Y597580D03*
X1519185Y603600D03*
Y615600D03*
X1519153Y607588D03*
X1519185Y619600D03*
X1523646Y634946D03*
X1519185Y623600D03*
X1520729Y634190D03*
X1524200Y646098D03*
X1519063Y876339D03*
X1518517Y878898D03*
X1518452Y873780D03*
X1517344Y896999D03*
X1515743Y888133D03*
X1517344Y903179D03*
X1517153Y908367D03*
X1516283Y912240D03*
X1519116D03*
X1523053Y912262D03*
X1525022Y909558D03*
X1522881Y901034D03*
X1522954Y897951D03*
X1523000Y923740D03*
X1526611Y921442D03*
X1525740Y928740D03*
X1521085Y921094D03*
X1515179D03*
X1527876Y939439D03*
X1528087Y936394D03*
X1527267Y932647D03*
X1522209Y937846D03*
X1521500Y947500D03*
X1528500Y947612D03*
X1524500Y949500D03*
X1525022Y957340D03*
X1530174Y956986D03*
X1529128Y952978D03*
X1521085Y957340D03*
X1525522Y971075D03*
X1525583Y968500D03*
X1530767Y972981D03*
X1519863Y977637D03*
X1525005Y974323D03*
X1523966Y980281D03*
X1530594Y979952D03*
X1531096Y988813D03*
X1523096D03*
X1519096D03*
X1515096Y997860D03*
X1531096D03*
X1519096D03*
X1523096D03*
X1527096D03*
X1516776Y1024954D03*
Y1012354D03*
X1526810Y1025090D03*
X1522904Y1021256D03*
X1521939Y1040818D03*
X1522099Y1035521D03*
X1531993Y1056453D03*
X1531961Y1050849D03*
X1524953Y1051037D03*
X1517855Y1053457D03*
X1519401Y1465513D03*
Y1460782D03*
X1528062Y1465913D03*
Y1456451D03*
Y1461182D03*
Y1481267D03*
X1519401Y1476136D03*
Y1470244D03*
Y1480867D03*
X1528062Y1471805D03*
Y1476536D03*
X1519401Y1491490D03*
Y1485598D03*
Y1496221D03*
X1528062Y1487159D03*
Y1491890D03*
Y1496621D03*
X1519401Y1506845D03*
Y1500952D03*
Y1511576D03*
X1528062Y1507245D03*
Y1502514D03*
Y1511976D03*
X1519401Y1516307D03*
Y1563144D03*
X1528062Y1558813D03*
Y1563544D03*
Y1578898D03*
X1519401Y1567875D03*
Y1578498D03*
Y1572606D03*
X1528062Y1568275D03*
Y1574167D03*
X1519401Y1587960D03*
X1528062Y1583629D03*
Y1589522D03*
Y1594253D03*
X1519401Y1583229D03*
Y1593853D03*
Y1609207D03*
Y1598584D03*
Y1603315D03*
X1528062Y1609607D03*
Y1604876D03*
Y1598984D03*
X1519401Y1613938D03*
Y1618669D03*
X1528062Y1614338D03*
X1547367Y44773D03*
X1538407Y85539D03*
Y82939D03*
Y75139D03*
Y80339D03*
Y77739D03*
X1547003Y94017D03*
X1543003D03*
X1546732Y101701D03*
Y98551D03*
X1538451Y92874D03*
X1547131Y110445D03*
Y115401D03*
X1537720Y116496D03*
Y109410D03*
Y102323D03*
X1540478Y107649D03*
Y104249D03*
X1547131Y129574D03*
X1537720Y130670D03*
Y123583D03*
X1547131Y124618D03*
X1537720Y137756D03*
X1545044Y147540D03*
Y151540D03*
X1540100Y162368D03*
X1537500D03*
X1547200Y162793D03*
Y165393D03*
Y167993D03*
Y170493D03*
X1546197Y181426D03*
X1548561Y188727D03*
X1546405Y184221D03*
X1538811Y213213D03*
Y210713D03*
X1542883Y211695D03*
X1545383D03*
X1542883Y208695D03*
X1545683D03*
X1538811Y208213D03*
Y226461D03*
X1542518Y226141D03*
X1538811Y228961D03*
Y231461D03*
X1546780Y229286D03*
X1538811Y223661D03*
X1545318Y226141D03*
X1538811Y215713D03*
X1542761Y236611D03*
X1545261D03*
X1546780Y231786D03*
X1542463Y248891D03*
X1544963D03*
X1534184Y264180D03*
X1531684D03*
X1531609Y258880D03*
X1549060Y265701D03*
X1545878Y270026D03*
X1543378D03*
X1540578D03*
X1543378Y267526D03*
X1540578D03*
X1545878D03*
X1531901Y293796D03*
X1539915Y288190D03*
X1542415Y285690D03*
X1539915D03*
X1542415Y288190D03*
X1545215D03*
Y285690D03*
X1534401Y293796D03*
X1544736Y305156D03*
X1541534Y322850D03*
X1545583Y316363D03*
X1539140Y320863D03*
X1545636Y325363D03*
X1542797Y329863D03*
X1545846Y334363D03*
X1544951Y343363D03*
X1541283Y354553D03*
X1538133D03*
X1545434Y352363D03*
X1546183Y541863D03*
Y545263D03*
X1544375Y553407D03*
X1546875D03*
X1544375Y550907D03*
X1546875D03*
X1542704Y572162D03*
X1543946Y569928D03*
X1546293Y570962D03*
X1546036Y568475D03*
X1548080Y910757D03*
X1547644Y903060D03*
X1532067Y1041832D03*
X1531947Y1046212D03*
X1531546Y1062769D03*
X1536909Y1151870D03*
Y1159350D03*
X1540649Y1155610D03*
X1545385Y1461183D03*
X1536724Y1465513D03*
Y1460782D03*
X1545385Y1465914D03*
Y1456452D03*
X1536724Y1476136D03*
Y1470244D03*
Y1480867D03*
X1545385Y1476537D03*
Y1471806D03*
Y1481268D03*
X1536724Y1491490D03*
Y1485598D03*
Y1496221D03*
X1545385Y1491891D03*
Y1487160D03*
Y1496622D03*
X1536724Y1506845D03*
Y1500952D03*
Y1511576D03*
X1545385Y1507246D03*
Y1502515D03*
Y1511977D03*
X1536724Y1516307D03*
X1545385Y1563544D03*
Y1558813D03*
X1536724Y1563144D03*
Y1567875D03*
X1545385Y1568275D03*
X1536724Y1578498D03*
Y1572606D03*
X1545385Y1578898D03*
Y1574167D03*
Y1594253D03*
Y1589522D03*
X1536724Y1583229D03*
X1545385Y1583629D03*
X1536724Y1593853D03*
Y1587960D03*
Y1609207D03*
Y1598584D03*
Y1603315D03*
X1545385Y1609607D03*
Y1598984D03*
Y1604876D03*
Y1614338D03*
X1536724Y1613938D03*
Y1618669D03*
X1532000Y1644980D03*
X1560080Y84140D03*
Y76140D03*
Y80140D03*
X1562828Y72615D03*
Y76587D03*
X1555012Y94017D03*
X1551003D03*
X1564267Y100625D03*
X1557286Y97475D03*
X1562525Y117557D03*
X1557533D03*
X1552123Y115401D03*
Y110445D03*
X1554282Y103783D03*
X1549627Y111223D03*
Y114623D03*
X1557217Y106186D03*
X1550282Y103783D03*
X1549627Y128796D03*
X1560029Y132509D03*
Y121735D03*
X1562525Y122513D03*
X1552123Y129574D03*
Y124618D03*
X1557533Y131731D03*
Y122513D03*
X1562525Y131731D03*
X1560029Y118335D03*
X1549627Y125396D03*
X1560029Y135909D03*
X1560624Y146461D03*
X1557533Y136687D03*
X1562525D03*
X1548816Y141247D03*
X1564846D03*
X1556283Y143740D03*
X1553663Y148277D03*
X1559526Y152367D03*
X1561226Y180572D03*
X1552203Y181009D03*
X1549408Y181366D03*
X1557378Y168697D03*
X1554705Y172190D03*
X1554124Y177616D03*
X1548694Y191941D03*
X1555194Y184619D03*
X1561226Y185165D03*
X1558466Y191941D03*
X1549022Y184012D03*
X1557174Y206760D03*
X1560475Y206767D03*
X1562975D03*
X1554144Y213132D03*
X1550441Y211359D03*
Y213859D03*
X1550473Y222212D03*
Y224712D03*
X1560605Y221708D03*
X1560020Y224421D03*
X1563105Y221708D03*
X1561720Y231021D03*
Y228221D03*
X1554144Y215632D03*
X1547761Y236611D03*
X1562271Y236189D03*
X1550388Y256535D03*
X1558388D03*
X1547463Y248891D03*
X1562212Y248765D03*
X1554388Y256303D03*
X1559163Y266114D03*
X1554147Y265896D03*
X1559418Y279208D03*
X1563522Y281307D03*
X1562409Y268195D03*
Y270695D03*
X1556636Y281982D03*
X1550695Y281716D03*
X1549441Y290755D03*
X1553441D03*
X1557441D03*
X1547972Y304906D03*
X1550931Y305158D03*
X1556151Y318596D03*
X1556294Y327814D03*
X1554403Y316363D03*
X1553534Y327337D03*
X1556437Y332022D03*
X1556380Y336917D03*
X1556498Y340958D03*
X1553910Y331798D03*
X1553597Y336601D03*
X1553862Y344867D03*
X1551175Y347283D03*
X1556353Y345636D03*
X1554403Y352363D03*
X1556429Y389154D03*
X1563248D03*
X1548629D03*
Y403327D03*
Y410413D03*
X1556429Y396240D03*
X1557708Y404911D03*
X1561778Y396240D03*
X1548629D03*
X1556662Y412571D03*
X1557849Y426299D03*
X1548629Y417500D03*
Y424587D03*
Y438760D03*
Y431673D03*
X1558160Y445847D03*
X1548629D03*
X1556429Y467539D03*
X1548629D03*
X1556429Y474626D03*
X1548629D03*
Y488799D03*
X1556690Y480828D03*
X1548629Y481713D03*
Y495886D03*
X1558640Y498834D03*
X1548629Y511673D03*
Y518760D03*
X1562089Y516841D03*
X1556429Y518760D03*
Y511673D03*
X1548629Y540020D03*
Y525847D03*
Y532933D03*
X1556429Y525847D03*
X1548629Y547106D03*
X1556914Y552872D03*
X1557036Y550123D03*
X1556588Y545528D03*
X1556359Y562443D03*
X1558668Y572334D03*
X1558127Y560675D03*
X1548359Y569426D03*
X1548645Y566929D03*
X1556900Y574102D03*
X1547910Y602197D03*
X1562385Y598400D03*
Y602400D03*
Y594400D03*
X1548374Y595108D03*
X1562385Y614400D03*
Y606400D03*
Y610400D03*
X1561535Y653161D03*
X1564670Y650122D03*
X1565132Y668153D03*
X1561552Y665455D03*
X1565132Y677843D03*
X1547813Y906581D03*
X1548629Y927836D03*
X1548504Y915689D03*
X1548616Y931602D03*
X1551099Y959096D03*
X1551163Y952888D03*
X1552000Y969850D03*
Y1644980D03*
X1576256Y-48799D03*
X1573003D03*
X1576241Y-46284D03*
X1572988D03*
X1579281Y-47479D03*
X1573000Y-41094D03*
X1576256Y-38499D03*
X1573003Y-38485D03*
X1573000Y-43594D03*
X1576241Y-35984D03*
X1573000Y-33080D03*
X1572988Y-35970D03*
X1573000Y-30480D03*
X1579281Y-37179D03*
X1576256Y-25273D03*
X1573003Y-25287D03*
X1576241Y-27788D03*
X1572988Y-27802D03*
X1579281Y-26693D03*
X1571895Y58013D03*
X1570733Y68581D03*
X1577108Y60513D03*
X1570746Y80581D03*
X1577236Y85731D03*
X1574851Y91951D03*
X1574876Y88801D03*
X1581742Y94279D03*
X1577793Y94351D03*
X1572929Y103621D03*
X1573455Y117261D03*
X1565449Y103621D03*
X1568640Y112083D03*
X1581420Y124283D03*
X1569333Y143518D03*
X1568433Y152373D03*
X1579827Y161306D03*
X1571583Y152562D03*
X1577078Y157370D03*
X1565909Y180527D03*
X1572275Y183834D03*
X1566990Y171523D03*
X1572385Y178560D03*
X1572448Y172665D03*
X1569632Y192421D03*
X1565864Y185121D03*
X1573261Y186629D03*
X1571795Y190185D03*
X1566520Y192490D03*
X1572565Y200864D03*
X1565475Y206767D03*
X1572654Y212455D03*
X1572588Y207037D03*
X1581194Y208864D03*
X1565605Y221708D03*
X1569955Y221642D03*
X1576835Y219379D03*
X1577463Y228631D03*
X1564771Y236189D03*
X1567271D03*
X1564712Y248765D03*
X1567212D03*
X1567709Y270695D03*
X1573869Y265897D03*
X1571369D03*
X1567709Y268195D03*
X1564909Y270695D03*
Y268195D03*
X1565512Y288345D03*
X1568012Y293645D03*
Y290845D03*
Y288345D03*
X1565512Y293645D03*
Y290845D03*
X1563877Y325363D03*
Y316363D03*
X1574845Y338843D03*
X1571625Y333549D03*
Y344131D03*
X1574775Y333549D03*
X1563877Y329863D03*
Y343363D03*
Y334363D03*
X1578587Y341787D03*
X1578420Y338309D03*
X1574775Y344127D03*
X1563877Y352363D03*
X1574540Y389154D03*
X1575935Y382109D03*
X1579340Y396240D03*
Y403327D03*
Y410413D03*
X1574540Y396240D03*
Y403327D03*
Y410413D03*
X1576940Y398082D03*
Y401482D03*
X1566555Y414823D03*
X1565863Y422864D03*
X1579340Y417500D03*
Y424586D03*
X1574540Y417500D03*
Y424586D03*
X1576940Y415655D03*
Y412255D03*
Y426428D03*
X1565933Y429832D03*
X1565538Y436447D03*
X1574540Y438760D03*
X1579340Y431673D03*
Y438760D03*
X1574540Y431673D03*
X1576940Y440602D03*
Y429828D03*
X1567573Y447953D03*
X1579340Y445847D03*
X1574540D03*
X1576940Y444002D03*
X1566740Y467539D03*
X1574540D03*
X1565482Y472772D03*
X1574540Y474626D03*
X1579340D03*
Y488799D03*
X1574540D03*
X1566216Y487711D03*
X1566329Y479104D03*
X1574540Y481713D03*
X1579340Y481712D03*
X1576940Y476468D03*
Y490641D03*
Y479868D03*
X1579340Y495886D03*
X1574540D03*
X1566740D03*
X1576940Y494041D03*
X1579340Y518760D03*
X1574540Y511673D03*
Y518760D03*
X1565050Y511673D03*
X1576940Y520602D03*
Y524002D03*
X1574540Y540020D03*
X1579340D03*
Y532933D03*
Y525846D03*
X1574540Y525847D03*
Y532933D03*
X1576940Y534775D03*
Y538175D03*
X1574540Y547106D03*
Y554193D03*
X1577862Y554121D03*
X1575000Y565414D03*
Y567914D03*
Y570414D03*
X1575934Y561420D03*
Y558917D03*
X1575000Y572914D03*
Y575414D03*
X1565323Y577716D03*
X1571755Y577937D03*
X1574540Y602205D03*
Y595118D03*
X1579753Y599100D03*
X1579760Y595500D03*
X1574760Y606929D03*
X1579260Y604567D03*
X1578679Y613047D03*
X1578114Y607563D03*
X1574720Y618400D03*
X1575001Y612592D03*
X1580418Y610072D03*
X1580354Y616317D03*
X1574222Y629872D03*
X1576297Y627600D03*
X1577077Y631712D03*
X1574880Y645891D03*
X1571888Y649380D03*
X1569926Y668885D03*
X1575950Y662981D03*
X1572141D03*
X1578000Y678776D03*
X1569434Y677111D03*
X1570331Y691851D03*
X1568872Y686971D03*
X1575942Y705043D03*
X1575192Y707592D03*
X1572000Y1644980D03*
X1583000Y-80014D03*
X1586256Y-77419D03*
X1583003Y-77405D03*
X1586256Y-87719D03*
X1583003D03*
X1583000Y-82514D03*
X1586241Y-85204D03*
X1582988D03*
X1589281Y-86399D03*
X1594683Y-83484D03*
Y-78528D03*
X1586241Y-74904D03*
X1583000Y-72000D03*
X1582988Y-74890D03*
X1586256Y-64207D03*
X1583003D03*
X1586241Y-66722D03*
X1582988D03*
X1583000Y-69400D03*
X1589281Y-76099D03*
Y-65613D03*
X1594683Y-68528D03*
Y-73484D03*
X1592187Y-69306D03*
Y-72706D03*
X1584683Y-44564D03*
Y-29608D03*
Y-34564D03*
Y-39608D03*
X1582187Y-33786D03*
Y-30386D03*
X1582822Y60922D03*
X1580327Y57448D03*
X1579968Y60438D03*
X1585649Y86012D03*
X1593204Y102249D03*
X1585649Y94374D03*
X1580790Y86046D03*
X1585204Y102249D03*
X1589204D03*
X1580986Y113394D03*
X1583635Y110784D03*
X1592955Y116594D03*
X1580986D03*
X1586929Y110784D03*
X1591929D03*
X1591229Y133298D03*
X1583229D03*
X1592955Y119594D03*
X1580986D03*
X1596489Y125107D03*
X1586486Y124879D03*
X1591508Y124663D03*
X1585376Y134579D03*
X1592852Y138838D03*
X1581162Y180665D03*
Y172665D03*
Y168665D03*
Y176665D03*
X1586504Y195176D03*
X1594304D03*
X1589004D03*
X1591123Y198883D03*
X1591504Y195176D03*
X1581162Y192665D03*
Y196665D03*
X1581275Y186778D03*
X1581194Y212864D03*
Y200864D03*
X1586364Y203393D03*
X1588864D03*
X1591123Y201683D03*
X1595052Y206838D03*
X1592552D03*
X1581194Y204864D03*
Y221864D03*
Y216864D03*
X1586243Y218085D03*
X1595622Y226320D03*
X1592843Y216385D03*
X1595556Y216970D03*
Y219470D03*
Y221970D03*
X1589043Y218085D03*
X1594548Y238589D03*
X1594190Y244571D03*
X1591570Y249108D03*
X1582951Y252371D03*
Y248371D03*
X1593290Y339876D03*
X1595069Y337361D03*
X1595109Y342663D03*
X1594466Y350984D03*
X1586640Y389153D03*
X1581840D03*
X1584240Y390995D03*
X1581840Y403326D03*
Y410413D03*
X1586640D03*
X1581840Y396240D03*
X1586640D03*
Y403326D03*
X1584240Y408568D03*
Y405168D03*
Y394395D03*
X1586640Y417499D03*
X1581840D03*
Y424586D03*
X1586640D03*
X1584240Y419341D03*
Y422741D03*
X1581840Y438760D03*
X1586640D03*
Y431673D03*
X1581840D03*
X1584240Y433515D03*
Y436915D03*
X1592635Y455911D03*
X1586640Y467539D03*
X1581840D03*
Y474626D03*
X1586640D03*
X1584240Y472781D03*
Y469381D03*
X1591443Y465332D03*
X1581840Y488799D03*
X1586640D03*
X1581840Y481712D03*
X1586640D03*
X1584240Y483554D03*
Y486954D03*
X1581840Y518760D03*
Y511673D03*
X1586640D03*
Y518760D03*
X1584240Y516915D03*
Y513515D03*
X1586640Y525846D03*
Y532933D03*
X1581840D03*
Y525846D03*
X1584240Y531088D03*
Y527688D03*
X1595185Y543925D03*
X1595760Y555000D03*
X1595460Y549800D03*
X1595260Y547075D03*
X1583720Y560500D03*
X1594760Y568000D03*
X1595364Y562800D03*
X1595300Y558800D03*
X1592020Y1433061D03*
X1596790Y1442557D03*
X1592643Y1460707D03*
X1593019Y1457557D03*
X1591610Y1469940D03*
X1591775Y1473090D03*
X1596038Y1492000D03*
X1591586Y1505130D03*
X1591925Y1512075D03*
X1591333Y1501980D03*
X1590748Y1523377D03*
X1604301Y44773D03*
X1611622Y53597D03*
X1602572Y97667D03*
X1611032Y103411D03*
X1611426Y97667D03*
X1606822Y95111D03*
X1609272Y109410D03*
X1601972Y116497D03*
X1609272D03*
X1606772D03*
X1596221Y109172D03*
X1599221D03*
X1598228Y106495D03*
X1611672Y111255D03*
Y114655D03*
X1598228Y102495D03*
X1611191Y106561D03*
X1601972Y123584D03*
Y130670D03*
X1606772Y123584D03*
X1609272Y123583D03*
Y130670D03*
X1606772D03*
X1604372Y118342D03*
X1611672Y125428D03*
X1604372Y121742D03*
X1611672Y128828D03*
X1604372Y132515D03*
X1606772Y137757D03*
X1597962Y146012D03*
X1599868Y141228D03*
X1601972Y137757D03*
X1604372Y135915D03*
X1597962Y142862D03*
X1605103Y143762D03*
X1599003Y148717D03*
X1602756Y150847D03*
X1604051Y195176D03*
X1605569Y199248D03*
X1601551Y195176D03*
X1606551D03*
X1609051D03*
X1608569Y199248D03*
X1610504Y213539D03*
X1603405Y206806D03*
X1605905D03*
X1601632Y210509D03*
X1604132D03*
X1608569Y202048D03*
X1605569Y201748D03*
X1603324Y230556D03*
X1607579Y227824D03*
X1612169Y230117D03*
X1598583Y228646D03*
X1604724Y247292D03*
X1597514Y236121D03*
X1612185Y238714D03*
X1603950Y238689D03*
X1608185Y238714D03*
X1602309Y242078D03*
X1607666Y246874D03*
X1597540Y232971D03*
X1609886Y244297D03*
X1597433Y253198D03*
X1604677D03*
X1597006Y290417D03*
X1596691Y287397D03*
X1596197Y293477D03*
X1608240Y329000D03*
X1603664Y342596D03*
X1607947Y332326D03*
X1605966Y343794D03*
X1598223Y351003D03*
X1602138Y351047D03*
X1599127Y375587D03*
X1596253Y375633D03*
X1596714Y383003D03*
X1599527Y392718D03*
X1596534Y379760D03*
X1599527Y408718D03*
Y400718D03*
Y404718D03*
Y396718D03*
Y412718D03*
X1596760Y530000D03*
X1596260Y540500D03*
X1614338Y636842D03*
X1611316Y685800D03*
X1611027Y722427D03*
X1611327Y735973D03*
X1611627Y780327D03*
X1609500Y776100D03*
X1611873Y795127D03*
X1606190Y803774D03*
X1606709Y819165D03*
X1597225Y1437014D03*
X1600333Y1440504D03*
X1596836Y1446488D03*
X1600333Y1449068D03*
X1603363Y1460570D03*
X1597457Y1452556D03*
X1601968Y1453442D03*
X1597457Y1460662D03*
X1598500Y1472500D03*
X1606745Y1474242D03*
X1605430Y1468023D03*
X1597039Y1475100D03*
X1599726Y1474990D03*
X1602580Y1483108D03*
X1598000Y1486000D03*
X1600008Y1488492D03*
X1601500Y1514500D03*
X1608500Y1506000D03*
X1604000Y1516000D03*
X1608500Y1515000D03*
X1613790Y1531334D03*
X1609348Y1527334D03*
X1613790Y1523334D03*
X1604000Y1519000D03*
X1600700Y1534300D03*
X1600732Y1539334D03*
X1609348Y1535334D03*
X1598574Y1543373D03*
X1622434Y82984D03*
Y80384D03*
Y75184D03*
Y77784D03*
X1624988Y92849D03*
X1622434Y85584D03*
X1622222Y90650D03*
X1627534Y90615D03*
X1621972Y95236D03*
Y102323D03*
X1622224Y109410D03*
Y116496D03*
X1613972D03*
Y102323D03*
Y109410D03*
X1622396Y124576D03*
X1623449Y130670D03*
X1613972D03*
Y123583D03*
X1623444Y137756D03*
X1613972D03*
X1626147Y351033D03*
X1628636Y422088D03*
X1625952Y431029D03*
X1626260Y427017D03*
X1625018Y435029D03*
X1623955Y442956D03*
X1625772Y438323D03*
X1625938Y449873D03*
X1621596Y456386D03*
X1625938Y445873D03*
X1625565Y472579D03*
X1620385Y465874D03*
X1627965Y474424D03*
X1625565Y479666D03*
Y486752D03*
X1627965Y488597D03*
Y477824D03*
X1625565Y493839D03*
X1627965Y491997D03*
X1625565Y523800D03*
Y516713D03*
X1627965Y521958D03*
Y518558D03*
X1625565Y537973D03*
Y530886D03*
X1627965Y536131D03*
Y532731D03*
X1616622Y546712D03*
Y542712D03*
X1625565Y566752D03*
X1627965Y571997D03*
Y568597D03*
X1625565Y588013D03*
Y573839D03*
Y580926D03*
X1627965Y582771D03*
Y586171D03*
X1625565Y602186D03*
Y595099D03*
X1627965Y596944D03*
Y600344D03*
X1625565Y609272D03*
Y616359D03*
X1627965Y614517D03*
Y611117D03*
X1618538Y618288D03*
X1614538D03*
X1620244Y638125D03*
X1627224Y643252D03*
X1617843Y665140D03*
X1613362Y656321D03*
X1621362D03*
X1617362D03*
X1613110Y678462D03*
X1616260D03*
X1619950Y678519D03*
X1615913Y692245D03*
X1624148Y708258D03*
X1628200Y711417D03*
X1612800Y705900D03*
X1620600D03*
X1620500Y723200D03*
X1628343Y747288D03*
X1616683Y744517D03*
X1620100Y738300D03*
X1627455Y759489D03*
X1624000Y760900D03*
X1612573Y761427D03*
X1619612Y783152D03*
X1620359Y774830D03*
X1619569Y796035D03*
X1620755Y787530D03*
X1613235Y808466D03*
X1620479Y815730D03*
X1620072Y801630D03*
X1628027Y801427D03*
X1616255Y824405D03*
X1613117Y828117D03*
X1619859Y839519D03*
X1618800Y1528558D03*
X1614200Y1519500D03*
X1614360Y1542860D03*
X1618600Y1532000D03*
X1631622Y53597D03*
X1640769Y85539D03*
Y82939D03*
Y75139D03*
Y80339D03*
Y77739D03*
X1640813Y92874D03*
X1631905Y95236D03*
X1631855Y99961D03*
X1631948Y103037D03*
X1632082Y116496D03*
Y109410D03*
X1640082Y116496D03*
Y109410D03*
Y102323D03*
X1642840Y104249D03*
Y107649D03*
X1632082Y130670D03*
Y123583D03*
X1640082Y130670D03*
Y123583D03*
X1628673Y137756D03*
X1640082D03*
X1639862Y162368D03*
X1642462D03*
X1641173Y213213D03*
Y210713D03*
Y208213D03*
X1630717Y210478D03*
Y215478D03*
Y212978D03*
Y207978D03*
X1641173Y231461D03*
X1630717Y223726D03*
Y226226D03*
Y231226D03*
Y228726D03*
X1641173Y223661D03*
Y226461D03*
X1644880Y226141D03*
X1641173Y228961D03*
Y215713D03*
X1644825Y248891D03*
X1634046Y264180D03*
X1636546D03*
X1633971Y258880D03*
X1642940Y267526D03*
Y270026D03*
X1644777Y288190D03*
X1642277Y285690D03*
X1644777D03*
X1642277Y288190D03*
X1636763Y293796D03*
X1634263D03*
X1629553Y329067D03*
X1632230Y330400D03*
X1635987Y335616D03*
X1629302Y334402D03*
X1640030Y335550D03*
X1636561Y343072D03*
X1629514Y331727D03*
X1630703Y350655D03*
X1636468Y345595D03*
X1630691Y347432D03*
X1640197Y374690D03*
X1638340Y379536D03*
X1641615Y379600D03*
X1636271Y410394D03*
Y403307D03*
X1637205Y440098D03*
Y437598D03*
Y435098D03*
Y432598D03*
Y430098D03*
X1635170Y442856D03*
X1637665Y458406D03*
Y451319D03*
X1632439Y452265D03*
X1633225Y458455D03*
X1636271Y453881D03*
X1635185Y446595D03*
X1637489Y462264D03*
X1632865Y465492D03*
X1637665D03*
Y472579D03*
X1632865D03*
X1630365D03*
X1635265Y470737D03*
Y467337D03*
X1630365Y479666D03*
X1632865D03*
X1637665Y479665D03*
Y486752D03*
X1630365D03*
X1632865D03*
X1635265Y484910D03*
Y481510D03*
X1630365Y493839D03*
X1637665D03*
X1632865Y509626D03*
Y516713D03*
X1630365D03*
Y523800D03*
X1632865D03*
X1637665Y523799D03*
Y516713D03*
Y509626D03*
X1635265Y514871D03*
Y511471D03*
X1630365Y530886D03*
X1637665D03*
X1632865D03*
X1637665Y537973D03*
X1630365D03*
X1635265Y529044D03*
Y525644D03*
X1637665Y559665D03*
Y566752D03*
X1630365D03*
X1632865D03*
Y559665D03*
X1635265Y564910D03*
Y561510D03*
X1632865Y573839D03*
X1630365Y580926D03*
X1632865D03*
X1637665D03*
Y588012D03*
X1630365Y588013D03*
X1632865Y588012D03*
X1637665Y573839D03*
X1630365D03*
X1635265Y575684D03*
Y579084D03*
X1632865Y602185D03*
X1630365Y602186D03*
X1637665Y602185D03*
Y595099D03*
X1632865D03*
X1630365D03*
X1635265Y593257D03*
Y604030D03*
Y589857D03*
X1630365Y616359D03*
X1632865Y609272D03*
X1630365D03*
X1637665Y616358D03*
Y609272D03*
X1635265Y607430D03*
X1637526Y699930D03*
X1637472Y717830D03*
X1631031Y732430D03*
X1628813Y727045D03*
X1635283Y728117D03*
X1631187Y750630D03*
X1629969Y740826D03*
X1630327Y774627D03*
X1629927Y787327D03*
X1644552Y871353D03*
X1644304Y891353D03*
X1635176Y886761D03*
X1644718Y909263D03*
X1635000Y919263D03*
X1644325Y942120D03*
X1637771Y952120D03*
X1640581Y1551907D03*
X1650417Y5374D03*
X1649730Y24773D03*
Y44773D03*
X1649365Y94017D03*
X1657374D03*
X1653365D03*
X1645365D03*
X1649094Y101701D03*
Y98551D03*
X1659648Y97475D03*
X1659895Y117557D03*
X1654485Y110445D03*
Y115401D03*
X1649493Y110445D03*
Y115401D03*
X1656644Y103783D03*
X1651989Y114623D03*
Y111223D03*
X1652644Y103783D03*
X1659579Y106186D03*
X1659895Y122513D03*
Y131731D03*
X1654485Y124618D03*
Y129574D03*
X1649493Y124618D03*
Y129574D03*
X1651989Y125396D03*
Y128796D03*
X1659895Y136687D03*
X1647406Y147540D03*
X1651178Y141247D03*
X1658645Y143740D03*
X1656025Y148277D03*
X1647406Y151540D03*
X1649562Y162793D03*
Y165393D03*
Y167993D03*
Y170493D03*
X1656486Y177616D03*
X1654565Y181009D03*
X1648559Y181426D03*
X1651770Y181366D03*
X1659740Y168697D03*
X1657067Y172190D03*
X1651056Y191941D03*
X1657556Y184619D03*
X1650923Y188727D03*
X1660828Y191941D03*
X1651384Y184012D03*
X1648767Y184221D03*
X1659536Y206760D03*
X1647745Y211695D03*
X1645245Y208695D03*
X1648045D03*
X1656506Y213132D03*
X1652803Y211359D03*
Y213859D03*
X1645245Y211695D03*
X1647680Y226141D03*
X1649142Y229286D03*
X1652835Y222212D03*
Y224712D03*
X1656506Y215632D03*
X1645123Y236611D03*
X1650123D03*
X1647623D03*
X1649142Y231786D03*
X1647325Y248891D03*
X1649825D03*
X1660750Y256535D03*
X1652750D03*
X1656750Y256303D03*
X1656509Y265896D03*
X1661525Y266114D03*
X1651422Y265701D03*
X1648240Y267526D03*
X1645740D03*
Y270026D03*
X1648240D03*
X1653057Y281716D03*
X1658998Y281982D03*
X1647577Y285690D03*
Y288190D03*
X1655803Y290755D03*
X1651803D03*
X1659803D03*
X1658200Y315039D03*
X1654771Y352088D03*
X1645685Y390500D03*
X1655335Y381500D03*
X1645685D03*
X1648835Y390500D03*
X1655555Y430760D03*
X1655576Y433570D03*
X1655392Y437072D03*
X1655433Y439963D03*
X1650044Y435158D03*
X1649789Y440489D03*
X1646209Y442606D03*
X1655677Y443180D03*
X1655697Y454744D03*
X1655639Y452018D03*
X1650087Y444841D03*
X1649773Y449961D03*
X1653490Y458572D03*
X1645826Y446606D03*
X1653507Y470136D03*
X1645465Y466027D03*
X1655776Y465492D03*
X1655742Y460250D03*
X1655776Y472579D03*
X1645607Y475262D03*
X1647133Y463479D03*
X1647604Y467367D03*
X1645607Y489435D03*
X1655776Y486752D03*
Y479665D03*
X1645607Y482666D03*
X1645423Y495088D03*
X1655776Y493839D03*
X1646158Y514608D03*
X1646080Y522134D03*
X1645465Y509626D03*
X1655776D03*
Y516713D03*
X1646562Y535677D03*
X1646723Y529136D03*
X1652236Y537973D03*
X1654716Y525483D03*
X1654637Y532756D03*
X1645465Y559665D03*
X1645846Y565574D03*
X1655776Y559665D03*
Y566752D03*
X1645493Y574338D03*
X1655626Y579978D03*
X1655776Y573839D03*
X1645592Y616358D03*
X1655840Y608117D03*
X1654572Y771702D03*
X1656112Y768669D03*
X1657042Y773604D03*
X1647402Y881460D03*
X1648375Y886766D03*
X1645128Y929263D03*
X1650205Y925911D03*
X1647763Y919268D03*
X1648387Y945554D03*
X1645342Y962120D03*
X1647470Y952125D03*
X1657091Y990823D03*
X1649571Y983857D03*
X1651443Y981515D03*
X1647565Y981432D03*
X1652944Y993796D03*
X1653414Y990590D03*
X1657983Y1460782D03*
X1649322Y1456451D03*
Y1465913D03*
X1657983Y1465513D03*
X1649322Y1461182D03*
Y1476536D03*
X1657983Y1476136D03*
Y1470244D03*
X1649322Y1471805D03*
Y1481267D03*
X1657983Y1480867D03*
X1649322Y1487159D03*
Y1496621D03*
X1657983Y1496221D03*
X1649322Y1491890D03*
X1657983Y1491490D03*
Y1485598D03*
Y1500952D03*
X1649322Y1502514D03*
X1657983Y1511576D03*
X1649322Y1511976D03*
Y1507245D03*
X1657983Y1506845D03*
Y1516307D03*
X1649322Y1558813D03*
Y1563544D03*
X1657983Y1563144D03*
Y1572606D03*
X1649322Y1574167D03*
Y1568275D03*
X1657983Y1567875D03*
X1649322Y1578898D03*
X1657983Y1578498D03*
X1649322Y1583629D03*
X1657983Y1583229D03*
X1649322Y1594253D03*
X1657983Y1593853D03*
Y1587960D03*
X1649322Y1589522D03*
Y1609607D03*
X1657983Y1609207D03*
X1649322Y1598984D03*
X1657983Y1598584D03*
Y1603315D03*
X1649322Y1604876D03*
Y1614338D03*
X1657983Y1613938D03*
Y1618669D03*
X1652000Y1644980D03*
X1669319Y3001D03*
X1676870Y55513D03*
X1673095Y68581D03*
X1679470Y60513D03*
X1662442Y84140D03*
Y76140D03*
Y80140D03*
X1673108Y80581D03*
X1665190Y76587D03*
Y72615D03*
X1679598Y85731D03*
X1677213Y91951D03*
X1677238Y88801D03*
X1675291Y103621D03*
X1666629Y100625D03*
X1675817Y117261D03*
X1664887Y117557D03*
X1667811Y103621D03*
X1671002Y112083D03*
X1662391Y118335D03*
Y121735D03*
X1664887Y122513D03*
Y131731D03*
X1662391Y132509D03*
Y135909D03*
X1662986Y146461D03*
X1664887Y136687D03*
X1667208Y141247D03*
X1671695Y143518D03*
X1670795Y152373D03*
X1661888Y152367D03*
X1673945Y152562D03*
X1663588Y180572D03*
X1668271Y180527D03*
X1674637Y183834D03*
X1669352Y171523D03*
X1674810Y172665D03*
X1674747Y178560D03*
X1671994Y192421D03*
X1663588Y185165D03*
X1668226Y185121D03*
X1675623Y186629D03*
X1674157Y190185D03*
X1668882Y192490D03*
X1667318Y198828D03*
X1674927Y200864D03*
X1664840Y192300D03*
X1662837Y206767D03*
X1667837D03*
X1665337D03*
X1674950Y207037D03*
X1675016Y212455D03*
X1667967Y221708D03*
X1665467D03*
X1664082Y231021D03*
Y228221D03*
X1672317Y221642D03*
X1662967Y221708D03*
X1662382Y224421D03*
X1669633Y236189D03*
X1667133D03*
X1664633D03*
X1667074Y248765D03*
X1664574D03*
X1669574D03*
X1661780Y279208D03*
X1665884Y281307D03*
X1676231Y265897D03*
X1673731D03*
X1670071Y268195D03*
Y270695D03*
X1667271Y268195D03*
X1664771D03*
Y270695D03*
X1667271D03*
X1670374Y290845D03*
Y288345D03*
X1667874Y290845D03*
Y288345D03*
X1670374Y293645D03*
X1667874D03*
X1674226Y324139D03*
X1673203Y328867D03*
Y332017D03*
X1668979Y339559D03*
X1666860Y353661D03*
X1663650Y353283D03*
X1673723Y353881D03*
X1670323Y353534D03*
X1670260Y377912D03*
X1669260Y391496D03*
X1663618Y393858D03*
X1663780Y384410D03*
X1666959Y382047D03*
X1670260Y386500D03*
X1663760Y410394D03*
Y403307D03*
X1669260Y409000D03*
X1665260Y398583D03*
X1670348Y397912D03*
X1667260Y403500D03*
X1663713Y440869D03*
Y438269D03*
X1666513Y433069D03*
Y430469D03*
Y435669D03*
Y440869D03*
Y438269D03*
X1663713Y433069D03*
Y430469D03*
Y435669D03*
X1663576Y458406D03*
X1669767Y445908D03*
X1673717Y445787D03*
X1664567Y451677D03*
X1667067D03*
X1664567Y454177D03*
X1667067D03*
X1663576Y465492D03*
Y472579D03*
X1666271Y460218D03*
Y463618D03*
X1663576Y479665D03*
Y486752D03*
Y493839D03*
Y523799D03*
Y516713D03*
Y509626D03*
Y537973D03*
Y530886D03*
Y559665D03*
Y566752D03*
Y580925D03*
Y588012D03*
Y573839D03*
Y602185D03*
Y595099D03*
Y616358D03*
Y609272D03*
X1666645Y1465913D03*
Y1456451D03*
Y1461182D03*
X1675306Y1465513D03*
Y1460782D03*
X1666645Y1471805D03*
Y1476536D03*
Y1481267D03*
X1675306Y1476136D03*
Y1470244D03*
Y1480867D03*
X1666645Y1487159D03*
Y1491890D03*
Y1496621D03*
X1675306Y1491490D03*
Y1485598D03*
Y1496221D03*
Y1511576D03*
X1666645Y1511976D03*
Y1507245D03*
Y1502514D03*
X1675306Y1506845D03*
Y1500952D03*
Y1516307D03*
X1666645Y1558813D03*
Y1563544D03*
X1675306Y1563144D03*
Y1578498D03*
Y1572606D03*
X1666645Y1568275D03*
X1675306Y1567875D03*
X1666645Y1574167D03*
Y1578898D03*
Y1583629D03*
X1675306Y1583229D03*
X1666645Y1589522D03*
Y1594253D03*
X1675306Y1593853D03*
Y1587960D03*
X1666645Y1604876D03*
Y1598984D03*
X1675306Y1609207D03*
Y1598584D03*
Y1603315D03*
X1666645Y1609607D03*
Y1614338D03*
X1675306Y1613938D03*
Y1618669D03*
X1672000Y1644980D03*
X1689319Y3001D03*
X1685184Y60922D03*
X1680020Y55513D03*
X1682330Y60438D03*
X1688011Y86012D03*
X1695566Y102249D03*
X1688011Y94374D03*
X1683152Y86046D03*
X1680155Y94351D03*
X1684104Y94279D03*
X1683348Y113394D03*
X1685997Y110784D03*
X1687566Y102249D03*
X1691566D03*
X1683348Y116594D03*
X1694291Y110784D03*
X1689291D03*
X1686171Y130898D03*
X1693591Y133298D03*
X1683348Y119594D03*
X1683782Y124283D03*
X1693870Y124663D03*
X1688848Y124879D03*
X1687738Y134579D03*
X1695214Y138838D03*
X1682189Y161306D03*
X1679440Y157370D03*
X1683524Y172665D03*
Y180665D03*
Y168665D03*
Y176665D03*
X1691366Y195176D03*
X1688866D03*
X1693485Y198883D03*
X1683524Y192665D03*
X1683637Y186778D03*
X1683556Y200864D03*
Y212864D03*
X1691226Y203393D03*
X1693485Y201683D03*
X1688726Y203393D03*
X1683556Y204864D03*
Y208864D03*
Y221864D03*
Y216864D03*
X1688605Y218085D03*
X1691405D03*
X1679197Y219379D03*
X1679825Y228631D03*
X1693932Y249108D03*
X1685313Y252371D03*
Y248371D03*
X1686339Y314890D03*
X1686115Y311740D03*
X1681273Y316731D03*
X1691117Y321649D03*
X1683523Y324518D03*
X1677810Y324466D03*
X1687164Y336324D03*
X1678072Y342319D03*
X1686408Y332584D03*
X1691743Y353506D03*
X1687424Y347937D03*
X1692676Y348015D03*
X1688593Y353470D03*
X1691182Y357016D03*
X1680518Y377912D03*
Y385912D03*
Y393924D03*
Y389912D03*
Y381912D03*
Y409924D03*
Y405924D03*
Y401924D03*
Y397912D03*
X1677933Y418838D03*
X1689757Y466528D03*
Y471484D03*
X1692253Y467306D03*
Y470706D03*
X1689757Y480701D03*
Y485657D03*
X1692253Y484879D03*
Y481479D03*
Y511439D03*
X1689757Y515617D03*
Y510661D03*
X1692253Y514839D03*
Y529013D03*
Y525613D03*
X1689757Y524835D03*
Y529791D03*
X1689920Y539315D03*
X1689236Y550137D03*
X1692028D03*
X1692253Y561479D03*
X1689757Y565657D03*
Y560701D03*
X1692253Y564879D03*
Y575652D03*
X1689757Y589047D03*
Y574874D03*
Y579830D03*
X1692253Y579052D03*
Y593225D03*
Y603999D03*
X1689757Y603221D03*
Y594003D03*
X1692253Y589825D03*
Y607399D03*
X1689757Y608177D03*
X1693000Y626912D03*
X1692379Y622912D03*
X1683968Y1465913D03*
Y1456451D03*
Y1461182D03*
X1692629Y1465513D03*
Y1460782D03*
X1683968Y1471805D03*
Y1476536D03*
Y1481267D03*
X1692629Y1476136D03*
Y1470244D03*
Y1480867D03*
X1683968Y1487159D03*
Y1491890D03*
Y1496621D03*
X1692629Y1491490D03*
Y1485598D03*
Y1496221D03*
X1683968Y1502514D03*
Y1511976D03*
X1692629Y1506845D03*
Y1500952D03*
Y1511576D03*
X1683968Y1507245D03*
X1692629Y1516307D03*
X1683968Y1558813D03*
Y1563544D03*
X1692629Y1563144D03*
Y1572606D03*
X1683968Y1568275D03*
Y1574167D03*
Y1578898D03*
X1692629Y1567875D03*
Y1578498D03*
X1683968Y1583629D03*
Y1589522D03*
Y1594253D03*
X1692629Y1583229D03*
Y1593853D03*
Y1587960D03*
X1683968Y1598984D03*
X1692629Y1609207D03*
Y1598584D03*
Y1603315D03*
X1683968Y1609607D03*
Y1604876D03*
Y1614338D03*
X1692629Y1613938D03*
Y1618669D03*
X1692000Y1644980D03*
X1705303Y4470D03*
X1706664Y24774D03*
Y44774D03*
X1704934Y97667D03*
X1709184Y95111D03*
X1698583Y109172D03*
X1701583D03*
X1700590Y106495D03*
X1709134Y116497D03*
X1704334D03*
X1695317Y116594D03*
X1700590Y102495D03*
X1709134Y123584D03*
Y130670D03*
X1704334Y123584D03*
Y130670D03*
X1695317Y119594D03*
X1706734Y118342D03*
Y132515D03*
Y121742D03*
X1698851Y125107D03*
X1700324Y146012D03*
X1702230Y141228D03*
X1709134Y137757D03*
X1704334D03*
X1706734Y135915D03*
X1700324Y142862D03*
X1707465Y143762D03*
X1701365Y148717D03*
X1705118Y150847D03*
X1696666Y195176D03*
X1693866D03*
X1708913D03*
X1710931Y199248D03*
X1706413Y195176D03*
X1703913D03*
X1707931Y199248D03*
X1697414Y206838D03*
X1694914D03*
X1707931Y201748D03*
X1706494Y210509D03*
X1703994D03*
X1705767Y206806D03*
X1708267D03*
X1697984Y226320D03*
X1695205Y216385D03*
X1697918Y216970D03*
Y219470D03*
Y221970D03*
X1705686Y230556D03*
X1709941Y228747D03*
X1700945Y228646D03*
X1707086Y247292D03*
X1699876Y236121D03*
X1696910Y238589D03*
X1706312Y238689D03*
X1704671Y242078D03*
X1699902Y232971D03*
X1696552Y244571D03*
X1699795Y253198D03*
X1703895Y256394D03*
X1701495Y289735D03*
X1700223Y292141D03*
X1703609Y287320D03*
X1695142Y303839D03*
X1698292Y303962D03*
X1694749Y466528D03*
Y471484D03*
X1700159Y473640D03*
X1705151D03*
X1702655Y474418D03*
Y477818D03*
X1705151Y487813D03*
X1700159D03*
X1705151Y478596D03*
X1694749Y480701D03*
X1700159Y478596D03*
X1694749Y485657D03*
X1702655Y488591D03*
Y491991D03*
X1700159Y492769D03*
X1705151D03*
Y517774D03*
Y522730D03*
X1694749Y510661D03*
Y515617D03*
X1700159Y517774D03*
Y522730D03*
X1702655Y521952D03*
Y518552D03*
Y536125D03*
X1700159Y536903D03*
X1705151D03*
Y531947D03*
X1694749Y524835D03*
Y529791D03*
X1700159Y531947D03*
X1702655Y532725D03*
X1698716Y550065D03*
X1705151Y572769D03*
X1700159D03*
X1705151Y567813D03*
X1698839Y564843D03*
X1700159Y567813D03*
X1694749Y565657D03*
Y560701D03*
X1702655Y571991D03*
Y568591D03*
X1694749Y579830D03*
X1705151Y586943D03*
Y581987D03*
X1694749Y589047D03*
X1700159Y586943D03*
Y581987D03*
X1694749Y574874D03*
X1702655Y586165D03*
Y582765D03*
Y600338D03*
X1694749Y603221D03*
X1700159Y601116D03*
X1705151D03*
Y596160D03*
X1700159D03*
X1694749Y594003D03*
X1702655Y596938D03*
Y611111D03*
X1705151Y615289D03*
X1700159Y610333D03*
X1694749Y608177D03*
X1700159Y615289D03*
X1705151Y610333D03*
X1702655Y614511D03*
X1708015Y1142700D03*
X1711333Y1146609D03*
X1706450Y1173065D03*
X1708889Y1189221D03*
X1703400Y1174400D03*
X1701290Y1465913D03*
Y1456451D03*
Y1461182D03*
Y1471805D03*
Y1476536D03*
Y1481267D03*
Y1487159D03*
Y1491890D03*
Y1496621D03*
Y1507245D03*
Y1502514D03*
Y1511976D03*
Y1558813D03*
Y1563544D03*
Y1568275D03*
Y1574167D03*
Y1578898D03*
Y1583629D03*
Y1589522D03*
Y1594253D03*
Y1609607D03*
Y1604876D03*
Y1598984D03*
Y1614338D03*
X1713985Y53598D03*
X1724796Y82984D03*
Y77784D03*
Y80384D03*
Y75184D03*
Y85584D03*
X1713394Y103411D03*
X1713788Y97667D03*
X1724584Y90650D03*
X1724334Y95236D03*
X1716334Y116496D03*
Y109410D03*
Y102323D03*
X1711634Y116497D03*
Y109410D03*
X1724334Y102323D03*
X1724586Y109410D03*
Y116496D03*
X1714034Y111255D03*
Y114655D03*
X1713553Y106561D03*
X1724758Y124576D03*
X1725811Y130670D03*
X1716334D03*
Y123583D03*
X1711634D03*
Y130670D03*
X1714034Y125428D03*
Y128828D03*
X1725806Y137756D03*
X1716334D03*
X1711413Y195176D03*
X1712866Y213539D03*
X1710931Y202048D03*
X1714531Y230117D03*
X1714547Y238714D03*
X1710547D03*
X1710028Y246874D03*
X1712248Y244297D03*
X1715705Y328692D03*
X1716755Y326179D03*
X1712734Y340534D03*
X1712226Y344028D03*
X1715930Y340969D03*
X1715590Y331719D03*
X1725746Y377173D03*
X1723964Y370935D03*
X1721746Y377173D03*
X1715228Y387966D03*
X1718851Y391533D03*
X1720571Y385644D03*
X1725746Y385123D03*
X1718318Y399918D03*
X1725154Y406060D03*
X1725415Y416289D03*
Y418889D03*
Y421489D03*
X1721423Y412106D03*
X1718710Y447486D03*
X1716310Y458334D03*
Y454334D03*
X1724627Y459330D03*
X1724580Y454214D03*
X1724923Y449045D03*
X1724930Y473571D03*
Y491118D03*
Y488618D03*
Y476071D03*
Y478571D03*
Y481071D03*
Y493618D03*
Y496118D03*
X1710174Y553101D03*
X1717626Y1134729D03*
X1710511Y1138130D03*
X1721008Y1134729D03*
X1723805Y1142666D03*
X1725008Y1134636D03*
X1720960Y1148000D03*
X1725680Y1157544D03*
X1723796Y1160168D03*
X1724191Y1167768D03*
X1713239Y1176038D03*
X1712526Y1171950D03*
X1728343Y1185205D03*
X1719692Y1187215D03*
X1719385Y1180175D03*
X1712715Y1188500D03*
X1725660Y1193019D03*
X1721660D03*
X1711783Y1193848D03*
X1721662Y1201043D03*
X1725658D03*
X1718625Y1199814D03*
X1712542Y1196600D03*
X1720536Y1217228D03*
X1723200Y1219895D03*
X1710825Y1231688D03*
X1712966Y1229841D03*
X1709952Y1465513D03*
Y1460782D03*
X1718613Y1465914D03*
Y1456452D03*
Y1461183D03*
Y1476537D03*
Y1471806D03*
Y1481268D03*
X1709952Y1476136D03*
Y1470244D03*
Y1480867D03*
Y1491490D03*
Y1485598D03*
Y1496221D03*
X1718613Y1491891D03*
Y1487160D03*
Y1496622D03*
Y1502515D03*
Y1511977D03*
X1709952Y1506845D03*
Y1500952D03*
Y1511576D03*
X1718613Y1507246D03*
X1709952Y1516307D03*
Y1563144D03*
X1718613Y1563544D03*
Y1558813D03*
X1709952Y1567875D03*
X1718613Y1568275D03*
X1709952Y1578498D03*
Y1572606D03*
X1718613Y1578898D03*
Y1574167D03*
Y1589522D03*
X1709952Y1583229D03*
X1718613Y1583629D03*
X1709952Y1593853D03*
Y1587960D03*
X1718613Y1594253D03*
Y1609607D03*
Y1598984D03*
Y1604876D03*
X1709952Y1609207D03*
Y1598584D03*
Y1603315D03*
Y1618669D03*
X1718613Y1614338D03*
X1709952Y1613938D03*
X1712000Y1644980D03*
X1742336Y-87777D03*
X1739311Y-86371D03*
X1733909Y-83456D03*
Y-78500D03*
X1742336Y-74565D03*
Y-64265D03*
X1739311Y-65585D03*
Y-75885D03*
X1733909Y-68500D03*
Y-73456D03*
X1736405Y-69278D03*
Y-72678D03*
X1733985Y53598D03*
X1727350Y92849D03*
X1743175Y92874D03*
X1729896Y90615D03*
X1734267Y95236D03*
X1734217Y99961D03*
X1734310Y103037D03*
X1734444Y116496D03*
Y109410D03*
Y130670D03*
Y123583D03*
X1730647Y137756D03*
X1742224Y162368D03*
X1733079Y207978D03*
Y210478D03*
Y215478D03*
Y212978D03*
Y223726D03*
Y226226D03*
Y231226D03*
Y228726D03*
X1743535Y223661D03*
X1736408Y264180D03*
X1738908D03*
X1736333Y258880D03*
X1739125Y293796D03*
X1736625D03*
X1734826Y376499D03*
X1744524Y379429D03*
X1741746Y377173D03*
X1737786D03*
X1729751D03*
X1733027Y392228D03*
X1728433Y392183D03*
X1733746Y385123D03*
X1730746D03*
X1737746D03*
X1741420Y391569D03*
X1739847Y409016D03*
X1735811Y409032D03*
X1732494Y402867D03*
X1728478Y396866D03*
X1733071D03*
X1739847Y401066D03*
X1729508Y403300D03*
X1728915Y405889D03*
Y408489D03*
Y413689D03*
Y411089D03*
Y416289D03*
Y421489D03*
Y418889D03*
Y424089D03*
X1729302Y439718D03*
Y442518D03*
Y432718D03*
Y435518D03*
X1739179Y439318D03*
X1728915Y426689D03*
X1739179Y442118D03*
Y449118D03*
Y446318D03*
X1738824Y452740D03*
X1736214Y450091D03*
X1733014D03*
X1730014D03*
X1727404Y447209D03*
X1730404D03*
X1738824Y456034D03*
Y461034D03*
X1737703Y472189D03*
X1740542Y468088D03*
Y465288D03*
X1733014Y462060D03*
X1730014D03*
X1736592Y487570D03*
Y490070D03*
X1734952Y479217D03*
X1737646Y477213D03*
Y479713D03*
X1729002Y477053D03*
X1731502D03*
X1734952Y476717D03*
X1728038Y491870D03*
X1730538D03*
X1733147Y493758D03*
Y496258D03*
X1741800Y917900D03*
X1742029Y1116251D03*
X1730675Y1132361D03*
X1726963Y1132319D03*
X1739508Y1137129D03*
X1729008Y1134729D03*
X1732881D03*
X1739917Y1146937D03*
Y1150087D03*
X1732137Y1157404D03*
X1729207Y1159455D03*
X1737393Y1162817D03*
Y1170767D03*
X1729210Y1167768D03*
X1728333Y1178240D03*
X1733052Y1187310D03*
X1737689Y1185238D03*
X1737482Y1180235D03*
X1733660Y1193019D03*
X1729660D03*
X1737660D03*
X1733662Y1201039D03*
X1729628Y1201043D03*
X1737662Y1200969D03*
X1733695Y1212164D03*
X1735989Y1214458D03*
X1731619Y1210089D03*
X1740785Y1219254D03*
X1737781Y1208993D03*
X1726475Y1223170D03*
X1731533Y1228226D03*
X1729322Y1226016D03*
X1732000Y1644980D03*
X1742351Y-77080D03*
X1745592Y-79984D03*
X1745604Y-77094D03*
X1745589Y-87777D03*
X1742351Y-85262D03*
X1745604D03*
X1745592Y-82584D03*
Y-71970D03*
X1745589Y-74579D03*
Y-64265D03*
X1745592Y-69470D03*
X1742351Y-66780D03*
X1745604D03*
X1752778Y5374D03*
X1752091Y24773D03*
Y44773D03*
X1743131Y85539D03*
Y82939D03*
Y75139D03*
Y80339D03*
Y77739D03*
X1755727Y94017D03*
X1751456Y101701D03*
X1747727Y94017D03*
X1751727D03*
X1751456Y98551D03*
X1754351Y111223D03*
X1742444Y102323D03*
Y116496D03*
Y109410D03*
X1751855Y110445D03*
Y115401D03*
X1756847D03*
Y110445D03*
X1754351Y114623D03*
X1755006Y103783D03*
X1745202Y104249D03*
Y107649D03*
X1754351Y128796D03*
Y125396D03*
X1742444Y130670D03*
Y123583D03*
X1751855Y129574D03*
Y124618D03*
X1756847D03*
Y129574D03*
X1742444Y137756D03*
X1744824Y162368D03*
X1751924Y162793D03*
Y165393D03*
Y167993D03*
Y170493D03*
X1758848Y177616D03*
X1759429Y172190D03*
X1756927Y181009D03*
X1750921Y181426D03*
X1754132Y181366D03*
X1753418Y191941D03*
X1753285Y188727D03*
X1751129Y184221D03*
X1753746Y184012D03*
X1747607Y211695D03*
X1755165Y211359D03*
Y213859D03*
X1750107Y211695D03*
X1747607Y208695D03*
X1750407D03*
X1743535Y208213D03*
Y213213D03*
Y210713D03*
Y226461D03*
X1747242Y226141D03*
X1755197Y224712D03*
X1743535Y228961D03*
Y231461D03*
X1751504Y229286D03*
X1755197Y222212D03*
X1750042Y226141D03*
X1743535Y215713D03*
X1752485Y236611D03*
X1749985D03*
X1751504Y231786D03*
X1747485Y236611D03*
X1747187Y248891D03*
X1749687D03*
X1752187D03*
X1755112Y256535D03*
X1753784Y265701D03*
X1758871Y265896D03*
X1750602Y267526D03*
X1745302D03*
X1748102D03*
X1745302Y270026D03*
X1748102D03*
X1750602D03*
X1755419Y281716D03*
X1749939Y288190D03*
X1747139D03*
X1744639D03*
X1749939Y285690D03*
X1744639D03*
X1747139D03*
X1758165Y290755D03*
X1754165D03*
X1744524Y370010D03*
X1756497Y370976D03*
X1748497Y371060D03*
X1752497Y371076D03*
X1750135Y379088D03*
X1755433Y379028D03*
X1747561Y385161D03*
X1744180Y383966D03*
X1748252Y395248D03*
X1750187Y409539D03*
X1753187D03*
X1750187Y406739D03*
X1753187Y407039D03*
X1752851Y401981D03*
X1755351D03*
X1757124Y398278D03*
X1754624D03*
X1749470Y424067D03*
X1751970D03*
X1756970D03*
X1754470D03*
X1749705Y413611D03*
X1752205D03*
X1757205D03*
X1754705D03*
X1756844Y438293D03*
X1747179Y439318D03*
X1756844Y441093D03*
X1747179Y442118D03*
X1756844Y450041D03*
Y452841D03*
Y455641D03*
X1747179Y449118D03*
Y446318D03*
X1747359Y454309D03*
Y458309D03*
X1756844Y443893D03*
X1747359Y462309D03*
X1747306Y470001D03*
X1744806D03*
X1756894Y472020D03*
X1756553Y466409D03*
X1756954Y477318D03*
X1745231Y489036D03*
X1743092Y485580D03*
X1745592D03*
X1748092D03*
X1758401Y484882D03*
X1756391Y487382D03*
X1747467Y492836D03*
Y495636D03*
X1753474Y542699D03*
X1756089Y542952D03*
X1750879Y541940D03*
X1757402Y825111D03*
Y820155D03*
X1754906Y824333D03*
Y820737D03*
X1746897Y879199D03*
X1746884Y884649D03*
X1744937Y912517D03*
X1747937D03*
X1750751Y910785D03*
X1747900Y900160D03*
X1744900D03*
X1750915Y902055D03*
X1749267Y918413D03*
X1751200Y931100D03*
X1746600Y935100D03*
X1748081Y984379D03*
X1751854Y991297D03*
X1749314Y987904D03*
X1745824Y987058D03*
X1748677Y993986D03*
X1756192Y996132D03*
X1753860Y997271D03*
X1759569Y1021944D03*
X1743224Y1119055D03*
X1744529Y1116251D03*
X1758390Y1577905D03*
X1758583Y1581027D03*
X1759947Y1599029D03*
X1750685Y1618504D03*
Y1621654D03*
X1756422Y1640303D03*
X1752000Y1644980D03*
X1765559Y3001D03*
X1764804Y84140D03*
Y76140D03*
Y80140D03*
X1767552Y76587D03*
Y72615D03*
X1759736Y94017D03*
X1762010Y97475D03*
X1768991Y100625D03*
X1767249Y117557D03*
X1770173Y103621D03*
X1759006Y103783D03*
X1762257Y117557D03*
X1761941Y106186D03*
X1773364Y112083D03*
X1764753Y121735D03*
X1762257Y122513D03*
Y131731D03*
X1767249Y122513D03*
Y131731D03*
X1764753Y118335D03*
Y132509D03*
Y135909D03*
X1762257Y136687D03*
X1767249D03*
X1765950Y180572D03*
X1770633Y180527D03*
X1771714Y171523D03*
X1776999Y183834D03*
X1762102Y168697D03*
X1774356Y192421D03*
X1759918Y184619D03*
X1770588Y185121D03*
X1765950Y185165D03*
X1763190Y191941D03*
X1771244Y192490D03*
X1776519Y190185D03*
X1767202Y192300D03*
X1761898Y206760D03*
X1765199Y206767D03*
X1770199D03*
X1767699D03*
X1758868Y213132D03*
X1765329Y221708D03*
X1770329D03*
X1767829D03*
X1764744Y224421D03*
X1766444Y231021D03*
Y228221D03*
X1774679Y221642D03*
X1758868Y215632D03*
X1771995Y236189D03*
X1769495D03*
X1766995D03*
X1763112Y256535D03*
X1771936Y248765D03*
X1769436D03*
X1766936D03*
X1759112Y256303D03*
X1763887Y266114D03*
X1764142Y279208D03*
X1768246Y281307D03*
X1767133Y270695D03*
X1769633D03*
X1772433Y268195D03*
Y270695D03*
X1769633Y268195D03*
X1767133D03*
X1761360Y281982D03*
X1772736Y293645D03*
X1770236D03*
Y290845D03*
Y288345D03*
X1772736Y290845D03*
Y288345D03*
X1762165Y290755D03*
X1760497Y371070D03*
X1765497Y370899D03*
X1762997Y377581D03*
X1765497Y379591D03*
X1772513Y387702D03*
X1769713D03*
X1765913Y389402D03*
X1763200Y388817D03*
Y383817D03*
Y386317D03*
X1766204Y398949D03*
X1770778Y402642D03*
X1773278D03*
X1767633Y409904D03*
Y407104D03*
X1763704Y401949D03*
X1767953Y413611D03*
X1770453D03*
X1772953D03*
X1772893Y423944D03*
X1770393D03*
X1767893D03*
X1765093D03*
X1765153Y413611D03*
X1766837Y438293D03*
Y441093D03*
Y450041D03*
Y452841D03*
Y455641D03*
Y443893D03*
X1765097Y466409D03*
X1768586Y467560D03*
X1764903Y470382D03*
X1764906Y474382D03*
X1776561Y467560D03*
X1777061Y475560D03*
X1765083Y487382D03*
X1764912Y482382D03*
X1768575Y479560D03*
X1765006Y478382D03*
X1768575Y475560D03*
X1770135Y490711D03*
X1758957Y543036D03*
X1761953Y706827D03*
X1772768Y818696D03*
X1761953Y865160D03*
X1773600Y888100D03*
X1773614Y895275D03*
X1773600Y902800D03*
X1770680Y926322D03*
X1763818Y926241D03*
X1773789Y927663D03*
X1765664Y923724D03*
X1769064D03*
X1773789Y930663D03*
X1772599Y993053D03*
X1762898Y992883D03*
X1774476Y995049D03*
X1773810Y990821D03*
X1762486Y990260D03*
X1760201Y992475D03*
X1758881Y995633D03*
X1769004Y1019395D03*
X1768844Y1023694D03*
Y1027248D03*
X1771773Y1028829D03*
X1764744Y1101930D03*
Y1097879D03*
X1766899Y1121122D03*
X1769499D03*
X1772099D03*
X1774799D03*
X1766999Y1130822D03*
X1772199D03*
X1769599D03*
X1772188Y1428369D03*
X1774339Y1437975D03*
X1774216Y1470165D03*
X1765294Y1575434D03*
X1766313Y1580198D03*
X1759092Y1588137D03*
X1767142Y1588219D03*
X1761072Y1590719D03*
X1765040Y1599511D03*
X1764422Y1640303D03*
X1760422D03*
X1768422D03*
X1772422D03*
X1762041Y1631511D03*
X1768422Y1632245D03*
X1773820Y1631238D03*
X1772000Y1644980D03*
X1788884Y59871D03*
X1782382Y55513D03*
X1779232D03*
X1775457Y68581D03*
X1785246Y60660D03*
X1781832Y60513D03*
X1775470Y80581D03*
X1781960Y85731D03*
X1790712Y81713D03*
X1790664Y71908D03*
X1779575Y91951D03*
X1779600Y88801D03*
X1790373Y94663D03*
X1786466Y85923D03*
Y94279D03*
X1782517Y94351D03*
X1778179Y117261D03*
X1777653Y103621D03*
X1785886Y172665D03*
Y180665D03*
Y168665D03*
Y176665D03*
X1777172Y172665D03*
X1777109Y178560D03*
X1777985Y186629D03*
X1785779Y192665D03*
X1785886Y196665D03*
X1777289Y200864D03*
X1785999Y186778D03*
X1785918Y200864D03*
Y212864D03*
Y204864D03*
X1777378Y212455D03*
X1777312Y207037D03*
X1785918Y208864D03*
Y216864D03*
Y221864D03*
X1781559Y219379D03*
X1782187Y228631D03*
X1778593Y265897D03*
X1776093D03*
X1790533Y303750D03*
X1787674Y303130D03*
X1777681Y387151D03*
Y382151D03*
Y384651D03*
X1790136Y399161D03*
Y401661D03*
Y396661D03*
X1778103Y399161D03*
Y401661D03*
Y396661D03*
X1783028Y408240D03*
X1785528D03*
X1780528D03*
X1783107Y424240D03*
X1780646Y420393D03*
X1785646D03*
X1783146D03*
X1783107Y426740D03*
X1786184Y435321D03*
Y438121D03*
X1783384Y435321D03*
Y438121D03*
X1786184Y440921D03*
X1783384D03*
X1786713Y455039D03*
X1786184Y443721D03*
X1783384D03*
X1786170Y448931D03*
X1792527Y452799D03*
X1790014Y468607D03*
X1783014Y474513D03*
X1786693Y459170D03*
X1790061Y474513D03*
X1784602Y564092D03*
X1779404Y826570D03*
X1791041Y818795D03*
X1778801Y836469D03*
X1782600Y874500D03*
X1780016Y874400D03*
X1788400Y888100D03*
X1781000Y888087D03*
X1788396Y895066D03*
X1788300Y902800D03*
X1780665Y902796D03*
X1786256Y927626D03*
X1784306Y924601D03*
X1775904Y924546D03*
X1778047Y916120D03*
X1786256Y930626D03*
X1789537Y930498D03*
X1781263Y964660D03*
X1780158Y953295D03*
X1785758Y956095D03*
Y953295D03*
X1782958D03*
Y956095D03*
X1780158D03*
X1784763Y964660D03*
X1789363Y969160D03*
X1782563Y979660D03*
X1785663D03*
X1779363D03*
X1786863Y985060D03*
X1779143Y995203D03*
X1779033Y1023432D03*
X1786740Y1019237D03*
X1780802Y1019474D03*
X1774863Y1019237D03*
X1774844Y1023694D03*
X1783844D03*
X1786844Y1027248D03*
X1780844D03*
X1774844D03*
X1789844Y1023694D03*
X1775998Y1074707D03*
Y1072207D03*
X1781198Y1074707D03*
X1778598D03*
X1783798D03*
Y1072207D03*
X1778598D03*
X1781198D03*
X1790736Y1072090D03*
Y1074590D03*
X1780326Y1089851D03*
X1777726D03*
X1782926D03*
Y1092351D03*
X1777726D03*
X1780326D03*
X1775126Y1089851D03*
Y1092351D03*
X1790639Y1082585D03*
X1790572Y1085152D03*
X1780662Y1108413D03*
X1783262D03*
X1778062D03*
X1775462D03*
X1785321Y1121122D03*
X1787921D03*
X1790521D03*
X1780566Y1111038D03*
X1783166D03*
X1777966D03*
X1775366D03*
X1774899Y1130822D03*
Y1139822D03*
X1777399D03*
X1790521Y1130822D03*
X1781874Y1139822D03*
X1787921Y1130822D03*
X1785321D03*
X1784374Y1139822D03*
X1777399Y1147822D03*
X1774899D03*
X1781802D03*
X1784302D03*
X1783278Y1208140D03*
X1779581Y1222200D03*
Y1219400D03*
Y1216600D03*
Y1213800D03*
X1782581Y1222200D03*
Y1219400D03*
Y1216600D03*
Y1213800D03*
X1780397Y1237469D03*
Y1230569D03*
Y1228069D03*
X1779581Y1225000D03*
X1782581D03*
X1785961Y1224892D03*
X1780397Y1234969D03*
Y1241869D03*
Y1244369D03*
Y1248769D03*
Y1251269D03*
X1791099Y1260421D03*
X1779868Y1446668D03*
X1778227Y1438099D03*
X1786091Y1443715D03*
X1787745Y1437765D03*
X1783178Y1437550D03*
X1786564Y1478858D03*
X1778104Y1470289D03*
X1777131Y1604357D03*
X1776422Y1640303D03*
X1804667Y-47581D03*
X1799265Y-44666D03*
X1804667Y-37095D03*
X1799265Y-39710D03*
Y-29710D03*
Y-34666D03*
X1801761Y-33888D03*
Y-30488D03*
X1804667Y-26795D03*
X1791570Y74535D03*
X1791088Y77296D03*
X1804758Y294429D03*
X1804993Y297591D03*
X1793524Y303343D03*
X1805196Y300952D03*
X1799897Y408104D03*
X1802697D03*
X1805497D03*
X1793475Y424939D03*
X1799614Y420375D03*
X1802414D03*
X1805214D03*
X1804984Y433975D03*
X1803570Y436164D03*
X1793475Y427439D03*
X1809095Y435101D03*
X1803700Y440101D03*
X1803530Y431112D03*
X1809358Y442114D03*
X1803335Y452718D03*
X1809346Y452601D03*
X1797907Y452987D03*
X1809338Y447121D03*
X1804933Y461607D03*
X1796933D03*
X1796136Y471334D03*
X1800933Y461607D03*
X1793149Y662810D03*
X1798705Y718793D03*
X1791302Y829031D03*
X1802000Y892447D03*
X1797365Y930761D03*
X1793474Y930374D03*
X1794163Y968760D03*
X1797963D03*
X1792263Y962960D03*
X1805463Y969260D03*
X1801963Y969160D03*
X1798163Y982360D03*
X1793563D03*
X1805863Y980760D03*
X1802363Y989660D03*
X1803351Y1027471D03*
X1805188Y1019078D03*
X1799646Y1018999D03*
X1793470Y1018762D03*
X1801844Y1023694D03*
X1795844D03*
X1798844Y1027248D03*
X1792844D03*
X1795936Y1072090D03*
X1793336D03*
X1798536D03*
Y1074590D03*
X1793336D03*
X1795936D03*
X1805013Y1091877D03*
X1801961Y1081717D03*
X1795819Y1088553D03*
X1792847Y1099210D03*
X1799012Y1095893D03*
X1805013Y1096470D03*
X1792863Y1103246D03*
X1800813D03*
X1806206Y1114589D03*
X1803506D03*
X1800906D03*
X1798306D03*
X1798702Y1124328D03*
X1801302D03*
X1803902D03*
X1806602D03*
X1793221Y1121122D03*
Y1130822D03*
X1804532Y1133356D03*
X1807232D03*
X1807035Y1136912D03*
Y1144912D03*
X1796607Y1200108D03*
X1801285Y1213373D03*
X1801147Y1208555D03*
X1806835Y1214668D03*
X1800489Y1220598D03*
X1807243Y1219955D03*
X1802670Y1210905D03*
X1802844Y1227695D03*
X1805126Y1225745D03*
X1799845Y1261044D03*
X1794845D03*
X1797345D03*
X1799845Y1263544D03*
X1797345D03*
X1794845D03*
X1793976Y1440762D03*
X1803885Y1435046D03*
X1806428Y1444543D03*
X1795374D03*
X1802813Y1464015D03*
X1807270Y1468535D03*
X1793879Y1472952D03*
X1803762Y1467236D03*
X1792000Y1644980D03*
X1807692Y-49001D03*
X1810945Y-48987D03*
X1807707Y-46486D03*
X1810960Y-46472D03*
X1810948Y-33180D03*
X1807692Y-35775D03*
X1810945Y-35789D03*
X1810948Y-30680D03*
X1807707Y-38290D03*
X1810948Y-41194D03*
X1810960Y-38304D03*
X1810948Y-43794D03*
X1807692Y-25475D03*
X1810945D03*
X1807707Y-27990D03*
X1810960D03*
X1822983Y346053D03*
Y366053D03*
Y386053D03*
Y406053D03*
Y426053D03*
Y446053D03*
X1817439Y447101D03*
X1822983Y466053D03*
Y486053D03*
Y506053D03*
Y526053D03*
Y546053D03*
Y566053D03*
Y586053D03*
Y606053D03*
Y626053D03*
Y646053D03*
Y666053D03*
Y686053D03*
Y706053D03*
Y726053D03*
Y746053D03*
Y766053D03*
Y786053D03*
Y806053D03*
Y826053D03*
Y846053D03*
Y866053D03*
Y886053D03*
Y906053D03*
X1819900Y906900D03*
X1822983Y926053D03*
Y946053D03*
X1816322Y977215D03*
X1807663Y966660D03*
Y963860D03*
X1823074Y992833D03*
X1808014Y984832D03*
X1812538Y1026859D03*
X1811468Y1021084D03*
X1807844Y1023694D03*
Y1027248D03*
X1810349Y1031264D03*
X1812296Y1075688D03*
X1809696Y1091832D03*
X1816756Y1089145D03*
Y1094145D03*
X1816235Y1083970D03*
X1810346Y1082250D03*
X1809651Y1096426D03*
X1816756Y1097145D03*
Y1101145D03*
X1810310Y1104819D03*
X1823028Y1124289D03*
X1817728D03*
X1815128D03*
X1820328D03*
X1822928Y1114589D03*
X1820228D03*
X1815028D03*
X1817628D03*
X1816385Y1136912D03*
X1813885D03*
X1815865Y1133356D03*
X1809535Y1136912D03*
X1813885Y1144912D03*
X1816385D03*
X1809535D03*
X1812130Y1205349D03*
X1822594Y1211054D03*
Y1215324D03*
X1814741Y1217093D03*
X1809897Y1237285D03*
Y1230385D03*
Y1232885D03*
X1811482Y1226423D03*
X1809897Y1239785D03*
Y1244185D03*
Y1246685D03*
X1810018Y1295944D03*
X1812818D03*
X1815618Y1298744D03*
Y1295944D03*
X1812818Y1298744D03*
X1810018D03*
X1812202Y1432624D03*
X1807393Y1436345D03*
X1809342Y1476733D03*
X1812000Y1644980D03*
X1825559Y3001D03*
X1836543Y4470D03*
X1837904Y24774D03*
Y44774D03*
Y64774D03*
Y84774D03*
Y104774D03*
Y124774D03*
Y144774D03*
Y164774D03*
Y184774D03*
Y204774D03*
Y224774D03*
Y244774D03*
Y264774D03*
Y284774D03*
Y304774D03*
X1837728Y324733D03*
X1830094Y333210D03*
X1830472Y960970D03*
X1837937Y973244D03*
X1831511Y978888D03*
X1837937Y993244D03*
X1831914Y992877D03*
X1837937Y1013244D03*
Y1033244D03*
Y1053244D03*
Y1073244D03*
X1824706Y1081145D03*
Y1089145D03*
Y1085145D03*
X1824949Y1077145D03*
X1824733Y1102830D03*
X1837937Y1093244D03*
X1825832Y1097589D03*
X1824706Y1100185D03*
Y1106145D03*
X1828272Y1095968D03*
X1824706Y1093150D03*
X1837937Y1113244D03*
X1830915Y1109146D03*
X1837937Y1133244D03*
Y1153244D03*
Y1173244D03*
Y1193244D03*
Y1213244D03*
X1834665Y1213239D03*
X1837937Y1253244D03*
Y1273244D03*
Y1293244D03*
Y1313244D03*
Y1333244D03*
Y1353244D03*
Y1373244D03*
Y1393244D03*
Y1433244D03*
Y1453244D03*
Y1473244D03*
Y1493244D03*
Y1513244D03*
Y1533244D03*
Y1553244D03*
Y1573244D03*
X1837933Y1636171D03*
X1832000Y1644980D03*
G54D211*
X884732Y570435D03*
Y568466D03*
Y566498D03*
Y572403D03*
Y586183D03*
Y584214D03*
Y582246D03*
Y580277D03*
Y578309D03*
Y576340D03*
Y574372D03*
Y592088D03*
Y590120D03*
Y588151D03*
X915244Y566498D03*
Y568466D03*
Y570435D03*
Y572403D03*
Y574372D03*
Y576340D03*
Y578309D03*
Y580277D03*
Y582246D03*
Y584214D03*
Y586183D03*
Y588151D03*
Y590120D03*
Y592088D03*
X1007094Y321088D03*
Y323057D03*
Y325025D03*
Y326994D03*
Y319120D03*
Y332899D03*
Y334868D03*
Y328962D03*
Y330931D03*
Y342742D03*
Y340773D03*
Y338805D03*
Y336836D03*
Y344710D03*
X1037606Y319120D03*
Y321088D03*
Y323057D03*
Y325025D03*
Y326994D03*
Y330931D03*
Y332899D03*
Y334868D03*
Y336836D03*
Y338805D03*
Y340773D03*
Y342742D03*
Y328962D03*
Y344710D03*
G54D230*
X944110Y1444139D03*
X939110D03*
X934110D03*
X949110D03*
X960268Y1444392D03*
X975268D03*
X970268D03*
X965268D03*
X993334D03*
X988334D03*
X983334D03*
X998334D03*
X1011366Y1444492D03*
X1006366D03*
X1021366D03*
X1016366D03*
X1039252Y1444608D03*
X1034252D03*
X1029252D03*
X1044252D03*
G54D20*
X13874Y111710D03*
X11314D03*
X13874Y128836D03*
X11314D03*
X208408Y64722D03*
X205848D03*
X208408Y81848D03*
X205848D03*
X310770Y64722D03*
X308210D03*
X310770Y81848D03*
X308210D03*
X355568Y1146842D03*
X358128D03*
X355568Y1163968D03*
X358128D03*
X563133Y64722D03*
X560573D03*
X563133Y81848D03*
X560573D03*
X665495Y64722D03*
X662935D03*
X665495Y81848D03*
X662935D03*
X765297Y64722D03*
Y81848D03*
X767857Y64722D03*
Y81848D03*
X812655Y1146842D03*
X815215D03*
X812655Y1163968D03*
X815215D03*
X836243Y935779D03*
X833683D03*
Y952905D03*
X836243D03*
X870219Y64722D03*
X867659D03*
X870219Y81848D03*
X867659D03*
X1020219Y64722D03*
X1017659D03*
X1020219Y81848D03*
X1017659D03*
X1122581Y64722D03*
X1120021D03*
X1122581Y81848D03*
X1120021D03*
X1224943Y64722D03*
X1222383D03*
X1224943Y81848D03*
X1222383D03*
X1269741Y1146842D03*
Y1163968D03*
X1272301Y1146842D03*
Y1163968D03*
X1477306Y64722D03*
X1474746D03*
X1477306Y81848D03*
X1474746D03*
X1577108Y64722D03*
Y81848D03*
X1579668Y64722D03*
Y81848D03*
X1599726Y1479190D03*
X1597166D03*
X1599726Y1496316D03*
X1597166D03*
X1682030Y64722D03*
X1679470D03*
X1682030Y81848D03*
X1679470D03*
X1726828Y1146842D03*
X1729388D03*
X1726828Y1163968D03*
X1729388D03*
X1784392Y64722D03*
X1781832D03*
X1784392Y81848D03*
X1781832D03*
G54D104*
X114974Y1109408D03*
Y1122008D03*
Y1134608D03*
Y1147208D03*
Y1159808D03*
Y1172408D03*
Y1185008D03*
X134100Y1016671D03*
X126620D03*
X134100Y1029271D03*
X126620D03*
X122454Y1109408D03*
Y1122008D03*
Y1134608D03*
Y1147208D03*
Y1159808D03*
Y1172408D03*
Y1185008D03*
X572061Y1109408D03*
Y1122008D03*
Y1134608D03*
Y1147208D03*
Y1159808D03*
Y1172408D03*
Y1185008D03*
X583707Y1016671D03*
Y1029271D03*
X579541Y1109408D03*
Y1122008D03*
Y1134608D03*
Y1147208D03*
Y1159808D03*
Y1172408D03*
Y1185008D03*
X591187Y1016671D03*
Y1029271D03*
X1040793Y1016671D03*
Y1029271D03*
X1036627Y1109408D03*
X1029147D03*
X1036627Y1122008D03*
X1029147D03*
X1036627Y1134608D03*
X1029147D03*
X1036627Y1147208D03*
X1029147D03*
X1036627Y1159808D03*
X1029147D03*
X1036627Y1172408D03*
X1029147D03*
X1036627Y1185008D03*
X1029147D03*
X1048273Y1016671D03*
Y1029271D03*
X1497880Y1016671D03*
Y1029271D03*
X1493714Y1109408D03*
X1486234D03*
X1493714Y1122008D03*
X1486234D03*
X1493714Y1134608D03*
X1486234D03*
X1493714Y1147208D03*
X1486234D03*
X1493714Y1172408D03*
X1486234D03*
X1493714Y1159808D03*
X1486234D03*
X1493714Y1185008D03*
X1486234D03*
X1505360Y1016671D03*
Y1029271D03*
G54D221*
X934878Y1555045D03*
X971690D03*
G54D203*
X863687Y1443780D03*
X861718D03*
X859750D03*
Y1461398D03*
X861718D03*
X863687D03*
X869592Y1443780D03*
X867624D03*
X865655D03*
Y1461398D03*
X867624D03*
X869592D03*
X911592Y1443780D03*
X909624D03*
X907655D03*
X905687D03*
X903718D03*
X901750D03*
Y1461398D03*
X903718D03*
X905687D03*
X907655D03*
X909624D03*
X911592D03*
G54D113*
X173829Y455492D03*
Y583957D03*
X202844Y455492D03*
Y583957D03*
X266841Y421555D03*
Y550020D03*
X295856Y421555D03*
Y550020D03*
X630915Y455492D03*
Y583957D03*
X659930Y455492D03*
Y583957D03*
X723927Y421555D03*
Y550020D03*
X752942Y421555D03*
Y550020D03*
X1088002Y455492D03*
Y583957D03*
X1117017Y455492D03*
Y583957D03*
X1181014Y421555D03*
Y550020D03*
X1210029Y421555D03*
Y550020D03*
X1545089Y455492D03*
Y583957D03*
X1574104Y455492D03*
Y583957D03*
X1638101Y421555D03*
Y550020D03*
X1667116Y421555D03*
Y550020D03*
G54D122*
X360727Y458603D03*
X466821Y473078D03*
X817813Y452603D03*
X1274900Y458603D03*
X1731987D03*
G54D131*
X405466Y673038D03*
X426726D03*
X443226D03*
X464486D03*
G54D11*
X6385Y997697D03*
X22792Y997712D03*
X16647Y997670D03*
X11449Y997669D03*
X16463Y1536219D03*
X16080Y1541684D03*
X21080Y1543113D03*
X34987Y997724D03*
X29275Y997737D03*
X24074Y1496519D03*
X26017Y1543931D03*
X36364Y1544384D03*
X31221Y1544634D03*
X31105Y1549755D03*
X50285Y172879D03*
X51946Y997678D03*
X46108Y997664D03*
X40334Y997805D03*
X46818Y1544660D03*
X52264Y1545189D03*
X41522Y1545112D03*
X68448Y997793D03*
X62211Y997892D03*
X57214Y997884D03*
X57598Y1544760D03*
X61611Y1539765D03*
X77688Y847363D03*
X97033Y679427D03*
X111733Y154865D03*
X116731Y1052235D03*
X106619Y1056423D03*
X102431Y1066535D03*
X106619Y1076647D03*
X116731Y1080835D03*
Y1249086D03*
X106619Y1253274D03*
X102431Y1263386D03*
X106619Y1273498D03*
X116731Y1277686D03*
X126843Y1056423D03*
Y1076647D03*
X131031Y1066535D03*
X126843Y1253274D03*
X131031Y1263386D03*
X126843Y1273498D03*
X158929Y382600D03*
X159020Y465177D03*
X159044Y552674D03*
X158982Y564371D03*
Y559371D03*
X158198Y596321D03*
X159020Y591388D03*
X158220Y606190D03*
X159042Y601257D03*
X159046Y621005D03*
X159049Y611126D03*
X158242Y616069D03*
X158555Y637979D03*
X159023Y630886D03*
X158219Y625950D03*
X214095Y154865D03*
X213594Y462800D03*
X213662Y549469D03*
X213797Y554598D03*
X214000Y619500D03*
Y625400D03*
X241825Y380718D03*
X246141Y387884D03*
X244960Y393858D03*
X242398Y404718D03*
X242561Y412718D03*
X243278Y628696D03*
X248984Y628670D03*
X249867Y645941D03*
X243078Y645900D03*
X253186Y391496D03*
X252004Y384718D03*
X251601Y408718D03*
X252819Y400718D03*
X256091Y542712D03*
X256120Y620788D03*
X280600Y894200D03*
X279500Y904200D03*
X294841Y317911D03*
X286784Y858900D03*
X287471Y868900D03*
X288580Y929400D03*
X288084Y939400D03*
X310665Y540335D03*
X310756Y622912D03*
X316457Y154865D03*
X342840Y1056423D03*
X338652Y1066535D03*
X342840Y1076647D03*
X345631Y1174897D03*
X342399Y1198783D03*
X344444Y1211312D03*
X342840Y1253274D03*
X338652Y1263386D03*
X342840Y1273498D03*
X352952Y1052235D03*
Y1080835D03*
Y1249086D03*
Y1277686D03*
X363064Y1056423D03*
Y1076647D03*
X367252Y1066535D03*
X363064Y1253274D03*
X367252Y1263386D03*
X363064Y1273498D03*
X383900Y744100D03*
X384600Y750005D03*
X382607Y764500D03*
X386500Y782100D03*
X383200Y790225D03*
X411800Y790900D03*
X408967Y854329D03*
X416200Y786700D03*
X420400Y790700D03*
X423104Y892213D03*
X431600Y777564D03*
X466458Y154865D03*
X472148Y996052D03*
X477248D03*
X471443Y1001144D03*
X477248Y1001052D03*
X467878Y1042357D03*
X461897Y1041794D03*
X486623Y655447D03*
X491006Y1000497D03*
X484497Y1001466D03*
X491647Y1011963D03*
X492042Y1020491D03*
X491210Y1027453D03*
X499263Y665627D03*
X508833Y765565D03*
X495574Y1004176D03*
X495663Y1015420D03*
X497073Y1026059D03*
X501422Y1037680D03*
X526210Y768013D03*
X518782Y754155D03*
X556334Y755432D03*
X568820Y154865D03*
X567445Y738419D03*
X563706Y1056423D03*
X559518Y1066535D03*
X563706Y1076647D03*
Y1253274D03*
X559518Y1263386D03*
X563706Y1273498D03*
X575295Y743494D03*
X579444Y784955D03*
X584200Y790791D03*
X583930Y1056423D03*
X573818Y1052235D03*
X583930Y1076647D03*
X588118Y1066535D03*
X573818Y1080835D03*
X583930Y1253274D03*
X573818Y1249086D03*
X588118Y1263386D03*
X573818Y1277686D03*
X583930Y1273498D03*
X596871Y949646D03*
X616015Y382600D03*
X616106Y465177D03*
X616130Y552674D03*
X616068Y564371D03*
Y559371D03*
X616128Y601257D03*
X616106Y591388D03*
X615306Y606190D03*
X615284Y596321D03*
X616132Y621005D03*
X616135Y611126D03*
X615328Y616069D03*
X615641Y637979D03*
X615305Y625950D03*
X616109Y630886D03*
X610562Y648262D03*
X651602Y704366D03*
X671182Y154865D03*
X670680Y462800D03*
X670748Y549469D03*
X670770Y554598D03*
X671086Y619500D03*
Y625400D03*
X664168Y684077D03*
X661346Y763137D03*
X661846Y779137D03*
X661346Y771137D03*
Y787137D03*
X674416Y689694D03*
X674846Y763137D03*
X675346Y779137D03*
X674846Y771137D03*
Y787137D03*
X702046Y393858D03*
X700364Y628696D03*
X700164Y645900D03*
X699272Y707772D03*
X708305Y387884D03*
X709905Y400718D03*
X713206Y620788D03*
X706070Y628670D03*
X706953Y645941D03*
X711738Y691609D03*
X713401Y709949D03*
X721141Y730734D03*
X715607Y747977D03*
X716346Y760137D03*
X719846Y764137D03*
X716346Y768637D03*
X719846Y756137D03*
Y772637D03*
X724994Y690625D03*
X726897Y750559D03*
X751927Y317911D03*
X740530Y1524113D03*
X744188Y1624699D03*
X768460Y448957D03*
X767751Y540335D03*
X767842Y622912D03*
X760433Y1480906D03*
X756274Y1490945D03*
X760433Y1500984D03*
X754862Y1592302D03*
X753985Y1620898D03*
X773544Y154865D03*
X776094Y441165D03*
X774099Y446595D03*
X770545Y900475D03*
X780511Y1480906D03*
X770472Y1476747D03*
Y1505143D03*
X780511Y1500984D03*
X799926Y1056423D03*
X795738Y1066535D03*
X799926Y1076647D03*
X802291Y1211461D03*
X795411Y1212399D03*
X799926Y1253274D03*
X795738Y1263386D03*
X799926Y1273498D03*
X790361Y1447895D03*
X790754Y1441399D03*
X790296Y1463459D03*
X787038Y1460533D03*
X790989Y1455695D03*
X784670Y1490945D03*
X787885Y1631364D03*
X810040Y378544D03*
X805881Y388583D03*
X810040Y398622D03*
X813635Y762000D03*
X811279Y869693D03*
X809500Y887500D03*
X810500Y900000D03*
X810038Y1052235D03*
Y1080835D03*
X802606Y1175026D03*
X810038Y1249086D03*
Y1277686D03*
X825977Y327207D03*
X819977Y317368D03*
Y324648D03*
X820196Y332149D03*
X820079Y374385D03*
X830118Y378544D03*
X820079Y402781D03*
X830118Y398622D03*
X834282Y536085D03*
X827284Y721262D03*
X829484Y903759D03*
X820150Y1056423D03*
Y1076647D03*
X824338Y1066535D03*
X820150Y1253274D03*
X824338Y1263386D03*
X820150Y1273498D03*
X826204Y1444689D03*
X826219Y1455244D03*
X830400Y1473900D03*
X834277Y388583D03*
X843284Y721262D03*
X836284Y721273D03*
X850377Y1443959D03*
X850744Y1461959D03*
X847600Y1474100D03*
X865331Y717919D03*
X852284Y721273D03*
X865012Y727387D03*
X865567Y849885D03*
X861832Y846197D03*
X864760Y840928D03*
X861599Y836900D03*
X867179Y855265D03*
X861663Y853141D03*
X862776Y862467D03*
X863726Y872719D03*
X863091Y867659D03*
X863792Y877798D03*
X852774Y1001027D03*
X860514Y1000691D03*
X859900Y1008686D03*
X880138Y549603D03*
X879449Y568863D03*
X877339Y574408D03*
X879449Y562703D03*
X879055Y582828D03*
X875887Y682223D03*
X881836Y682219D03*
X869970Y704561D03*
X882765Y713846D03*
X879190Y821364D03*
X867858Y845174D03*
X867876Y836956D03*
X868123Y865298D03*
Y860298D03*
Y875298D03*
Y870298D03*
Y880298D03*
Y885298D03*
X879147Y896530D03*
X879664Y901568D03*
X874002Y1009399D03*
X868934Y1009274D03*
X879086Y1009110D03*
X878954Y1446432D03*
X878245Y1465859D03*
X875800Y1478600D03*
X878244Y1471359D03*
X889414Y544911D03*
X887939Y558338D03*
X893536Y558394D03*
X897689Y544660D03*
X891527Y728033D03*
X896161Y824930D03*
X889190Y821364D03*
X884190D03*
X899190Y821269D03*
X886664Y825717D03*
X894154Y896438D03*
X899103Y899321D03*
X889154Y896438D03*
X884154D03*
X896654Y903807D03*
X891654Y900773D03*
X886654D03*
X884110Y1009264D03*
X889202Y1009184D03*
X899313Y1009197D03*
X894225Y1009250D03*
X892616Y1446517D03*
X892101Y1467602D03*
X893200Y1478600D03*
X905114Y551773D03*
X903710Y544382D03*
X902236Y689332D03*
Y694332D03*
X906457Y723731D03*
X901226Y796828D03*
X904940Y821364D03*
X908378Y825308D03*
X901690Y825699D03*
X904154Y896438D03*
X914154D03*
X909154D03*
X901654Y903844D03*
X911654Y900773D03*
X906654D03*
X911352Y1012137D03*
X904484Y1011004D03*
X923544Y154865D03*
X920544Y570607D03*
X920870Y575763D03*
X919328Y685622D03*
X928672Y703241D03*
X929822Y709770D03*
X927662Y821009D03*
X925302Y825658D03*
X922431Y821308D03*
X924154Y896438D03*
X919154D03*
X916654Y900773D03*
X921654D03*
X926654D03*
X918503Y1009401D03*
X929069Y1009103D03*
X923576Y1009292D03*
X931159Y1379427D03*
X920360Y1387039D03*
X931199Y1371951D03*
X931159Y1390827D03*
Y1406027D03*
X920235Y1443493D03*
X921629Y1463235D03*
X921653Y1476971D03*
X937567Y306013D03*
X938858Y844582D03*
X938820Y836863D03*
X938984Y849888D03*
X939000Y863474D03*
X939042Y854928D03*
X945100Y852400D03*
X946482Y869624D03*
X939309Y879021D03*
X939269Y868921D03*
X938729Y874396D03*
X934525Y1009346D03*
X939966Y1009184D03*
X945166Y1009189D03*
X939559Y1398427D03*
X953692Y696577D03*
X955576Y1009333D03*
X960845Y1008941D03*
X950389Y1009350D03*
X972792Y710988D03*
X966466Y1009238D03*
X971798Y1009319D03*
X980018Y1009991D03*
X970071Y1365652D03*
Y1409152D03*
X988192Y327561D03*
X994830Y326789D03*
X988045Y355812D03*
X1001443Y357523D03*
X1011862Y354276D03*
X1010827Y378544D03*
X1006668Y388583D03*
X1010827Y398622D03*
X1005814Y1351584D03*
X1025906Y154865D03*
X1025418Y310476D03*
X1018820Y311772D03*
X1013664Y311359D03*
X1025885Y352848D03*
X1020866Y374385D03*
Y402781D03*
X1020793Y1056423D03*
X1016605Y1066535D03*
X1020793Y1076647D03*
Y1253274D03*
X1016605Y1263386D03*
X1020793Y1273498D03*
X1021406Y1323530D03*
X1019109Y1353132D03*
X1024316Y1358339D03*
X1019330Y1380797D03*
X1041496Y311094D03*
X1030418Y310476D03*
X1045939Y332533D03*
X1030905Y378544D03*
X1035064Y388583D03*
X1030905Y398622D03*
X1037934Y847222D03*
X1029913Y853842D03*
X1038432Y946661D03*
X1041017Y1056423D03*
X1030905Y1052235D03*
X1041017Y1076647D03*
X1030905Y1080835D03*
X1041017Y1253274D03*
X1030905Y1249086D03*
Y1277686D03*
X1041017Y1273498D03*
X1034196Y1309624D03*
X1038996Y1376272D03*
X1050632Y314539D03*
X1047063Y361176D03*
X1053358Y826499D03*
X1045205Y1066535D03*
Y1263386D03*
X1049174Y1315612D03*
X1062053Y1437930D03*
X1053194Y1456493D03*
X1060433Y1480906D03*
X1056274Y1490945D03*
X1060433Y1500984D03*
X1073102Y382600D03*
X1073193Y465177D03*
X1073217Y552674D03*
X1073155Y564371D03*
Y559371D03*
X1073215Y601257D03*
X1072371Y596321D03*
X1073193Y591388D03*
X1072393Y606190D03*
X1072415Y616069D03*
X1073222Y611126D03*
X1073219Y621005D03*
X1072728Y637979D03*
X1072392Y625950D03*
X1073196Y630886D03*
X1070472Y1476747D03*
Y1505143D03*
X1080511Y1480906D03*
X1084670Y1490945D03*
X1080511Y1500984D03*
X1109113Y706901D03*
X1122228Y683055D03*
X1128268Y154865D03*
X1138571Y329148D03*
X1127767Y462800D03*
X1127857Y554598D03*
X1127835Y549469D03*
X1128173Y619500D03*
Y625400D03*
X1133869Y648421D03*
X1130970Y689694D03*
X1155998Y380718D03*
X1159133Y393858D03*
X1156571Y404718D03*
X1156734Y412718D03*
X1157451Y628696D03*
X1157251Y645900D03*
X1152485Y775642D03*
X1156485Y779142D03*
X1159485Y834142D03*
Y820642D03*
X1169668Y373503D03*
X1166177Y384718D03*
X1167359Y391496D03*
X1160314Y387884D03*
X1165774Y408718D03*
X1166992Y400718D03*
X1170264Y542712D03*
X1170293Y620788D03*
X1163157Y628670D03*
X1164040Y645941D03*
X1168985Y775642D03*
X1164985Y779142D03*
X1160485Y775642D03*
X1175485Y833642D03*
X1167485Y834142D03*
Y820642D03*
X1175485Y820142D03*
X1181155Y329703D03*
X1180312Y319267D03*
X1183485Y834142D03*
Y820642D03*
X1209014Y317911D03*
X1230630Y154865D03*
X1224838Y540335D03*
X1224929Y622912D03*
X1256938Y894863D03*
X1252825Y1066535D03*
X1252381Y1207061D03*
X1252825Y1263386D03*
X1268457Y864487D03*
Y854487D03*
Y859487D03*
Y879487D03*
Y869487D03*
Y874487D03*
Y889487D03*
Y884487D03*
X1261622Y907067D03*
X1267125Y1052235D03*
X1257013Y1056423D03*
Y1076647D03*
X1267125Y1080835D03*
X1259802Y1174426D03*
X1257411Y1211284D03*
X1272351Y1230750D03*
X1267125Y1249086D03*
X1257013Y1253274D03*
Y1273498D03*
X1267125Y1277686D03*
X1282055Y857317D03*
X1279822Y968916D03*
X1277237Y1056423D03*
Y1076647D03*
X1281425Y1066535D03*
X1277237Y1253274D03*
X1281425Y1263386D03*
X1277237Y1273498D03*
X1296770Y828775D03*
X1299990Y847500D03*
X1295943Y855500D03*
X1299855Y862312D03*
X1299488Y868440D03*
X1295758Y877783D03*
X1301482Y881783D03*
X1301314Y873484D03*
X1301379Y889783D03*
X1295799Y885783D03*
X1318063Y359511D03*
X1317000Y817500D03*
X1321000Y814200D03*
X1313000D03*
X1325007Y360259D03*
X1334071Y757675D03*
X1334340Y768876D03*
X1325000Y817500D03*
X1333000D03*
X1337000Y814200D03*
X1329000D03*
X1322500Y915300D03*
X1334500Y911643D03*
X1326500Y911500D03*
X1338500Y915300D03*
X1330500D03*
X1345000Y814200D03*
X1353000D03*
X1349000Y817500D03*
X1341000D03*
X1344500Y911500D03*
X1351380Y915164D03*
X1349566Y1102794D03*
X1365000Y817500D03*
X1368381Y814312D03*
X1357000Y817500D03*
X1361000Y814200D03*
X1368000Y911500D03*
X1364500Y915300D03*
X1361000Y911500D03*
X1356500Y915000D03*
X1380631Y154865D03*
X1380544Y815248D03*
X1371604Y817398D03*
X1384090Y817377D03*
X1375600Y814702D03*
X1382000Y911500D03*
X1371500Y915300D03*
X1378500D03*
X1375000Y911500D03*
X1386322Y996052D03*
X1385617Y1001144D03*
X1376071Y1041794D03*
X1382052Y1042357D03*
X1401583Y832491D03*
X1395998Y837744D03*
X1397000Y850343D03*
X1402500Y856000D03*
X1398909Y872000D03*
X1391422Y996052D03*
X1398671Y1001466D03*
X1391422Y1001052D03*
X1405180Y1000497D03*
X1405821Y1011963D03*
X1409748Y1004176D03*
X1406216Y1020491D03*
X1410397Y1027097D03*
X1405384Y1027452D03*
X1409837Y1015420D03*
X1415596Y1037680D03*
X1416396Y1538143D03*
X1416319Y1543379D03*
X1415241Y1556416D03*
X1415962Y1564320D03*
X1432806Y947059D03*
X1428212Y933016D03*
X1432818Y941439D03*
X1421560Y1511532D03*
X1431788Y1503314D03*
X1426593Y1503302D03*
X1424573Y1548351D03*
X1423817Y1569486D03*
X1443428Y1029000D03*
X1436448Y1549610D03*
X1444598Y1566170D03*
X1461585Y939543D03*
X1461441Y944864D03*
X1456669Y933701D03*
X1482993Y154865D03*
X1477879Y1056423D03*
X1473691Y1066535D03*
X1477879Y1076647D03*
Y1253274D03*
X1473691Y1263386D03*
X1477879Y1273498D03*
X1498103Y1056423D03*
X1487991Y1052235D03*
X1498103Y1076647D03*
X1487991Y1080835D03*
X1498103Y1253274D03*
X1487991Y1249086D03*
Y1277686D03*
X1498103Y1273498D03*
X1502291Y1066535D03*
Y1263386D03*
X1530189Y382600D03*
X1530280Y465177D03*
X1530304Y552674D03*
X1530242Y559371D03*
Y564371D03*
X1529458Y596321D03*
X1530302Y601257D03*
X1530280Y591388D03*
X1529480Y606190D03*
X1530309Y611126D03*
X1529502Y616069D03*
X1530306Y621005D03*
X1530283Y630886D03*
X1529815Y637979D03*
X1529479Y625950D03*
X1535221Y971822D03*
X1562810Y954054D03*
X1578448Y683787D03*
X1566655Y707314D03*
X1585355Y154865D03*
X1584854Y462800D03*
X1584944Y554598D03*
X1584922Y549469D03*
X1585260Y619500D03*
Y625400D03*
X1586978Y652399D03*
X1590707Y1451470D03*
X1587746Y1465452D03*
X1613085Y380718D03*
X1613658Y404718D03*
X1613821Y412718D03*
X1614538Y628696D03*
X1614338Y645900D03*
X1608750Y788150D03*
X1603251Y797012D03*
X1609400Y803800D03*
X1609800Y817300D03*
X1602595Y802852D03*
X1603966Y816799D03*
X1602862Y829738D03*
X1611522Y1540314D03*
X1617925Y370700D03*
X1616220Y393858D03*
X1624446Y391496D03*
X1617401Y387884D03*
X1623264Y384718D03*
X1622861Y408718D03*
X1624079Y400718D03*
X1627351Y542712D03*
X1627380Y620788D03*
X1620244Y628670D03*
X1621127Y645941D03*
X1621111Y687047D03*
X1620600Y699930D03*
X1620500Y717830D03*
X1621200Y732430D03*
X1621700Y750630D03*
X1616655Y769300D03*
X1629500Y782300D03*
X1629700Y795700D03*
X1628400Y809400D03*
X1625500Y826900D03*
X1639300Y708900D03*
X1640100Y723200D03*
X1635300Y743400D03*
X1634541Y761759D03*
X1666101Y317911D03*
X1687717Y154865D03*
X1681925Y540335D03*
X1682016Y622912D03*
X1709912Y1066535D03*
Y1263386D03*
X1724212Y1052235D03*
X1714100Y1056423D03*
Y1076647D03*
X1724212Y1080835D03*
X1716700Y1174526D03*
X1724212Y1249086D03*
X1714100Y1253274D03*
Y1273498D03*
X1724212Y1277686D03*
X1734324Y1056423D03*
Y1076647D03*
X1738512Y1066535D03*
X1729553Y1230788D03*
X1734324Y1253274D03*
X1738512Y1263386D03*
X1734324Y1273498D03*
X1757879Y879213D03*
X1757933Y897260D03*
X1757914Y884667D03*
X1757805Y913336D03*
X1757275Y926200D03*
X1756060Y1010750D03*
X1761745Y1010616D03*
X1773278Y1010643D03*
X1767133Y1010601D03*
X1782357Y919151D03*
X1789774Y918954D03*
X1790820Y1010736D03*
X1779761Y1010668D03*
X1785473Y1010655D03*
X1782088Y1430956D03*
X1786936Y1467917D03*
X1804600Y910175D03*
X1795764Y918695D03*
X1796594Y1010595D03*
X1807688Y1010616D03*
X1802432Y1010609D03*
X1795100Y1463678D03*
X1795147Y1478147D03*
X1814900Y907025D03*
X1813114Y973235D03*
X1818934Y1010724D03*
X1812697D03*
X1903466Y2079348D03*
X1915566D03*
X1927666Y2067248D03*
Y2079348D03*
X1949818Y2056098D03*
X1939605Y2057393D03*
G54D140*
X413469Y1183065D03*
Y1208261D03*
X439639Y896653D03*
Y921849D03*
X440399Y1183065D03*
Y1208261D03*
X486671Y1183065D03*
Y1208261D03*
X513601Y1183065D03*
Y1208261D03*
X1327643Y1183065D03*
Y1208261D03*
X1354573Y1183065D03*
Y1208261D03*
X1400845Y1183065D03*
Y1208261D03*
X1427775Y1183065D03*
Y1208261D03*
G54D212*
X899988Y579293D03*
G54D150*
X423674Y430898D03*
X919000Y447239D03*
X1337847Y430898D03*
X1794934D03*
G54D21*
X6305Y105001D03*
X13806Y242078D03*
X9836Y248371D03*
X13806Y262078D03*
X9836Y268371D03*
X9206Y1496782D03*
X6548Y1556883D03*
X22912Y51296D03*
Y55305D03*
X26820Y67527D03*
Y63527D03*
Y59527D03*
X24930Y106495D03*
X29448Y177448D03*
X21614Y206864D03*
X20785Y242078D03*
Y262078D03*
X30447Y250599D03*
Y270599D03*
X23570Y292608D03*
X31786Y281272D03*
X28490Y536726D03*
Y531726D03*
Y552726D03*
Y540726D03*
Y544726D03*
X30208Y629311D03*
Y625311D03*
X45417Y177606D03*
X38321Y478982D03*
Y483982D03*
Y487982D03*
Y499982D03*
Y491982D03*
X40615Y597393D03*
X47270Y631212D03*
X50240Y1072761D03*
X40707Y1093757D03*
X39543Y1248448D03*
X56265Y847718D03*
X68751Y843118D03*
X64600Y1091656D03*
X58301Y1213720D03*
X62419Y1544571D03*
X74291Y151540D03*
X77750Y168697D03*
X77945Y191941D03*
X79914Y224321D03*
X80292Y571614D03*
Y575614D03*
X69035Y575841D03*
X78830Y686107D03*
X94902Y149768D03*
X101838Y192665D03*
Y196665D03*
X101933Y204864D03*
X116168Y242078D03*
X112198Y252371D03*
X127301Y106495D03*
X123976Y206864D03*
X123147Y242078D03*
X132809Y250599D03*
X144204Y554555D03*
Y558555D03*
Y562555D03*
X151116Y382600D03*
Y463600D03*
X150484Y595588D03*
Y591588D03*
X150516Y603600D03*
X150484Y599588D03*
X150516Y611600D03*
Y619600D03*
X150484Y607588D03*
X150516Y615600D03*
Y623600D03*
Y627600D03*
Y637969D03*
Y641974D03*
X176653Y151540D03*
X180112Y168697D03*
X180307Y191941D03*
X182276Y224321D03*
X194014Y68581D03*
Y80581D03*
X197264Y149768D03*
X203339Y58013D03*
X199557Y114488D03*
X204200Y196665D03*
Y192665D03*
X204295Y204864D03*
X214560Y252371D03*
X229654Y106495D03*
X226338Y206864D03*
X218530Y242078D03*
X225509D03*
X230780Y384718D03*
Y380718D03*
Y392718D03*
Y396718D03*
Y400718D03*
Y404718D03*
Y408718D03*
Y412718D03*
X218316Y458800D03*
X227116Y553700D03*
X218516Y545800D03*
X227116Y557700D03*
X227560Y1474522D03*
X227559Y1478442D03*
Y1486442D03*
X229559Y1510442D03*
X229564Y1518578D03*
X235171Y250599D03*
X241941Y675832D03*
X246402Y816300D03*
X245402Y836800D03*
X246401Y1506058D03*
X249216Y453873D03*
Y458859D03*
X248401Y542712D03*
X248701Y1517958D03*
X279015Y151540D03*
X296376Y68581D03*
Y80581D03*
X282474Y168697D03*
X282669Y191941D03*
X284638Y224321D03*
X309197Y35007D03*
X305701Y58013D03*
X301919Y114488D03*
X299626Y149768D03*
X306562Y192665D03*
Y196665D03*
X306657Y204864D03*
X328700Y206864D03*
X320892Y242078D03*
X327871D03*
X316922Y252371D03*
X323973Y306652D03*
X315601Y545912D03*
Y626912D03*
X332016Y106495D03*
X337533Y250599D03*
X343941Y1146071D03*
X347541Y458334D03*
Y450334D03*
X357914Y1170370D03*
X351283Y1191599D03*
X368416Y488816D03*
X376102Y745300D03*
X374402Y764500D03*
X363984Y943480D03*
X372948Y959812D03*
Y955812D03*
Y951812D03*
Y963812D03*
Y967812D03*
Y971812D03*
X384836Y168697D03*
X385031Y191941D03*
X387000Y224321D03*
X388184Y470382D03*
X389711Y868286D03*
X384533Y1547700D03*
Y1555700D03*
X404281Y114488D03*
X408924Y192665D03*
Y196665D03*
X409019Y204864D03*
X404072Y331589D03*
Y335589D03*
X399817Y467560D03*
Y479560D03*
X402904Y889786D03*
X404481Y1446807D03*
X416991Y35983D03*
X415649Y425413D03*
X418189Y455301D03*
Y459101D03*
Y463101D03*
X421817Y474560D03*
X411305Y889551D03*
X410717Y1523296D03*
X424132Y1537088D03*
X424652Y1550211D03*
X429016Y151540D03*
X440689Y424601D03*
Y428101D03*
Y431601D03*
X449627Y149768D03*
X452675Y328285D03*
Y324685D03*
Y344033D03*
Y340433D03*
Y336159D03*
Y332559D03*
Y351907D03*
Y348307D03*
X453635Y464809D03*
Y472809D03*
X442956Y508999D03*
X450493Y638279D03*
X456301Y1002180D03*
Y1007180D03*
X453801Y1012325D03*
Y1016325D03*
X445607Y1022766D03*
Y1034266D03*
Y1030266D03*
X452685Y1043140D03*
X452608Y1047047D03*
X470893Y242078D03*
X466923Y252371D03*
X462919Y495669D03*
Y516609D03*
X482017Y106495D03*
X478701Y206864D03*
X477872Y242078D03*
X487534Y250599D03*
X485426Y387089D03*
Y391589D03*
X485576Y536726D03*
Y531726D03*
Y544726D03*
Y540726D03*
X487294Y629311D03*
Y625311D03*
X478878Y652906D03*
X482301Y1031680D03*
X491301Y1032180D03*
X495407Y478982D03*
Y483982D03*
Y487982D03*
Y499982D03*
Y491982D03*
X497701Y597393D03*
X504356Y631212D03*
X499619Y660441D03*
X505110Y989235D03*
X501107Y1004766D03*
Y996766D03*
Y1008766D03*
X500974Y1020258D03*
X501107Y1030766D03*
X515723Y749443D03*
X509107Y1000766D03*
Y1004766D03*
Y996766D03*
Y1016266D03*
Y1020266D03*
Y1030766D03*
X531378Y151540D03*
X534837Y168697D03*
X535032Y191941D03*
X537001Y224321D03*
X535702Y345723D03*
Y359223D03*
Y354723D03*
Y350223D03*
Y363723D03*
Y377223D03*
Y372723D03*
Y368223D03*
Y386223D03*
Y390723D03*
X537378Y571614D03*
Y575614D03*
X526121Y575841D03*
X532540Y779889D03*
X529202Y840700D03*
X548739Y68581D03*
Y80581D03*
X554282Y114488D03*
X551989Y149768D03*
X545702Y345723D03*
Y350223D03*
Y359223D03*
Y354723D03*
Y377223D03*
Y372723D03*
Y368223D03*
Y363723D03*
Y381723D03*
X549989Y684509D03*
Y700509D03*
Y688509D03*
Y692509D03*
Y696509D03*
Y704509D03*
Y708509D03*
Y712509D03*
Y716509D03*
Y720509D03*
X552642Y841388D03*
X558064Y58013D03*
X558925Y192665D03*
Y196665D03*
X559020Y204864D03*
X569285Y252371D03*
X567519Y747079D03*
X584379Y106495D03*
X581063Y206864D03*
X580234Y242078D03*
X573255D03*
X585805Y957207D03*
X573319Y961807D03*
X585448Y1509687D03*
X589896Y250599D03*
X601290Y554555D03*
Y558555D03*
Y562555D03*
X595001Y1493658D03*
Y1497558D03*
X595101Y1501458D03*
X591197Y1505794D03*
X608202Y382600D03*
Y463600D03*
X607570Y595588D03*
Y591588D03*
X607602Y603600D03*
X607570Y599588D03*
X607602Y611600D03*
Y619600D03*
X607570Y607588D03*
X607602Y615600D03*
Y623600D03*
Y627600D03*
Y637969D03*
Y641974D03*
X633740Y151540D03*
X637199Y168697D03*
X637394Y191941D03*
X651101Y68581D03*
Y80581D03*
X639363Y224321D03*
X660426Y58013D03*
X656644Y114488D03*
X654351Y149768D03*
X661287Y192665D03*
Y196665D03*
X661382Y204864D03*
X655843Y666275D03*
X657959Y710129D03*
X683425Y206864D03*
X675617Y242078D03*
X682596D03*
X671647Y252371D03*
X675402Y458800D03*
X684202Y553700D03*
X675602Y545800D03*
X684202Y557700D03*
X675602Y558800D03*
Y562800D03*
X686741Y106495D03*
X692258Y250599D03*
X687866Y384718D03*
Y380718D03*
Y392718D03*
Y396718D03*
Y400718D03*
Y404718D03*
Y408718D03*
Y412718D03*
X699027Y675832D03*
X706302Y453873D03*
Y458859D03*
X705487Y542712D03*
X713291Y696718D03*
X717212Y779958D03*
X710366Y783453D03*
X724862Y756137D03*
Y764137D03*
Y768137D03*
Y772137D03*
X732916Y1606600D03*
X732267Y1634485D03*
X732283Y1630030D03*
X736102Y151540D03*
X739561Y168697D03*
X739756Y191941D03*
X741725Y224321D03*
X762788Y58013D03*
X753463Y68581D03*
Y80581D03*
X759006Y114488D03*
X756713Y149768D03*
X763649Y196665D03*
Y192665D03*
X763744Y204864D03*
X777979Y242078D03*
X774009Y252371D03*
X781059Y306652D03*
X781608Y442498D03*
X781640Y450510D03*
Y446510D03*
X772687Y545912D03*
Y626912D03*
X780265Y1427432D03*
Y1431432D03*
Y1439432D03*
X778519Y1458066D03*
X771648Y1449870D03*
X789103Y106495D03*
X785787Y206864D03*
X784958Y242078D03*
X794620Y250599D03*
X796360Y1436559D03*
X804627Y444334D03*
Y452334D03*
X808840Y836919D03*
X812340Y893419D03*
X801028Y1146071D03*
X814958Y1171120D03*
X803360Y1436559D03*
X805021Y1476616D03*
X825502Y483816D03*
X827016Y758500D03*
Y762500D03*
Y780500D03*
Y776500D03*
Y794500D03*
Y798500D03*
Y812500D03*
Y816500D03*
X819250Y830038D03*
X816840Y900919D03*
X831220Y1444849D03*
X841923Y168697D03*
X842118Y191941D03*
X844087Y224321D03*
X845270Y465382D03*
X842801Y831558D03*
X836332Y839953D03*
X842873Y839292D03*
X839974Y879459D03*
X842761Y875507D03*
X840284Y871459D03*
X839974Y883459D03*
X841194Y892564D03*
X839881Y887490D03*
X835016Y901500D03*
X842247Y1440859D03*
X842260Y1448959D03*
Y1444959D03*
Y1457959D03*
X855825Y68581D03*
Y80581D03*
X861368Y114488D03*
X863970Y491303D03*
Y479303D03*
X860777Y713170D03*
Y705170D03*
X861516Y768000D03*
Y786000D03*
Y804000D03*
Y822000D03*
X853744Y831469D03*
X853775Y843459D03*
Y847459D03*
Y839459D03*
Y863459D03*
Y859459D03*
Y855459D03*
Y851459D03*
Y867459D03*
Y879459D03*
Y875459D03*
Y871459D03*
Y892959D03*
Y883459D03*
Y887759D03*
X865150Y58013D03*
X866011Y192665D03*
Y196665D03*
X866106Y204864D03*
X880493Y309368D03*
Y305368D03*
Y313368D03*
Y325368D03*
Y321368D03*
Y317368D03*
Y329368D03*
X872600Y337342D03*
X880493D03*
Y333368D03*
X869584Y554703D03*
Y558703D03*
Y574703D03*
Y586828D03*
X869010Y698388D03*
X878777Y686970D03*
Y698970D03*
X886102Y151540D03*
X885970Y486303D03*
X892516Y529633D03*
X883777Y718570D03*
X896930Y1081764D03*
X887397Y1102760D03*
X883233Y1257451D03*
X883760Y1440859D03*
Y1448859D03*
Y1464859D03*
X883735Y1452663D03*
X883760Y1472859D03*
X906713Y149768D03*
X899276Y362369D03*
Y370369D03*
X910975Y441754D03*
X913515Y471642D03*
Y479442D03*
Y475442D03*
X910669Y547348D03*
X906977Y683770D03*
Y695770D03*
Y699770D03*
X911290Y1104659D03*
Y1100659D03*
X901991Y1222723D03*
X927668Y305255D03*
X916861Y304585D03*
X926168Y561578D03*
Y565578D03*
X926152Y585578D03*
Y589578D03*
X926168Y594329D03*
Y598329D03*
X920966Y704111D03*
X921744Y1472100D03*
X939103Y106495D03*
X936453Y192035D03*
X942659Y236866D03*
X944605Y316739D03*
X938693Y351281D03*
X936015Y440942D03*
Y444442D03*
Y447942D03*
X942663Y536726D03*
Y531726D03*
Y544726D03*
Y540726D03*
X944381Y629311D03*
Y625311D03*
X944786Y878216D03*
X936386Y883790D03*
X936388Y887508D03*
X944930Y899890D03*
X952494Y478982D03*
Y483982D03*
Y487982D03*
Y499982D03*
Y491982D03*
X954788Y597393D03*
X961443Y631212D03*
X949700Y792505D03*
X954573Y846665D03*
X947659Y846635D03*
X953214Y870278D03*
X960907Y1081764D03*
X951374Y1102760D03*
X947210Y1257451D03*
X978122Y343112D03*
Y346612D03*
X975267Y1100659D03*
Y1104659D03*
X965968Y1222723D03*
X988464Y151540D03*
X991923Y168697D03*
X992118Y191941D03*
X994087Y224321D03*
X979641Y338972D03*
Y331972D03*
X994465Y571614D03*
Y575614D03*
X983208Y575841D03*
X979637Y848597D03*
X981719Y837159D03*
X983951Y1104622D03*
X983988Y1100302D03*
X1005825Y68581D03*
Y80581D03*
X1009075Y149768D03*
X1008687Y196620D03*
X1011024Y1353714D03*
X1010977Y1363533D03*
X1010999Y1372734D03*
X1010994Y1376752D03*
X1015150Y58013D03*
X1011368Y114488D03*
X1016011Y196665D03*
Y192665D03*
X1016106Y204864D03*
X1026371Y252371D03*
X1015219Y837659D03*
X1014935Y958822D03*
X1041465Y106495D03*
X1038149Y206864D03*
X1030341Y242078D03*
X1037320D03*
X1030004Y847222D03*
X1027421Y954222D03*
X1046982Y250599D03*
X1055741Y314539D03*
Y322843D03*
Y328156D03*
Y319243D03*
X1055628Y339509D03*
X1055741Y331756D03*
X1055220Y360151D03*
Y364276D03*
X1058377Y554555D03*
Y558555D03*
Y562555D03*
X1065289Y382600D03*
Y463600D03*
X1064657Y595588D03*
Y591588D03*
X1064689Y603600D03*
X1064657Y599588D03*
X1064689Y611600D03*
Y619600D03*
X1064657Y607588D03*
X1064689Y615600D03*
Y623600D03*
Y627600D03*
Y637969D03*
Y641974D03*
X1090826Y151540D03*
X1108187Y68581D03*
Y80581D03*
X1094285Y168697D03*
X1094480Y191941D03*
X1096449Y224321D03*
X1117512Y58013D03*
X1113730Y114488D03*
X1111437Y149768D03*
X1109994Y168713D03*
X1118373Y192665D03*
Y196665D03*
X1118468Y204864D03*
X1117516Y329000D03*
Y334000D03*
Y339000D03*
X1112930Y666275D03*
X1115046Y710129D03*
X1140511Y206864D03*
X1132703Y242078D03*
X1139682D03*
X1128733Y252371D03*
X1126016Y329000D03*
Y334000D03*
Y339000D03*
X1132489Y458800D03*
X1132689Y545800D03*
Y558800D03*
Y562800D03*
X1143827Y106495D03*
X1149344Y250599D03*
X1144953Y392718D03*
Y384718D03*
Y380718D03*
Y404718D03*
Y408718D03*
Y396718D03*
Y400718D03*
Y412718D03*
X1141289Y553700D03*
Y557700D03*
X1156114Y675832D03*
X1163389Y453873D03*
Y458859D03*
X1162574Y542712D03*
X1184100Y324142D03*
X1188980Y329398D03*
X1174686Y774434D03*
X1193188Y151540D03*
X1196647Y168697D03*
X1196842Y191941D03*
X1198811Y224321D03*
X1219874Y58013D03*
X1210549Y68581D03*
Y80581D03*
X1216092Y114488D03*
X1213799Y149768D03*
X1212356Y168713D03*
X1220735Y192665D03*
Y196665D03*
X1220830Y204864D03*
X1235065Y242078D03*
X1231095Y252371D03*
X1238146Y306652D03*
X1229774Y545912D03*
Y626912D03*
X1246189Y106495D03*
X1242873Y206864D03*
X1242044Y242078D03*
X1251706Y250599D03*
X1252956Y1192376D03*
X1258016Y336000D03*
X1261714Y450334D03*
Y458334D03*
X1261710Y894866D03*
X1258114Y1146071D03*
X1257201Y1523458D03*
X1257162Y1527334D03*
X1257201Y1543558D03*
X1257162Y1531334D03*
Y1539334D03*
X1257186Y1535385D03*
X1282589Y488816D03*
X1282030Y768576D03*
Y780576D03*
X1273687Y848145D03*
X1273783Y864487D03*
Y859487D03*
X1273771Y852029D03*
X1273783Y874487D03*
Y869487D03*
Y879487D03*
Y889487D03*
Y884487D03*
X1284016Y919500D03*
X1280392Y933598D03*
X1272044Y1171120D03*
X1299009Y168697D03*
X1299204Y191941D03*
X1301173Y224321D03*
X1295516Y326500D03*
Y337000D03*
Y330000D03*
Y333500D03*
X1302357Y470382D03*
X1288016Y819500D03*
Y839500D03*
Y843500D03*
Y847500D03*
Y851500D03*
Y863500D03*
Y867000D03*
X1288011Y885783D03*
X1301016Y942500D03*
X1318454Y114488D03*
X1314718Y168713D03*
X1313990Y467560D03*
Y479560D03*
X1331164Y35983D03*
X1323097Y196665D03*
Y192665D03*
X1323192Y204864D03*
X1329822Y425413D03*
X1332362Y455301D03*
Y459101D03*
Y463101D03*
X1329516Y558500D03*
Y562500D03*
Y566500D03*
X1321516D03*
X1329516Y574500D03*
Y586500D03*
Y578500D03*
Y582500D03*
X1321516D03*
Y586500D03*
X1329516Y590500D03*
Y605000D03*
X1321516Y590500D03*
X1329516Y609000D03*
Y613000D03*
Y621000D03*
X1321516Y613000D03*
X1329516Y637000D03*
Y633000D03*
Y625000D03*
Y629000D03*
X1321516D03*
Y633000D03*
Y637000D03*
X1329516Y653500D03*
Y649500D03*
X1321516Y645000D03*
X1329516Y665500D03*
Y657500D03*
X1321516D03*
X1329516Y669500D03*
X1321516Y677500D03*
Y681500D03*
Y673500D03*
X1329516D03*
Y681500D03*
Y677500D03*
Y696500D03*
Y700500D03*
X1321516Y704500D03*
X1329516D03*
Y712500D03*
Y716500D03*
X1321516Y720500D03*
Y728500D03*
Y724500D03*
X1329516Y728500D03*
Y724500D03*
Y720500D03*
X1321486Y736464D03*
X1343189Y151540D03*
X1335990Y474560D03*
X1339309Y749675D03*
Y745675D03*
Y741675D03*
Y737675D03*
Y765675D03*
Y761675D03*
Y757675D03*
Y753675D03*
Y769675D03*
Y781675D03*
X1363800Y149768D03*
X1355260Y327777D03*
Y331377D03*
Y335651D03*
Y339251D03*
Y343525D03*
Y347125D03*
Y351399D03*
Y354999D03*
X1354862Y424601D03*
Y428101D03*
Y431601D03*
X1367975Y1012325D03*
Y1016325D03*
X1359781Y1022766D03*
Y1034266D03*
X1366859Y1043140D03*
X1359781Y1030266D03*
X1366782Y1047047D03*
X1381096Y252371D03*
X1370475Y1002180D03*
Y1007180D03*
X1396190Y106495D03*
X1392874Y206864D03*
X1392045Y242078D03*
X1385066D03*
X1387967Y361371D03*
Y356871D03*
X1399750Y536726D03*
Y531726D03*
Y544726D03*
Y540726D03*
X1385602Y577192D03*
X1385603Y627817D03*
X1399516Y652000D03*
Y660000D03*
Y703000D03*
Y707000D03*
X1396475Y1031680D03*
X1401707Y250599D03*
X1409581Y478982D03*
Y483982D03*
Y487982D03*
Y499982D03*
Y491982D03*
X1411875Y597393D03*
X1401468Y629311D03*
Y625311D03*
X1412516Y689000D03*
Y705000D03*
Y713000D03*
Y709000D03*
Y733000D03*
X1412485Y720894D03*
X1412516Y749000D03*
Y753000D03*
Y757000D03*
X1412539Y765343D03*
X1408114Y815683D03*
X1408016Y832000D03*
Y828000D03*
X1407965Y823934D03*
X1407918Y819817D03*
X1408016Y848000D03*
Y840000D03*
Y836000D03*
Y852000D03*
Y864000D03*
Y856000D03*
Y880000D03*
Y868000D03*
Y884000D03*
Y896000D03*
Y900000D03*
X1411085Y992307D03*
X1415281Y1004766D03*
Y996766D03*
Y1008766D03*
X1415285Y1020250D03*
X1415281Y1030766D03*
X1405475Y1032180D03*
X1408627Y1539557D03*
X1408135Y1562235D03*
X1418530Y631212D03*
X1420516Y681000D03*
Y685000D03*
Y689000D03*
Y697000D03*
Y701000D03*
Y713000D03*
Y709000D03*
Y705000D03*
Y725000D03*
Y729000D03*
Y733000D03*
Y741000D03*
Y745000D03*
Y749000D03*
Y753000D03*
Y757000D03*
X1429516Y774500D03*
Y798500D03*
Y790500D03*
Y794500D03*
Y818500D03*
Y834500D03*
Y838500D03*
Y842500D03*
X1418230Y939292D03*
X1425097Y951563D03*
X1425037Y947595D03*
X1423281Y1000766D03*
Y1004766D03*
Y996766D03*
Y1016266D03*
Y1020266D03*
Y1030766D03*
X1423487Y1494706D03*
X1426457Y1524252D03*
X1445551Y151540D03*
X1449010Y168697D03*
X1449205Y191941D03*
X1443223Y320861D03*
Y325361D03*
Y329861D03*
Y334361D03*
Y338861D03*
Y343361D03*
Y347861D03*
Y352361D03*
Y356861D03*
X1440295Y575841D03*
X1437516Y766500D03*
Y774500D03*
Y770500D03*
Y782500D03*
Y798500D03*
Y794500D03*
Y790500D03*
Y786500D03*
Y814500D03*
Y810500D03*
Y830500D03*
Y826500D03*
Y818500D03*
Y834500D03*
Y838500D03*
Y842500D03*
X1462912Y68581D03*
Y80581D03*
X1464719Y168713D03*
X1451174Y224321D03*
X1453223Y320861D03*
Y325361D03*
Y329861D03*
Y334361D03*
Y338861D03*
Y343361D03*
Y347861D03*
Y352361D03*
X1451552Y571614D03*
Y575614D03*
X1456634Y950980D03*
X1476913Y38244D03*
X1472237Y58013D03*
X1468455Y114488D03*
X1466162Y149768D03*
X1473098Y196665D03*
Y192665D03*
X1473193Y204864D03*
X1482016Y685630D03*
X1466633Y947600D03*
X1495236Y206864D03*
X1487428Y242078D03*
X1494407D03*
X1483458Y252371D03*
X1490062Y358700D03*
Y354200D03*
X1482516Y727500D03*
X1497299Y907240D03*
X1498552Y106495D03*
X1504069Y250599D03*
X1499516Y769000D03*
Y813000D03*
X1522376Y382600D03*
Y463600D03*
X1515464Y554555D03*
Y558555D03*
Y562555D03*
X1521744Y595588D03*
Y591588D03*
X1521776Y603600D03*
X1521744Y599588D03*
X1521776Y611600D03*
Y619600D03*
X1521744Y607588D03*
X1521776Y615600D03*
Y623600D03*
Y627600D03*
Y637969D03*
Y641974D03*
X1517401Y968739D03*
X1543663Y969737D03*
X1547913Y151540D03*
X1551372Y168697D03*
X1551567Y191941D03*
X1553536Y224321D03*
X1558395Y316363D03*
Y325363D03*
X1548395Y316363D03*
Y325363D03*
X1558395Y329863D03*
Y334363D03*
Y343363D03*
X1548395Y329863D03*
Y334363D03*
Y343363D03*
X1558395Y352363D03*
X1574599Y58013D03*
X1565274Y68581D03*
Y80581D03*
X1570817Y114488D03*
X1568524Y149768D03*
X1567081Y168713D03*
X1575460Y192665D03*
Y196665D03*
X1575555Y204864D03*
X1571716Y341600D03*
X1570017Y666275D03*
X1572133Y710129D03*
X1589790Y242078D03*
X1585820Y252371D03*
X1589576Y458800D03*
X1589776Y545800D03*
X1590824Y1442557D03*
X1600914Y106495D03*
X1597598Y206864D03*
X1596769Y242078D03*
X1606431Y250599D03*
X1608813Y336252D03*
Y344252D03*
Y340252D03*
X1602040Y384718D03*
Y380718D03*
Y392718D03*
Y400718D03*
Y404718D03*
Y408718D03*
Y396718D03*
Y412718D03*
X1598376Y553700D03*
Y557700D03*
X1611118Y699917D03*
Y717817D03*
X1611418Y732417D03*
X1599382Y1468023D03*
X1603619Y1527334D03*
X1620476Y453873D03*
Y458859D03*
X1619661Y542712D03*
X1613201Y675832D03*
X1627518Y744317D03*
X1626818Y762717D03*
X1616518Y828117D03*
X1612701Y1528558D03*
X1616301Y1539358D03*
X1612401Y1535258D03*
X1631118Y711417D03*
X1638518Y728117D03*
X1640766Y881999D03*
X1641114Y917241D03*
X1640872Y952125D03*
X1650275Y151540D03*
X1653734Y168697D03*
X1653929Y191941D03*
X1655898Y224321D03*
X1648331Y871345D03*
X1648868Y909279D03*
X1648475Y942136D03*
X1676961Y58013D03*
X1667636Y68581D03*
Y80581D03*
X1673179Y114488D03*
X1670886Y149768D03*
X1669443Y168713D03*
X1677822Y192665D03*
Y196665D03*
X1677917Y204864D03*
X1692152Y242078D03*
X1688182Y252371D03*
X1686861Y545912D03*
Y626912D03*
X1703276Y106495D03*
X1699960Y206864D03*
X1699131Y242078D03*
X1708793Y250599D03*
X1695233Y306652D03*
X1718801Y458334D03*
Y450334D03*
X1715201Y1146071D03*
X1739676Y488816D03*
X1729131Y1171120D03*
X1756096Y168697D03*
X1756291Y191941D03*
X1758260Y224321D03*
X1750123Y879199D03*
X1750178Y897279D03*
X1754216Y935100D03*
X1769998Y68581D03*
Y80581D03*
X1771805Y168713D03*
X1759444Y470382D03*
X1771077Y471560D03*
Y479560D03*
X1779323Y58013D03*
X1775541Y114488D03*
X1780184Y196665D03*
Y192665D03*
X1780279Y204864D03*
X1789678Y200716D03*
X1786909Y425413D03*
X1789449Y455301D03*
Y459101D03*
Y463101D03*
X1789579Y989660D03*
X1787150Y1430956D03*
X1793077Y474560D03*
X1802065Y985060D03*
X1804887Y1082250D03*
X1795354Y1103246D03*
X1791190Y1257937D03*
X1811949Y424601D03*
Y428101D03*
Y431601D03*
X1819247Y1101145D03*
Y1105145D03*
X1809948Y1223209D03*
G54D105*
X115257Y1202289D03*
X106772Y1210774D03*
X118091Y1223388D03*
X129405Y1212075D03*
X126576Y1214903D03*
X120918Y1220560D03*
X572344Y1202289D03*
X563859Y1210774D03*
X586492Y1212075D03*
X583663Y1214903D03*
X578005Y1220560D03*
X575178Y1223388D03*
X1020945Y1210774D03*
X1029430Y1202289D03*
X1040749Y1214903D03*
X1043578Y1212075D03*
X1035091Y1220560D03*
X1032264Y1223388D03*
X1478032Y1210774D03*
X1486517Y1202289D03*
X1492178Y1220560D03*
X1497836Y1214903D03*
X1489351Y1223388D03*
X1500665Y1212075D03*
G54D12*
X13780Y1226024D03*
X79331Y1186654D03*
X390354Y1141024D03*
X536418Y1086654D03*
X854291Y1225118D03*
X993504Y1170748D03*
X1304528Y1141024D03*
X1450591Y1086654D03*
X1761614Y1215000D03*
X1827165Y1235630D03*
G54D222*
X938526Y719903D03*
X946086Y712147D03*
Y719903D03*
G54D30*
X18463Y250245D03*
Y270245D03*
X19075Y284082D03*
X25549Y250245D03*
Y270245D03*
X82918Y149414D03*
X84679Y1012213D03*
X90004Y149414D03*
X91765Y1012213D03*
X108643Y139695D03*
X127911Y250245D03*
X120825D03*
X192366Y149414D03*
X185280D03*
X211005Y139695D03*
X230273Y250245D03*
X223187D03*
X294728Y149414D03*
X287642D03*
X313367Y139695D03*
X325549Y250245D03*
X332635D03*
X408758Y471560D03*
X415844D03*
X437643Y149414D03*
X444729D03*
X463368Y139695D03*
X482636Y250245D03*
X475550D03*
X540005Y149414D03*
X547091D03*
X548852Y1012213D03*
X541766D03*
X565730Y139695D03*
X584998Y250245D03*
X577912D03*
X649453Y149414D03*
X642367D03*
X668092Y139695D03*
X680274Y250245D03*
X687360D03*
X744729Y149414D03*
X751815D03*
X770454Y139695D03*
X782636Y250245D03*
X789722D03*
X879997Y483303D03*
X872911D03*
X894729Y149414D03*
X901815D03*
X920454Y139695D03*
X1004177Y149414D03*
X997091D03*
X1005938Y1012213D03*
X998852D03*
X1022816Y139695D03*
X1042084Y250245D03*
X1034998D03*
X1106539Y149414D03*
X1099453D03*
X1125178Y139695D03*
X1137360Y250245D03*
X1144446D03*
X1201815Y149414D03*
X1208901D03*
X1227540Y139695D03*
X1246808Y250245D03*
X1239722D03*
X1267792Y905324D03*
X1274878D03*
X1330017Y471560D03*
X1322931D03*
X1351816Y149414D03*
X1358902D03*
X1377541Y139695D03*
X1396809Y250245D03*
X1389723D03*
X1421368Y1540385D03*
X1428454D03*
X1420995Y1561025D03*
X1428081D03*
X1461264Y149414D03*
X1454178D03*
X1463025Y1012213D03*
X1455939D03*
X1479903Y139695D03*
X1492085Y250245D03*
X1499171D03*
X1556540Y149414D03*
X1563626D03*
X1582265Y139695D03*
X1594447Y250245D03*
X1601533D03*
X1627155Y702883D03*
Y720783D03*
X1627455Y735383D03*
Y753583D03*
X1623741Y777783D03*
X1616655D03*
X1623541Y790483D03*
X1616455D03*
X1623241Y804583D03*
X1616155D03*
X1623341Y818683D03*
X1616255D03*
X1634241Y702883D03*
Y720783D03*
X1634541Y735383D03*
Y753583D03*
X1658902Y149414D03*
X1665988D03*
X1684627Y139695D03*
X1703895Y250245D03*
X1696809D03*
X1787104Y471560D03*
X1780018D03*
X1790264Y1443715D03*
X1783178D03*
X1790141Y1475905D03*
X1783055D03*
G54D240*
X980085Y1480881D03*
Y1498597D03*
X1017867Y1480881D03*
Y1498597D03*
G54D204*
X857781Y1443730D03*
Y1461448D03*
X871561Y1443730D03*
Y1461448D03*
X899781Y1443730D03*
Y1461448D03*
X913561Y1443730D03*
Y1461448D03*
G54D123*
X360727Y453485D03*
X466821Y467960D03*
X817813Y447485D03*
X1274900Y453485D03*
X1731987D03*
G54D141*
X414519Y1251852D03*
Y1264254D03*
X512830Y1251852D03*
Y1264254D03*
X1328693Y1251852D03*
Y1264254D03*
X1427004Y1251852D03*
Y1264254D03*
G54D231*
X941610Y1459592D03*
X967768Y1459845D03*
X990834D03*
X1013866Y1459945D03*
X1036752Y1460061D03*
G54D132*
X409284Y745280D03*
X407316D03*
X405347D03*
X403379D03*
X401410D03*
X399442D03*
X397473D03*
X395505D03*
X393536D03*
X423064D03*
X421095D03*
X419127D03*
X417158D03*
X415190D03*
X413221D03*
X411253D03*
X1772142Y877880D03*
X1770173D03*
X1768205D03*
X1766236D03*
X1789858D03*
X1787890D03*
X1785921D03*
X1783953D03*
X1781984D03*
X1780016D03*
X1778047D03*
X1776079D03*
X1774110D03*
X1795764D03*
X1793795D03*
X1791827D03*
G54D213*
X887193Y564037D03*
X889161D03*
X891130D03*
X893098D03*
X895067D03*
Y594549D03*
X893098D03*
X891130D03*
X889161D03*
X887193D03*
X910815Y564037D03*
X908846D03*
X906878D03*
X904909D03*
X899004D03*
X897035D03*
X902941D03*
X900972D03*
X912783D03*
Y594549D03*
X910815D03*
X900972D03*
X899004D03*
X897035D03*
X908846D03*
X906878D03*
X904909D03*
X902941D03*
X1009555Y316659D03*
Y347171D03*
X1011523Y316659D03*
X1013492D03*
X1015460D03*
X1017429D03*
X1019397D03*
X1021366D03*
X1023334D03*
X1025303D03*
X1015460Y347171D03*
X1013492D03*
X1025303D03*
X1023334D03*
X1021366D03*
X1019397D03*
X1017429D03*
X1011523D03*
X1031208Y316659D03*
X1027271D03*
X1029240D03*
X1033177D03*
X1035145D03*
Y347171D03*
X1033177D03*
X1031208D03*
X1029240D03*
X1027271D03*
G54D114*
X190325Y368760D03*
X279360Y636752D03*
X647411Y368760D03*
X736446Y636752D03*
X1104498Y368760D03*
X1193533Y636752D03*
X1561585Y368760D03*
X1650620Y636752D03*
G54D133*
X408300Y762800D03*
X1781000Y895400D03*
G54D22*
X9272Y105001D03*
X16773Y242078D03*
X12803Y248371D03*
X16773Y262078D03*
X12803Y268371D03*
X12173Y1496782D03*
X9515Y1556883D03*
X25879Y51296D03*
Y55305D03*
X29787Y67527D03*
Y63527D03*
Y59527D03*
X27897Y106495D03*
X32415Y177448D03*
X24581Y206864D03*
X23752Y242078D03*
Y262078D03*
X33414Y250599D03*
Y270599D03*
X26537Y292608D03*
X34753Y281272D03*
X31457Y536726D03*
Y531726D03*
Y552726D03*
Y540726D03*
Y544726D03*
X33175Y629311D03*
Y625311D03*
X48384Y177606D03*
X41288Y478982D03*
Y483982D03*
Y487982D03*
Y499982D03*
Y491982D03*
X43582Y597393D03*
X50237Y631212D03*
X43674Y1093757D03*
X42510Y1248448D03*
X59232Y847718D03*
X53207Y1072761D03*
X67567Y1091656D03*
X61268Y1213720D03*
X65386Y1544571D03*
X77258Y151540D03*
X80717Y168697D03*
X80912Y191941D03*
X82881Y224321D03*
X83259Y571614D03*
Y575614D03*
X72002Y575841D03*
X81797Y686107D03*
X71718Y843118D03*
X97869Y149768D03*
X104805Y192665D03*
Y196665D03*
X104900Y204864D03*
X115165Y252371D03*
X130268Y106495D03*
X126943Y206864D03*
X119135Y242078D03*
X126114D03*
X135776Y250599D03*
X147171Y554555D03*
Y558555D03*
Y562555D03*
X154083Y382600D03*
Y463600D03*
X153451Y595588D03*
Y591588D03*
X153483Y603600D03*
X153451Y599588D03*
X153483Y611600D03*
Y619600D03*
X153451Y607588D03*
X153483Y615600D03*
Y623600D03*
Y627600D03*
Y637969D03*
Y641974D03*
X179620Y151540D03*
X196981Y68581D03*
Y80581D03*
X183079Y168697D03*
X183274Y191941D03*
X185243Y224321D03*
X206306Y58013D03*
X202524Y114488D03*
X200231Y149768D03*
X207167Y196665D03*
Y192665D03*
X207262Y204864D03*
X229305Y206864D03*
X221497Y242078D03*
X228476D03*
X217527Y252371D03*
X221283Y458800D03*
X230083Y553700D03*
X221483Y545800D03*
X230083Y557700D03*
X230527Y1474522D03*
X230526Y1478442D03*
Y1486442D03*
X232621Y106495D03*
X238138Y250599D03*
X233747Y384718D03*
Y380718D03*
Y392718D03*
Y396718D03*
Y400718D03*
Y404718D03*
Y408718D03*
Y412718D03*
X244908Y675832D03*
X232526Y1510442D03*
X232531Y1518578D03*
X252183Y453873D03*
Y458859D03*
X251368Y542712D03*
X249369Y816300D03*
X248369Y836800D03*
X249368Y1506058D03*
X251668Y1517958D03*
X281982Y151540D03*
X285441Y168697D03*
X285636Y191941D03*
X287605Y224321D03*
X312164Y35007D03*
X308668Y58013D03*
X299343Y68581D03*
Y80581D03*
X304886Y114488D03*
X302593Y149768D03*
X309529Y192665D03*
Y196665D03*
X309624Y204864D03*
X323859Y242078D03*
X319889Y252371D03*
X326940Y306652D03*
X318568Y545912D03*
Y626912D03*
X334983Y106495D03*
X331667Y206864D03*
X330838Y242078D03*
X340500Y250599D03*
X350508Y458334D03*
Y450334D03*
X346908Y1146071D03*
X360881Y1170370D03*
X354250Y1191599D03*
X371383Y488816D03*
X377369Y764500D03*
X366951Y943480D03*
X375915Y959812D03*
Y955812D03*
Y951812D03*
Y963812D03*
Y967812D03*
Y971812D03*
X387803Y168697D03*
X387998Y191941D03*
X389967Y224321D03*
X391151Y470382D03*
X379069Y745300D03*
X392678Y868286D03*
X387500Y1547700D03*
Y1555700D03*
X407248Y114488D03*
X407039Y331589D03*
Y335589D03*
X402784Y467560D03*
Y479560D03*
X405871Y889786D03*
X407448Y1446807D03*
X419958Y35983D03*
X411891Y192665D03*
Y196665D03*
X411986Y204864D03*
X418616Y425413D03*
X421156Y455301D03*
Y459101D03*
Y463101D03*
X424784Y474560D03*
X414272Y889551D03*
X413684Y1523296D03*
X431983Y151540D03*
X427099Y1537088D03*
X427619Y1550211D03*
X452594Y149768D03*
X455642Y328285D03*
Y324685D03*
Y344033D03*
Y340433D03*
Y336159D03*
Y332559D03*
Y351907D03*
Y348307D03*
X443656Y424601D03*
Y428101D03*
Y431601D03*
X456602Y464809D03*
Y472809D03*
X445923Y508999D03*
X453460Y638279D03*
X456768Y1012325D03*
Y1016325D03*
X448574Y1022766D03*
Y1034266D03*
Y1030266D03*
X455652Y1043140D03*
X455575Y1047047D03*
X473860Y242078D03*
X469890Y252371D03*
X465886Y495669D03*
Y516609D03*
X459268Y1002180D03*
Y1007180D03*
X484984Y106495D03*
X481668Y206864D03*
X480839Y242078D03*
X490501Y250599D03*
X488393Y387089D03*
Y391589D03*
X488543Y536726D03*
Y531726D03*
Y544726D03*
Y540726D03*
X490261Y629311D03*
Y625311D03*
X481845Y652906D03*
X485268Y1031680D03*
X498374Y478982D03*
Y483982D03*
Y487982D03*
Y499982D03*
Y491982D03*
X500668Y597393D03*
X507323Y631212D03*
X502586Y660441D03*
X504074Y1004766D03*
Y996766D03*
Y1008766D03*
X503941Y1020258D03*
X504074Y1030766D03*
X494268Y1032180D03*
X518690Y749443D03*
X508077Y989235D03*
X512074Y1000766D03*
Y1004766D03*
Y996766D03*
Y1016266D03*
Y1020266D03*
Y1030766D03*
X534345Y151540D03*
X537804Y168697D03*
X537999Y191941D03*
X539968Y224321D03*
X538669Y345723D03*
Y359223D03*
Y354723D03*
Y350223D03*
Y363723D03*
Y377223D03*
Y372723D03*
Y368223D03*
Y386223D03*
Y390723D03*
X529088Y575841D03*
X535507Y779889D03*
X532169Y840700D03*
X551706Y68581D03*
Y80581D03*
X554956Y149768D03*
X548669Y345723D03*
Y350223D03*
Y359223D03*
Y354723D03*
Y377223D03*
Y372723D03*
Y368223D03*
Y363723D03*
Y381723D03*
X540345Y571614D03*
Y575614D03*
X552956Y684509D03*
Y700509D03*
Y688509D03*
Y692509D03*
Y696509D03*
Y704509D03*
Y708509D03*
Y712509D03*
Y716509D03*
Y720509D03*
X555609Y841388D03*
X561031Y58013D03*
X557249Y114488D03*
X561892Y192665D03*
Y196665D03*
X561987Y204864D03*
X572252Y252371D03*
X570486Y747079D03*
X587346Y106495D03*
X584030Y206864D03*
X583201Y242078D03*
X576222D03*
X588772Y957207D03*
X576286Y961807D03*
X588415Y1509687D03*
X592863Y250599D03*
X604257Y554555D03*
Y558555D03*
Y562555D03*
X597968Y1493658D03*
Y1497558D03*
X598068Y1501458D03*
X594164Y1505794D03*
X611169Y382600D03*
Y463600D03*
X610537Y595588D03*
Y591588D03*
X610569Y603600D03*
X610537Y599588D03*
X610569Y611600D03*
Y619600D03*
X610537Y607588D03*
X610569Y615600D03*
Y623600D03*
Y627600D03*
Y637969D03*
Y641974D03*
X636707Y151540D03*
X640166Y168697D03*
X640361Y191941D03*
X642330Y224321D03*
X663393Y58013D03*
X654068Y68581D03*
Y80581D03*
X659611Y114488D03*
X657318Y149768D03*
X664254Y192665D03*
Y196665D03*
X664349Y204864D03*
X658810Y666275D03*
X660926Y710129D03*
X678584Y242078D03*
X685563D03*
X674614Y252371D03*
X678369Y458800D03*
X678569Y545800D03*
Y558800D03*
Y562800D03*
X689708Y106495D03*
X686392Y206864D03*
X695225Y250599D03*
X690833Y384718D03*
Y380718D03*
Y392718D03*
Y396718D03*
Y400718D03*
Y404718D03*
Y408718D03*
Y412718D03*
X687169Y553700D03*
Y557700D03*
X701994Y675832D03*
X709269Y453873D03*
Y458859D03*
X708454Y542712D03*
X716258Y696718D03*
X713333Y783453D03*
X727829Y756137D03*
Y764137D03*
X720179Y779958D03*
X727829Y768137D03*
Y772137D03*
X739069Y151540D03*
X742528Y168697D03*
X742723Y191941D03*
X744692Y224321D03*
X735883Y1606600D03*
X735234Y1634485D03*
X735250Y1630030D03*
X765755Y58013D03*
X756430Y68581D03*
Y80581D03*
X761973Y114488D03*
X759680Y149768D03*
X766616Y196665D03*
Y192665D03*
X766711Y204864D03*
X780946Y242078D03*
X776976Y252371D03*
X775654Y545912D03*
Y626912D03*
X783232Y1427432D03*
Y1431432D03*
Y1439432D03*
X781486Y1458066D03*
X774615Y1449870D03*
X792070Y106495D03*
X788754Y206864D03*
X787925Y242078D03*
X797587Y250599D03*
X784026Y306652D03*
X784575Y442498D03*
X784607Y450510D03*
Y446510D03*
X799327Y1436559D03*
X807594Y444334D03*
Y452334D03*
X811807Y836919D03*
X815307Y893419D03*
X803995Y1146071D03*
X806327Y1436559D03*
X807988Y1476616D03*
X828469Y483816D03*
X829983Y758500D03*
Y762500D03*
Y780500D03*
Y776500D03*
Y794500D03*
Y798500D03*
Y812500D03*
Y816500D03*
X822217Y830038D03*
X819807Y900919D03*
X817925Y1171120D03*
X844890Y168697D03*
X845085Y191941D03*
X847054Y224321D03*
X848237Y465382D03*
X845768Y831558D03*
X839299Y839953D03*
X845840Y839292D03*
X842941Y879459D03*
X845728Y875507D03*
X843251Y871459D03*
X842941Y883459D03*
X844161Y892564D03*
X842848Y887490D03*
X837983Y901500D03*
X845214Y1440859D03*
X834187Y1444849D03*
X845227Y1448959D03*
Y1444959D03*
Y1457959D03*
X858792Y68581D03*
Y80581D03*
X864335Y114488D03*
X863744Y713170D03*
Y705170D03*
X864483Y768000D03*
Y786000D03*
Y804000D03*
Y822000D03*
X856711Y831469D03*
X856742Y843459D03*
Y847459D03*
Y839459D03*
Y863459D03*
Y859459D03*
Y855459D03*
Y851459D03*
Y867459D03*
Y879459D03*
Y875459D03*
Y871459D03*
Y892959D03*
Y883459D03*
Y887759D03*
X868117Y58013D03*
X868978Y192665D03*
Y196665D03*
X869073Y204864D03*
X875567Y337342D03*
X866937Y491303D03*
Y479303D03*
X872551Y554703D03*
Y558703D03*
Y574703D03*
Y586828D03*
X871977Y698388D03*
X889069Y151540D03*
X883460Y309368D03*
Y305368D03*
Y313368D03*
Y325368D03*
Y321368D03*
Y317368D03*
Y329368D03*
Y337342D03*
Y333368D03*
X888937Y486303D03*
X895483Y529633D03*
X881744Y686970D03*
Y698970D03*
X886744Y718570D03*
X890364Y1102760D03*
X886200Y1257451D03*
X886727Y1440859D03*
Y1448859D03*
Y1464859D03*
X886702Y1452663D03*
X886727Y1472859D03*
X909680Y149768D03*
X902243Y362369D03*
Y370369D03*
X913636Y547348D03*
X909944Y683770D03*
Y695770D03*
Y699770D03*
X899897Y1081764D03*
X904958Y1222723D03*
X919828Y304585D03*
X913942Y441754D03*
X916482Y471642D03*
Y479442D03*
Y475442D03*
X929135Y561578D03*
Y565578D03*
X929119Y585578D03*
Y589578D03*
X929135Y594329D03*
Y598329D03*
X923933Y704111D03*
X914257Y1104659D03*
Y1100659D03*
X924711Y1472100D03*
X942070Y106495D03*
X939420Y192035D03*
X945626Y236866D03*
X930635Y305255D03*
X941660Y351281D03*
X938982Y440942D03*
Y444442D03*
Y447942D03*
X945630Y536726D03*
Y531726D03*
Y544726D03*
Y540726D03*
X939353Y883790D03*
X939355Y887508D03*
X947572Y316739D03*
X955461Y478982D03*
Y483982D03*
Y487982D03*
Y499982D03*
Y491982D03*
X957755Y597393D03*
X947348Y629311D03*
Y625311D03*
X952667Y792505D03*
X957540Y846665D03*
X950626Y846635D03*
X947753Y878216D03*
X956181Y870278D03*
X947897Y899890D03*
X954341Y1102760D03*
X950177Y1257451D03*
X964410Y631212D03*
X963874Y1081764D03*
X978234Y1100659D03*
Y1104659D03*
X968935Y1222723D03*
X991431Y151540D03*
X982608Y338972D03*
X981089Y343112D03*
X982608Y331972D03*
X981089Y346612D03*
X986175Y575841D03*
X982604Y848597D03*
X984686Y837159D03*
X986918Y1104622D03*
X986955Y1100302D03*
X1008792Y68581D03*
Y80581D03*
X994890Y168697D03*
X995085Y191941D03*
X997054Y224321D03*
X997432Y571614D03*
Y575614D03*
X1018117Y58013D03*
X1014335Y114488D03*
X1012042Y149768D03*
X1018978Y196665D03*
Y192665D03*
X1011654Y196620D03*
X1019073Y204864D03*
X1018186Y837659D03*
X1017902Y958822D03*
X1013991Y1353714D03*
X1013944Y1363533D03*
X1013966Y1372734D03*
X1013961Y1376752D03*
X1041116Y206864D03*
X1033308Y242078D03*
X1040287D03*
X1029338Y252371D03*
X1032971Y847222D03*
X1030388Y954222D03*
X1044432Y106495D03*
X1049949Y250599D03*
X1058708Y314539D03*
Y322843D03*
Y328156D03*
Y319243D03*
X1058595Y339509D03*
X1058708Y331756D03*
X1058187Y360151D03*
Y364276D03*
X1068256Y382600D03*
Y463600D03*
X1061344Y554555D03*
Y558555D03*
Y562555D03*
X1067624Y595588D03*
Y591588D03*
X1067656Y603600D03*
X1067624Y599588D03*
X1067656Y611600D03*
Y619600D03*
X1067624Y607588D03*
X1067656Y615600D03*
Y623600D03*
Y627600D03*
Y637969D03*
Y641974D03*
X1093793Y151540D03*
X1097252Y168697D03*
X1097447Y191941D03*
X1099416Y224321D03*
X1120479Y58013D03*
X1111154Y68581D03*
Y80581D03*
X1116697Y114488D03*
X1114404Y149768D03*
X1112961Y168713D03*
X1121340Y192665D03*
Y196665D03*
X1121435Y204864D03*
X1120483Y329000D03*
Y334000D03*
Y339000D03*
X1115897Y666275D03*
X1118013Y710129D03*
X1135670Y242078D03*
X1131700Y252371D03*
X1128983Y329000D03*
Y334000D03*
Y339000D03*
X1135456Y458800D03*
X1135656Y545800D03*
Y558800D03*
Y562800D03*
X1146794Y106495D03*
X1143478Y206864D03*
X1142649Y242078D03*
X1152311Y250599D03*
X1147920Y392718D03*
Y384718D03*
Y380718D03*
Y404718D03*
Y408718D03*
Y396718D03*
Y400718D03*
Y412718D03*
X1144256Y553700D03*
Y557700D03*
X1166356Y453873D03*
Y458859D03*
X1165541Y542712D03*
X1159081Y675832D03*
X1187067Y324142D03*
X1177653Y774434D03*
X1196155Y151540D03*
X1199614Y168697D03*
X1199809Y191941D03*
X1201778Y224321D03*
X1191947Y329398D03*
X1213516Y68581D03*
Y80581D03*
X1219059Y114488D03*
X1216766Y149768D03*
X1215323Y168713D03*
X1222841Y58013D03*
X1223702Y192665D03*
Y196665D03*
X1223797Y204864D03*
X1238032Y242078D03*
X1234062Y252371D03*
X1232741Y545912D03*
Y626912D03*
X1249156Y106495D03*
X1245840Y206864D03*
X1245011Y242078D03*
X1254673Y250599D03*
X1241113Y306652D03*
X1260983Y336000D03*
X1264681Y450334D03*
Y458334D03*
X1264677Y894866D03*
X1261081Y1146071D03*
X1255923Y1192376D03*
X1260168Y1523458D03*
X1260129Y1527334D03*
X1260168Y1543558D03*
X1260129Y1531334D03*
Y1539334D03*
X1260153Y1535385D03*
X1285556Y488816D03*
X1284997Y768576D03*
Y780576D03*
X1276654Y848145D03*
X1276750Y864487D03*
Y859487D03*
X1276738Y852029D03*
X1276750Y874487D03*
Y869487D03*
Y879487D03*
Y889487D03*
Y884487D03*
X1286983Y919500D03*
X1283359Y933598D03*
X1275011Y1171120D03*
X1301976Y168697D03*
X1302171Y191941D03*
X1298483Y326500D03*
Y337000D03*
Y330000D03*
Y333500D03*
X1290983Y819500D03*
Y839500D03*
Y843500D03*
Y847500D03*
Y851500D03*
Y863500D03*
Y867000D03*
X1290978Y885783D03*
X1317685Y168713D03*
X1304140Y224321D03*
X1305324Y470382D03*
X1316957Y467560D03*
Y479560D03*
X1303983Y942500D03*
X1334131Y35983D03*
X1321421Y114488D03*
X1326064Y196665D03*
Y192665D03*
X1326159Y204864D03*
X1332789Y425413D03*
X1335329Y455301D03*
Y459101D03*
Y463101D03*
X1332483Y558500D03*
Y562500D03*
Y566500D03*
X1324483D03*
X1332483Y574500D03*
Y586500D03*
Y578500D03*
Y582500D03*
X1324483D03*
Y586500D03*
X1332483Y590500D03*
Y605000D03*
X1324483Y590500D03*
X1332483Y609000D03*
Y613000D03*
Y621000D03*
X1324483Y613000D03*
X1332483Y637000D03*
Y633000D03*
Y625000D03*
Y629000D03*
X1324483D03*
Y633000D03*
Y637000D03*
X1332483Y653500D03*
Y649500D03*
X1324483Y645000D03*
X1332483Y665500D03*
Y657500D03*
X1324483D03*
X1332483Y669500D03*
X1324483Y677500D03*
Y681500D03*
Y673500D03*
X1332483D03*
Y681500D03*
Y677500D03*
Y696500D03*
Y700500D03*
X1324483Y704500D03*
X1332483D03*
Y712500D03*
Y716500D03*
X1324483Y720500D03*
Y728500D03*
Y724500D03*
X1332483Y728500D03*
Y724500D03*
Y720500D03*
X1324453Y736464D03*
X1346156Y151540D03*
X1338957Y474560D03*
X1342276Y749675D03*
Y745675D03*
Y741675D03*
Y737675D03*
Y765675D03*
Y761675D03*
Y757675D03*
Y753675D03*
Y769675D03*
Y781675D03*
X1366767Y149768D03*
X1358227Y327777D03*
Y331377D03*
Y335651D03*
Y339251D03*
Y343525D03*
Y347125D03*
Y351399D03*
Y354999D03*
X1357829Y424601D03*
Y428101D03*
Y431601D03*
X1362748Y1022766D03*
Y1034266D03*
Y1030266D03*
X1384063Y252371D03*
X1373442Y1002180D03*
Y1007180D03*
X1370942Y1012325D03*
Y1016325D03*
X1369826Y1043140D03*
X1369749Y1047047D03*
X1399157Y106495D03*
X1395841Y206864D03*
X1395012Y242078D03*
X1388033D03*
X1390934Y361371D03*
Y356871D03*
X1388569Y577192D03*
X1388570Y627817D03*
X1399442Y1031680D03*
X1404674Y250599D03*
X1412548Y478982D03*
Y483982D03*
Y487982D03*
Y499982D03*
Y491982D03*
X1402717Y536726D03*
Y531726D03*
Y544726D03*
Y540726D03*
X1414842Y597393D03*
X1404435Y629311D03*
Y625311D03*
X1402483Y652000D03*
Y660000D03*
X1415483Y689000D03*
X1402483Y703000D03*
Y707000D03*
X1415483Y705000D03*
Y713000D03*
Y709000D03*
Y733000D03*
X1415452Y720894D03*
X1415483Y749000D03*
Y753000D03*
Y757000D03*
X1415506Y765343D03*
X1411081Y815683D03*
X1410983Y832000D03*
Y828000D03*
X1410932Y823934D03*
X1410885Y819817D03*
X1410983Y848000D03*
Y840000D03*
Y836000D03*
Y852000D03*
Y864000D03*
Y856000D03*
Y880000D03*
Y868000D03*
Y884000D03*
Y896000D03*
Y900000D03*
X1414052Y992307D03*
X1408442Y1032180D03*
X1411594Y1539557D03*
X1411102Y1562235D03*
X1421497Y631212D03*
X1423483Y681000D03*
Y685000D03*
Y689000D03*
Y697000D03*
Y701000D03*
Y713000D03*
Y709000D03*
Y705000D03*
Y725000D03*
Y729000D03*
Y733000D03*
Y741000D03*
Y745000D03*
Y749000D03*
Y753000D03*
Y757000D03*
X1432483Y774500D03*
Y798500D03*
Y790500D03*
Y794500D03*
Y818500D03*
Y834500D03*
Y838500D03*
Y842500D03*
X1421197Y939292D03*
X1428064Y951563D03*
X1428004Y947595D03*
X1418248Y1004766D03*
X1426248Y1000766D03*
X1418248Y996766D03*
Y1008766D03*
X1426248Y1004766D03*
Y996766D03*
Y1016266D03*
X1418252Y1020250D03*
X1426248Y1020266D03*
X1418248Y1030766D03*
X1426248D03*
X1426454Y1494706D03*
X1429424Y1524252D03*
X1448518Y151540D03*
X1446190Y320861D03*
Y325361D03*
Y329861D03*
Y334361D03*
Y338861D03*
Y343361D03*
Y347861D03*
Y352361D03*
Y356861D03*
X1443262Y575841D03*
X1440483Y766500D03*
Y774500D03*
Y770500D03*
Y782500D03*
Y798500D03*
Y794500D03*
Y790500D03*
Y786500D03*
Y814500D03*
Y810500D03*
Y830500D03*
Y826500D03*
Y818500D03*
Y834500D03*
Y838500D03*
Y842500D03*
X1465879Y68581D03*
Y80581D03*
X1451977Y168697D03*
X1452172Y191941D03*
X1454141Y224321D03*
X1456190Y320861D03*
Y325361D03*
Y329861D03*
Y334361D03*
Y338861D03*
Y343361D03*
Y347861D03*
Y352361D03*
X1454519Y571614D03*
Y575614D03*
X1459601Y950980D03*
X1479880Y38244D03*
X1475204Y58013D03*
X1471422Y114488D03*
X1469129Y149768D03*
X1467686Y168713D03*
X1476065Y196665D03*
Y192665D03*
X1476160Y204864D03*
X1469600Y947600D03*
X1498203Y206864D03*
X1490395Y242078D03*
X1497374D03*
X1486425Y252371D03*
X1493029Y358700D03*
Y354200D03*
X1484983Y685630D03*
X1485483Y727500D03*
X1501519Y106495D03*
X1507036Y250599D03*
X1502483Y769000D03*
Y813000D03*
X1500266Y907240D03*
X1525343Y382600D03*
Y463600D03*
X1518431Y554555D03*
Y558555D03*
Y562555D03*
X1524711Y595588D03*
Y591588D03*
X1524743Y603600D03*
X1524711Y599588D03*
X1524743Y611600D03*
Y619600D03*
X1524711Y607588D03*
X1524743Y615600D03*
Y623600D03*
Y627600D03*
Y637969D03*
Y641974D03*
X1520368Y968739D03*
X1546630Y969737D03*
X1550880Y151540D03*
X1554339Y168697D03*
X1554534Y191941D03*
X1556503Y224321D03*
X1561362Y316363D03*
Y325363D03*
X1551362Y316363D03*
Y325363D03*
X1561362Y329863D03*
Y334363D03*
Y343363D03*
X1551362Y329863D03*
Y334363D03*
Y343363D03*
X1561362Y352363D03*
X1577566Y58013D03*
X1568241Y68581D03*
Y80581D03*
X1573784Y114488D03*
X1571491Y149768D03*
X1570048Y168713D03*
X1578427Y192665D03*
Y196665D03*
X1578522Y204864D03*
X1574683Y341600D03*
X1572984Y666275D03*
X1575100Y710129D03*
X1592757Y242078D03*
X1588787Y252371D03*
X1592543Y458800D03*
X1592743Y545800D03*
X1593791Y1442557D03*
X1603881Y106495D03*
X1600565Y206864D03*
X1599736Y242078D03*
X1609398Y250599D03*
X1611780Y336252D03*
Y344252D03*
Y340252D03*
X1605007Y384718D03*
Y380718D03*
Y392718D03*
Y400718D03*
Y404718D03*
Y408718D03*
Y396718D03*
Y412718D03*
X1601343Y553700D03*
Y557700D03*
X1602349Y1468023D03*
X1606586Y1527334D03*
X1623443Y453873D03*
Y458859D03*
X1622628Y542712D03*
X1616168Y675832D03*
X1614085Y699917D03*
Y717817D03*
X1614385Y732417D03*
X1619485Y828117D03*
X1615668Y1528558D03*
X1619268Y1539358D03*
X1615368Y1535258D03*
X1634085Y711417D03*
X1641485Y728117D03*
X1630485Y744317D03*
X1629785Y762717D03*
X1643733Y881999D03*
X1644081Y917241D03*
X1643839Y952125D03*
X1653242Y151540D03*
X1656701Y168697D03*
X1656896Y191941D03*
X1658865Y224321D03*
X1651298Y871345D03*
X1651835Y909279D03*
X1651442Y942136D03*
X1670603Y68581D03*
Y80581D03*
X1676146Y114488D03*
X1673853Y149768D03*
X1672410Y168713D03*
X1679928Y58013D03*
X1680789Y192665D03*
Y196665D03*
X1680884Y204864D03*
X1691149Y252371D03*
X1689828Y545912D03*
Y626912D03*
X1706243Y106495D03*
X1702927Y206864D03*
X1695119Y242078D03*
X1702098D03*
X1698200Y306652D03*
X1711760Y250599D03*
X1721768Y458334D03*
Y450334D03*
X1718168Y1146071D03*
X1732098Y1171120D03*
X1742643Y488816D03*
X1753090Y879199D03*
X1753145Y897279D03*
X1757183Y935100D03*
X1772965Y68581D03*
Y80581D03*
X1759063Y168697D03*
X1759258Y191941D03*
X1761227Y224321D03*
X1762411Y470382D03*
X1774044Y471560D03*
Y479560D03*
X1782290Y58013D03*
X1778508Y114488D03*
X1774772Y168713D03*
X1783151Y196665D03*
Y192665D03*
X1783246Y204864D03*
X1789876Y425413D03*
X1790117Y1430956D03*
X1792645Y200716D03*
X1792416Y455301D03*
Y459101D03*
Y463101D03*
X1796044Y474560D03*
X1805032Y985060D03*
X1792546Y989660D03*
X1798321Y1103246D03*
X1794157Y1257937D03*
X1814916Y424601D03*
Y428101D03*
Y431601D03*
X1807854Y1082250D03*
X1822214Y1101145D03*
Y1105145D03*
X1812915Y1223209D03*
G54D106*
X117356Y1204388D03*
X108871Y1212873D03*
X131504Y1214174D03*
X128675Y1217002D03*
X123017Y1222659D03*
X120190Y1225487D03*
X565958Y1212873D03*
X574443Y1204388D03*
X588591Y1214174D03*
X585762Y1217002D03*
X580104Y1222659D03*
X577277Y1225487D03*
X1023044Y1212873D03*
X1031529Y1204388D03*
X1042848Y1217002D03*
X1037190Y1222659D03*
X1034363Y1225487D03*
X1045677Y1214174D03*
X1480131Y1212873D03*
X1488616Y1204388D03*
X1494277Y1222659D03*
X1491450Y1225487D03*
X1502764Y1214174D03*
X1499935Y1217002D03*
G54D250*
X1045145Y812262D03*
Y825844D03*
G54D223*
X939314Y712147D03*
G54D160*
X440114Y339287D03*
Y337713D03*
Y344012D03*
Y332988D03*
Y342437D03*
Y340862D03*
Y336138D03*
Y334563D03*
Y331413D03*
Y329839D03*
Y347161D03*
Y345587D03*
X1342699Y342379D03*
Y340805D03*
Y336080D03*
Y343954D03*
Y339230D03*
Y337655D03*
Y334505D03*
Y332931D03*
Y347104D03*
Y350253D03*
Y348679D03*
Y345529D03*
G54D241*
X990699Y783295D03*
X993258D03*
X990699Y806295D03*
X993258D03*
X1006053Y783295D03*
X998376D03*
X1003494D03*
X1000935D03*
X995817D03*
X998376Y806295D03*
X995817D03*
X1000935D03*
X1006053D03*
X1003494D03*
G54D13*
X19685Y-83298D03*
X26789Y1373669D03*
X19685Y1801195D03*
X184851Y334492D03*
X235433Y1580079D03*
Y1626339D03*
X581890Y1580079D03*
Y1626339D03*
X1259055Y1580079D03*
Y1626339D03*
X1605512Y1580079D03*
Y1626339D03*
X1796847Y1517889D03*
X1809883Y120792D03*
X1821260Y-83298D03*
Y1801195D03*
G54D232*
X942586Y1477022D03*
Y1498282D03*
G54D40*
X20079Y1433831D03*
X12599D03*
X16339Y1441705D03*
X20041Y1449735D03*
X12561D03*
X16301Y1457609D03*
X1056934Y1443022D03*
X1053194Y1450896D03*
X1060674D03*
G54D214*
X888691Y684403D03*
X897291D03*
X918361Y720570D03*
X926961D03*
G54D142*
X397498Y1539978D03*
Y1538009D03*
Y1541947D03*
Y1545883D03*
Y1543915D03*
Y1549821D03*
Y1547852D03*
X416494Y1543915D03*
Y1541947D03*
Y1538009D03*
Y1545883D03*
Y1539978D03*
Y1547852D03*
Y1549821D03*
X911845Y359317D03*
Y357348D03*
Y361286D03*
Y369160D03*
Y367191D03*
Y365222D03*
Y363254D03*
X930841Y357348D03*
Y359317D03*
Y363254D03*
Y361286D03*
Y367191D03*
Y365222D03*
Y369160D03*
G54D124*
X356790Y454076D03*
Y456044D03*
Y458012D03*
X364664D03*
Y456044D03*
Y454076D03*
X470758Y472487D03*
Y470519D03*
Y468551D03*
X462884Y472487D03*
Y470519D03*
Y468551D03*
X813876Y452012D03*
Y450044D03*
Y448076D03*
X821750Y452012D03*
Y450044D03*
Y448076D03*
X1270963Y458012D03*
Y456044D03*
Y454076D03*
X1278837Y458012D03*
Y456044D03*
Y454076D03*
X1735924Y458012D03*
Y456044D03*
Y454076D03*
X1728050Y458012D03*
Y456044D03*
Y454076D03*
G54D205*
X855812Y1445699D03*
Y1459479D03*
X873530Y1445699D03*
Y1459479D03*
X897812Y1445699D03*
Y1459479D03*
X915530Y1445699D03*
Y1459479D03*
G54D31*
X12804Y252371D03*
Y272371D03*
X11394Y284118D03*
X19363Y1464612D03*
X19274Y1496782D03*
X15691Y1501619D03*
X32082Y97667D03*
X27898Y102495D03*
X33811Y241681D03*
X34754Y289272D03*
Y285272D03*
X31458Y527726D03*
Y548726D03*
X33176Y621311D03*
X41024Y177606D03*
X41289Y495982D03*
X52508Y688473D03*
X38214Y1078372D03*
X44869Y1193263D03*
X51908Y1192250D03*
X63287Y483388D03*
X53477Y529269D03*
X60176Y608311D03*
X59233Y843118D03*
X67568Y1071656D03*
Y1075656D03*
Y1067656D03*
Y1083656D03*
Y1087656D03*
Y1079656D03*
X54647Y1124923D03*
X61269Y1209720D03*
X54395Y1213709D03*
X81229Y141247D03*
X77259Y147540D03*
X88208Y141247D03*
X97870Y145768D03*
X87598Y678107D03*
Y682107D03*
X94495Y1021177D03*
X87200Y1021048D03*
X104806Y172665D03*
Y180665D03*
Y176665D03*
Y168665D03*
Y184665D03*
Y188665D03*
X104901Y200864D03*
Y208864D03*
Y212864D03*
Y216864D03*
Y221864D03*
X104898Y225719D03*
X115166Y248371D03*
X111288Y1027361D03*
X130260Y102495D03*
X124689Y134838D03*
Y138838D03*
X134444Y97667D03*
X136173Y241681D03*
X154084Y378600D03*
Y459600D03*
X154172Y554555D03*
X154204Y562567D03*
X154172Y558555D03*
X153484Y631421D03*
X179621Y147540D03*
X186316Y80140D03*
Y76140D03*
Y84140D03*
X197027Y76587D03*
Y72587D03*
X183591Y141247D03*
X190570D03*
X200232Y145768D03*
X207168Y172665D03*
Y180665D03*
Y176665D03*
Y168665D03*
Y184665D03*
Y188665D03*
X207263Y208864D03*
Y212864D03*
Y216864D03*
Y221864D03*
X207260Y225719D03*
X227051Y134838D03*
Y138838D03*
X217528Y248371D03*
X221284Y462800D03*
X221484Y549800D03*
X230084Y549700D03*
X221484Y562800D03*
Y558800D03*
X221884Y621400D03*
Y625400D03*
X230521Y1494361D03*
X230527Y1482442D03*
Y1490442D03*
X222999Y1515642D03*
X222699Y1522542D03*
X236806Y97667D03*
X232622Y102495D03*
X238535Y241681D03*
X233748Y388718D03*
X232532Y1514578D03*
Y1526578D03*
Y1522578D03*
X252184Y445873D03*
Y449873D03*
Y462859D03*
X251369Y546712D03*
X251749Y675889D03*
X249550Y1514169D03*
Y1510142D03*
X286853Y27156D03*
X288678Y84140D03*
Y76140D03*
Y80140D03*
X281983Y147540D03*
X292932Y141247D03*
X285953D03*
X289999Y317873D03*
X299389Y76587D03*
Y72587D03*
X302594Y145768D03*
X309530Y180665D03*
Y172665D03*
Y176665D03*
Y168665D03*
Y184665D03*
X302575Y196286D03*
X309530Y188665D03*
X309625Y208864D03*
Y212864D03*
Y216864D03*
Y221864D03*
X309622Y225719D03*
X328390Y15806D03*
Y19806D03*
Y11806D03*
Y27806D03*
Y23806D03*
Y31806D03*
X319890Y248371D03*
X320392Y350850D03*
X318569Y541912D03*
Y622912D03*
X339168Y97667D03*
X334984Y102495D03*
X329413Y134838D03*
Y138838D03*
X340897Y241681D03*
X350509Y454334D03*
X353840Y1171120D03*
X364460Y406532D03*
X364804Y447357D03*
X373508Y458309D03*
Y454309D03*
Y462309D03*
X377384Y786400D03*
X375916Y939976D03*
Y943812D03*
Y947812D03*
X391040Y84140D03*
Y80140D03*
Y76140D03*
X389898Y401923D03*
X391152Y466409D03*
Y474382D03*
Y487382D03*
Y482382D03*
Y478382D03*
X379084Y750000D03*
X392654Y864408D03*
X387501Y1539700D03*
Y1543700D03*
Y1551700D03*
Y1559700D03*
X404568Y196620D03*
X402785Y471560D03*
Y475560D03*
X403684Y789000D03*
X401893Y860535D03*
Y864409D03*
X401835Y868286D03*
X399809Y948536D03*
X400004Y971780D03*
X407599Y1442942D03*
X419887Y26534D03*
X419982Y22627D03*
X419959Y30483D03*
X411892Y180665D03*
Y172665D03*
Y176665D03*
Y168665D03*
Y184665D03*
Y188665D03*
X411987Y208864D03*
Y212864D03*
Y216864D03*
Y221864D03*
X411984Y225719D03*
X419922Y834800D03*
X412174Y1098826D03*
X420188Y1523296D03*
X435954Y141247D03*
X431984Y147540D03*
X437575Y620456D03*
X427708Y1546372D03*
X434708Y1550158D03*
X452595Y145768D03*
X442933Y141247D03*
X443657Y435101D03*
Y439101D03*
Y443101D03*
Y447101D03*
Y452601D03*
X456603Y468809D03*
X446121Y620456D03*
X453461Y634279D03*
X446492Y640876D03*
X453456Y642588D03*
X445320Y711199D03*
X448575Y1026266D03*
X457075Y1024766D03*
X444302Y1098826D03*
X469891Y248371D03*
X470875Y461864D03*
X465887Y491669D03*
Y499669D03*
Y503669D03*
Y507669D03*
Y512669D03*
X489169Y97667D03*
X484985Y102495D03*
X479414Y134838D03*
Y138838D03*
X490898Y241681D03*
X478291Y347995D03*
Y352495D03*
X478394Y360089D03*
X488291Y347995D03*
Y352495D03*
X488394Y360089D03*
X478394Y364589D03*
Y369089D03*
Y373589D03*
X488394Y364589D03*
Y369089D03*
Y373589D03*
X478394Y378089D03*
Y382589D03*
Y387089D03*
Y391589D03*
X488394Y378089D03*
Y382589D03*
X479602Y468784D03*
Y472784D03*
Y476784D03*
X488544Y527726D03*
Y548726D03*
X490262Y621311D03*
X481890Y648968D03*
X477761Y1098826D03*
X498375Y495982D03*
X502664Y655149D03*
X498418Y685006D03*
Y689006D03*
Y697006D03*
Y693006D03*
X504075Y1000766D03*
Y1016266D03*
Y1012266D03*
X520373Y483388D03*
X510563Y529269D03*
X517262Y608311D03*
X509225Y844649D03*
X513754Y969933D03*
X513706Y973885D03*
X509889Y1098826D03*
X538316Y141247D03*
X534346Y147540D03*
X538670Y381723D03*
X535051Y394309D03*
X528164Y1103717D03*
X541041Y80140D03*
Y76140D03*
Y84140D03*
X551752Y76587D03*
Y72587D03*
X545295Y141247D03*
X554957Y145768D03*
X548670Y386223D03*
Y390723D03*
X555665Y738558D03*
X547686Y746514D03*
X542508Y779889D03*
X551582Y1021177D03*
X544287Y1021048D03*
X561893Y180665D03*
Y172665D03*
Y176665D03*
Y168665D03*
Y184665D03*
Y188665D03*
X561988Y208864D03*
Y212864D03*
Y216864D03*
Y221864D03*
X561985Y225719D03*
X572253Y248371D03*
X570504Y743122D03*
X564271Y754992D03*
X567829Y1026933D03*
X587347Y102495D03*
X581776Y134838D03*
Y138838D03*
X575098Y776700D03*
Y780700D03*
X576287Y957207D03*
X588416Y1497687D03*
Y1493687D03*
X585199Y1514042D03*
X588416Y1501687D03*
X584450Y1505724D03*
X575241Y1526224D03*
X591531Y97667D03*
X593260Y241681D03*
X611170Y378600D03*
Y459600D03*
X611258Y554555D03*
Y558555D03*
X611290Y562567D03*
X610570Y631421D03*
X636708Y147540D03*
X643403Y76140D03*
Y84140D03*
Y80140D03*
X647657Y141247D03*
X640678D03*
X654114Y76587D03*
Y72587D03*
X657319Y145768D03*
X664255Y180665D03*
Y172665D03*
Y176665D03*
Y168665D03*
Y184665D03*
Y188665D03*
X664350Y208864D03*
Y212864D03*
Y216864D03*
Y221864D03*
X664347Y225719D03*
X661026Y660402D03*
X665047Y689694D03*
X669830Y763137D03*
X656330Y759137D03*
Y767137D03*
Y763137D03*
X669830Y779137D03*
Y771137D03*
X656330Y779137D03*
Y775137D03*
Y771137D03*
Y783137D03*
Y787137D03*
X669830D03*
X684138Y134838D03*
Y138838D03*
X674615Y248371D03*
X678370Y462800D03*
X678570Y549800D03*
X678970Y621400D03*
Y625400D03*
X693893Y97667D03*
X689709Y102495D03*
X695622Y241681D03*
X690834Y388718D03*
X687170Y549700D03*
X709270Y445873D03*
Y449873D03*
Y462859D03*
X708455Y546712D03*
X708835Y675889D03*
X707069Y709303D03*
X710074Y728050D03*
X720273Y691609D03*
X727830Y760137D03*
X745765Y84140D03*
Y76140D03*
Y80140D03*
X750019Y141247D03*
X743040D03*
X739070Y147540D03*
X747085Y317873D03*
X739214Y1622015D03*
X756476Y72562D03*
Y76587D03*
X759681Y145768D03*
X766617Y180665D03*
Y172665D03*
Y176665D03*
Y168665D03*
Y184665D03*
Y188665D03*
X759293Y196620D03*
X766712Y200864D03*
Y208864D03*
Y212864D03*
Y216864D03*
Y221864D03*
X776977Y248371D03*
X777478Y350850D03*
X775655Y541912D03*
Y622912D03*
X783245Y1443445D03*
X783233Y1435432D03*
X774694Y1454305D03*
X796255Y97667D03*
X792071Y102495D03*
X786500Y134838D03*
Y138838D03*
X797984Y241681D03*
X791608Y442510D03*
Y450510D03*
Y446510D03*
X814961Y305368D03*
Y309368D03*
X806961Y305368D03*
Y309368D03*
X814961Y313368D03*
X806961D03*
X814961Y317368D03*
Y321368D03*
Y325368D03*
X806961Y317368D03*
Y321368D03*
Y325368D03*
X814961Y329368D03*
X806961D03*
X814961Y333368D03*
X806961Y337368D03*
Y333368D03*
X814961Y346368D03*
X806961D03*
X814961Y350368D03*
X814958Y354741D03*
X807595Y448334D03*
X811808Y840919D03*
X810927Y1171120D03*
X810113Y1404769D03*
X807978Y1484354D03*
X821867Y441389D03*
X830594Y456309D03*
Y448309D03*
Y452309D03*
X820047Y742502D03*
X829984Y766500D03*
Y784500D03*
Y802500D03*
Y820500D03*
X823461Y933571D03*
X828894Y1462461D03*
X848127Y76140D03*
Y80140D03*
Y84140D03*
X848238Y461382D03*
Y469382D03*
Y473382D03*
Y482382D03*
Y477382D03*
X841326Y827459D03*
X843748Y843790D03*
Y847490D03*
X845793Y835459D03*
Y851459D03*
X843221Y863413D03*
X843348Y855395D03*
X843221Y867413D03*
X834188Y1440849D03*
Y1448849D03*
X845228Y1461959D03*
X834206Y1454525D03*
X858838Y76587D03*
Y72587D03*
X861655Y196620D03*
X853458Y414760D03*
X864715Y414533D03*
X853458Y418760D03*
X863745Y701170D03*
Y709170D03*
X863545Y722670D03*
X864484Y756000D03*
Y760000D03*
Y764000D03*
Y778000D03*
Y782000D03*
Y774000D03*
Y792000D03*
Y796000D03*
Y800000D03*
Y814000D03*
Y810000D03*
X856815Y827468D03*
X864484Y818000D03*
X849124Y827686D03*
X856743Y835459D03*
X868979Y180665D03*
Y172665D03*
Y176665D03*
Y168665D03*
Y184665D03*
Y188665D03*
X869074Y208864D03*
Y212864D03*
Y216864D03*
Y221864D03*
X875461Y309368D03*
Y305368D03*
Y313368D03*
Y325368D03*
Y321368D03*
Y317368D03*
X865229Y340454D03*
X875461Y329368D03*
Y333368D03*
X866938Y487303D03*
Y483303D03*
X872397Y549771D03*
X872552Y562703D03*
Y570703D03*
Y566703D03*
Y578703D03*
Y582828D03*
X876212Y794227D03*
X893040Y141247D03*
X889070Y147540D03*
X883461Y341342D03*
X891371Y341537D03*
X883461Y345342D03*
X885224Y415264D03*
X881745Y694970D03*
Y690970D03*
X886745Y727178D03*
Y722770D03*
X884904Y1087375D03*
X888559Y1202266D03*
X895598Y1201253D03*
X886728Y1444859D03*
Y1460859D03*
Y1476859D03*
Y1468859D03*
X900019Y141247D03*
X909681Y145768D03*
X902244Y358369D03*
Y354369D03*
Y374369D03*
Y366369D03*
X909945Y687770D03*
Y691770D03*
X910745Y718970D03*
X906818Y948607D03*
X901337Y1133926D03*
X904959Y1218723D03*
X898085Y1222712D03*
X920051Y310985D03*
X920870Y547348D03*
X929136Y557641D03*
Y569578D03*
Y573578D03*
Y577578D03*
Y581578D03*
X914258Y1076659D03*
Y1080659D03*
Y1084659D03*
Y1088659D03*
Y1092659D03*
Y1096659D03*
X925324Y1449536D03*
X924688Y1468100D03*
X942071Y102495D03*
X936500Y134838D03*
Y138838D03*
X938983Y451442D03*
Y455442D03*
Y459442D03*
Y463442D03*
Y468942D03*
X945631Y527726D03*
Y548726D03*
X943570Y792330D03*
X930690Y798271D03*
X939312Y891216D03*
X946255Y97667D03*
X948650Y226852D03*
X955462Y495982D03*
X947349Y621311D03*
X952512Y782467D03*
X952668Y799233D03*
X952437Y786366D03*
X947611Y864862D03*
X947548Y883146D03*
X955048Y899890D03*
X948881Y1087375D03*
X952536Y1202122D03*
X959575Y1201253D03*
X962062Y1222712D03*
X977460Y483388D03*
X967650Y529269D03*
X974349Y608311D03*
X976569Y831799D03*
X976575Y827907D03*
X978235Y1076659D03*
Y1088659D03*
Y1084659D03*
Y1080659D03*
Y1092659D03*
Y1096659D03*
X965314Y1133926D03*
X968936Y1218723D03*
X991432Y147540D03*
X982609Y328472D03*
Y335472D03*
X984687Y825159D03*
Y829159D03*
Y833159D03*
X998127Y84140D03*
Y76140D03*
Y80140D03*
X1008838Y72587D03*
Y76587D03*
X1002381Y141247D03*
X995402D03*
X997661Y314653D03*
X1008668Y1021177D03*
X1012043Y145768D03*
X1018979Y180665D03*
Y172665D03*
Y176665D03*
Y168665D03*
Y184665D03*
Y188665D03*
X1019074Y200864D03*
Y208864D03*
Y212864D03*
Y216864D03*
Y221864D03*
X1019071Y225719D03*
X1019379Y754546D03*
Y771974D03*
Y775974D03*
X1019342Y815046D03*
X1019379Y825981D03*
Y818974D03*
X1018187Y833659D03*
X1018687Y848680D03*
X1017903Y954222D03*
X1024915Y1026933D03*
X1013988Y1357938D03*
X1013976Y1368835D03*
X1013971Y1380797D03*
X1038862Y134838D03*
Y138838D03*
X1029339Y248371D03*
X1043147Y1309487D03*
X1038924Y1357372D03*
X1038867Y1361287D03*
X1038875Y1365009D03*
X1048617Y97667D03*
X1044433Y102495D03*
X1050346Y241681D03*
X1058709Y310574D03*
X1058596Y343509D03*
X1058188Y356151D03*
Y368276D03*
X1057471Y1311436D03*
X1057517Y1315605D03*
X1051420Y1323611D03*
X1068257Y378600D03*
Y459600D03*
X1068345Y554555D03*
Y558555D03*
X1068377Y562567D03*
X1067657Y631421D03*
X1061319Y1456486D03*
X1100489Y76140D03*
Y80140D03*
Y84140D03*
X1093794Y147540D03*
X1104743Y141247D03*
X1097764D03*
X1111200Y72587D03*
Y76587D03*
X1114405Y145768D03*
X1121341Y180665D03*
Y172665D03*
Y176665D03*
Y168665D03*
Y188665D03*
Y184665D03*
X1121436Y200864D03*
Y208864D03*
Y212864D03*
Y216864D03*
Y221864D03*
X1121433Y225719D03*
X1118113Y660402D03*
X1122134Y689694D03*
X1131701Y248371D03*
X1135457Y462800D03*
X1135657Y549800D03*
X1136057Y621400D03*
Y625400D03*
X1150979Y97667D03*
X1146795Y102495D03*
X1141224Y134838D03*
Y138838D03*
X1152708Y241681D03*
X1147921Y388718D03*
X1144257Y549700D03*
X1166357Y445873D03*
Y449873D03*
Y462859D03*
X1165542Y546712D03*
X1165922Y675889D03*
X1182820Y339103D03*
X1202851Y84140D03*
Y76140D03*
Y80140D03*
X1200126Y141247D03*
X1196156Y147540D03*
X1204172Y317873D03*
X1213562Y72587D03*
Y76587D03*
X1216767Y145768D03*
X1207105Y141247D03*
X1216379Y196620D03*
X1223703Y180665D03*
Y172665D03*
Y176665D03*
Y168665D03*
Y184665D03*
Y188665D03*
X1223798Y200864D03*
Y208864D03*
Y212864D03*
Y216864D03*
Y221864D03*
X1223795Y225719D03*
X1234063Y248371D03*
X1234565Y350850D03*
X1232742Y541912D03*
Y622912D03*
X1253341Y97667D03*
X1249157Y102495D03*
X1243586Y134838D03*
Y138838D03*
X1250599Y1531342D03*
X1255070Y241681D03*
X1261984Y327000D03*
X1264682Y454334D03*
X1268013Y1171120D03*
X1260117Y1519459D03*
X1278633Y406532D03*
X1278977Y447357D03*
X1284998Y776576D03*
Y772576D03*
Y784576D03*
X1280984Y914000D03*
X1271774Y914949D03*
Y918956D03*
X1287681Y458309D03*
Y454309D03*
Y462309D03*
X1298550Y796321D03*
X1290984Y827500D03*
Y831500D03*
Y823500D03*
Y835500D03*
Y859500D03*
Y855500D03*
X1290979Y877783D03*
Y881783D03*
Y889767D03*
X1293984Y919500D03*
X1305213Y84140D03*
Y76140D03*
Y80140D03*
X1318741Y196620D03*
X1304071Y401923D03*
X1305325Y466409D03*
X1316958Y471560D03*
X1305325Y474382D03*
Y487382D03*
Y482382D03*
X1316958Y475560D03*
X1305325Y478382D03*
X1334060Y26534D03*
X1334132Y30483D03*
X1334155Y22627D03*
X1326065Y168665D03*
Y176665D03*
Y172665D03*
Y180665D03*
Y184665D03*
Y188665D03*
X1326160Y200864D03*
Y208864D03*
Y212864D03*
Y216864D03*
Y221864D03*
X1326157Y225719D03*
X1324484Y558500D03*
Y562500D03*
Y574500D03*
Y578500D03*
X1332484Y594500D03*
X1324484D03*
Y605000D03*
Y621000D03*
Y609000D03*
Y625000D03*
X1332484Y641000D03*
X1324484Y653500D03*
Y641000D03*
Y649500D03*
Y665500D03*
Y669500D03*
Y685500D03*
X1332484D03*
X1324484Y700500D03*
Y696500D03*
Y716500D03*
Y712500D03*
Y732500D03*
X1332484D03*
X1326348Y1098826D03*
X1350127Y141247D03*
X1346157Y147540D03*
X1342277Y773675D03*
X1357106Y141247D03*
X1366768Y145768D03*
X1357830Y435101D03*
Y439101D03*
Y443101D03*
Y447101D03*
Y452601D03*
X1362749Y1026266D03*
X1358476Y1098826D03*
X1384064Y248371D03*
X1380935Y320871D03*
Y325371D03*
Y343371D03*
Y338871D03*
Y334371D03*
Y329871D03*
Y347871D03*
Y361371D03*
Y356871D03*
Y352371D03*
X1371249Y1024766D03*
X1399158Y102495D03*
X1393587Y134838D03*
Y138838D03*
X1390935Y320871D03*
Y325371D03*
Y329871D03*
Y343371D03*
Y338871D03*
Y334371D03*
Y352371D03*
Y347871D03*
X1388225Y569000D03*
Y565000D03*
Y561000D03*
X1388571Y581317D03*
X1388225Y615500D03*
Y611500D03*
Y607500D03*
X1388570Y623692D03*
X1394484Y652000D03*
Y656000D03*
Y660000D03*
X1393984Y675000D03*
X1394484Y699000D03*
Y703000D03*
Y707000D03*
X1393984Y722000D03*
X1391935Y1098826D03*
X1403342Y97667D03*
X1405071Y241681D03*
X1412549Y495982D03*
X1402718Y527726D03*
Y548726D03*
X1404436Y621311D03*
X1402484Y656000D03*
X1401984Y675000D03*
X1415484Y681000D03*
Y685000D03*
X1402484Y699000D03*
X1415484Y697000D03*
Y701000D03*
Y717000D03*
X1401984Y722000D03*
X1415484Y725000D03*
Y729000D03*
Y741000D03*
Y745000D03*
Y761000D03*
X1410984Y844000D03*
Y860000D03*
Y876000D03*
Y872000D03*
Y888000D03*
Y892000D03*
Y904000D03*
X1410798Y911137D03*
Y915186D03*
X1414052Y988403D03*
X1424737Y529269D03*
X1431436Y608311D03*
X1423484Y717000D03*
X1432484Y766500D03*
X1423484Y761000D03*
X1432484Y770500D03*
Y782500D03*
Y786500D03*
Y802500D03*
Y814500D03*
Y810500D03*
Y830500D03*
Y826500D03*
Y846500D03*
X1428017Y943390D03*
X1418249Y1000766D03*
Y1016266D03*
Y1012266D03*
X1424063Y1098826D03*
X1426461Y1498545D03*
X1429423Y1520364D03*
X1419648Y1548217D03*
X1419006Y1569486D03*
X1448519Y147540D03*
X1437667Y359673D03*
X1434547Y483388D03*
X1440484Y802500D03*
Y846500D03*
X1438940Y951902D03*
X1443096Y1001518D03*
X1435578Y1001519D03*
X1442338Y1103717D03*
X1454569Y26393D03*
Y30393D03*
X1454285Y39193D03*
X1455214Y84140D03*
Y76140D03*
Y80140D03*
X1452489Y141247D03*
X1459468D03*
X1456191Y356861D03*
X1461680Y928177D03*
X1464832Y932887D03*
X1458460Y1021048D03*
X1465755Y1021177D03*
X1465925Y72587D03*
Y76587D03*
X1469130Y145768D03*
X1476066Y168665D03*
Y176665D03*
Y172665D03*
Y180665D03*
Y184665D03*
Y188665D03*
X1476161Y200864D03*
Y208864D03*
Y212864D03*
Y216864D03*
Y221864D03*
X1476158Y225719D03*
X1469684Y939543D03*
X1469648Y943496D03*
X1473984Y972000D03*
X1482002Y1026933D03*
X1496106Y19043D03*
Y15043D03*
Y23043D03*
Y31043D03*
Y27043D03*
Y35043D03*
X1495949Y138838D03*
Y134838D03*
X1486426Y248371D03*
X1493030Y322700D03*
X1483030Y327200D03*
Y322700D03*
X1493030Y327200D03*
Y331700D03*
Y340700D03*
X1483030D03*
Y331700D03*
X1493030Y349700D03*
X1483030Y345200D03*
Y358700D03*
Y354200D03*
Y349700D03*
X1493030Y345200D03*
X1492997Y368576D03*
X1484984Y681630D03*
Y677630D03*
Y697630D03*
Y689630D03*
Y693630D03*
X1492984Y706500D03*
X1484984D03*
X1485484Y731500D03*
Y723500D03*
Y735500D03*
X1484984Y750500D03*
X1485484Y743500D03*
Y739500D03*
X1492984Y750500D03*
X1505704Y97667D03*
X1501520Y102495D03*
X1507433Y241681D03*
X1502484Y765000D03*
Y781000D03*
Y773000D03*
Y777000D03*
X1509984Y792000D03*
X1501984D03*
X1502484Y785000D03*
Y809000D03*
Y817000D03*
Y825000D03*
Y821000D03*
Y829000D03*
X1509984Y836000D03*
X1501984D03*
X1507267Y907240D03*
X1525344Y378600D03*
Y459600D03*
X1525432Y554555D03*
Y558555D03*
X1525464Y562567D03*
X1524744Y631421D03*
X1541192Y352053D03*
X1557576Y84140D03*
Y76140D03*
Y80140D03*
X1550881Y147540D03*
X1561830Y141247D03*
X1554851D03*
X1551363Y352363D03*
X1554198Y956600D03*
X1568287Y72587D03*
Y76587D03*
X1571492Y145768D03*
X1578428Y168665D03*
Y176665D03*
Y172665D03*
Y180665D03*
Y184665D03*
Y188665D03*
X1578523Y200864D03*
Y208864D03*
Y212864D03*
Y216864D03*
Y221864D03*
X1578520Y225719D03*
X1574684Y336200D03*
X1575200Y660402D03*
X1579221Y689694D03*
X1588788Y248371D03*
X1592544Y462800D03*
X1592744Y549800D03*
Y558800D03*
Y562800D03*
X1593144Y621400D03*
Y625400D03*
X1593766Y1446488D03*
X1608066Y97667D03*
X1603882Y102495D03*
X1598311Y134838D03*
Y138838D03*
X1609795Y241681D03*
X1605008Y388718D03*
X1601344Y549700D03*
X1604596Y1471973D03*
X1606587Y1539334D03*
X1606575Y1543373D03*
X1619781Y344252D03*
Y340252D03*
X1623444Y445873D03*
Y449873D03*
Y462859D03*
X1622629Y546712D03*
X1623009Y675889D03*
X1659938Y84140D03*
Y80140D03*
Y76140D03*
X1657213Y141247D03*
X1653243Y147540D03*
X1670649Y72587D03*
Y76587D03*
X1664192Y141247D03*
X1673854Y145768D03*
X1673466Y196620D03*
X1661259Y317873D03*
X1680790Y168665D03*
Y176665D03*
Y172665D03*
Y180665D03*
Y188665D03*
Y184665D03*
X1680885Y200864D03*
Y208864D03*
Y212864D03*
Y216864D03*
Y221864D03*
X1680882Y225719D03*
X1691150Y248371D03*
X1691652Y350850D03*
X1689829Y541912D03*
Y622912D03*
X1706244Y102495D03*
X1700673Y134838D03*
Y138838D03*
X1710428Y97667D03*
X1712157Y241681D03*
X1721769Y454334D03*
X1725100Y1171120D03*
X1735720Y406532D03*
X1736064Y447357D03*
X1744768Y458309D03*
Y454309D03*
Y462309D03*
X1753092Y884649D03*
X1752326Y915451D03*
X1757184Y931100D03*
X1762300Y80140D03*
Y76140D03*
Y84140D03*
X1773011Y72587D03*
Y76587D03*
X1761158Y401923D03*
X1762412Y466409D03*
X1774045Y467560D03*
X1762412Y474382D03*
Y487382D03*
Y482382D03*
X1774045Y475560D03*
X1762412Y478382D03*
X1763991Y824383D03*
Y820883D03*
X1783152Y168665D03*
Y176665D03*
Y172665D03*
Y180665D03*
X1775828Y196620D03*
X1783152Y184665D03*
Y188665D03*
X1783247Y200864D03*
Y208864D03*
Y212864D03*
Y216864D03*
Y221864D03*
X1783244Y225719D03*
X1781452Y924546D03*
X1786114Y1462700D03*
X1792672Y196531D03*
X1792547Y985060D03*
X1792861Y1087861D03*
X1803555Y1201739D03*
X1796516Y1202756D03*
X1806042Y1223198D03*
X1803005Y1444543D03*
X1802882Y1476733D03*
X1814917Y435101D03*
Y439101D03*
Y443101D03*
Y447101D03*
Y452601D03*
X1822215Y1077145D03*
Y1081145D03*
Y1089145D03*
Y1085145D03*
Y1093145D03*
Y1097145D03*
X1813294Y1134412D03*
X1812916Y1219209D03*
G54D151*
X424040Y532429D03*
Y549751D03*
X447704Y532429D03*
Y549751D03*
G54D115*
X226566Y836900D03*
Y904200D03*
X238062Y826900D03*
Y846900D03*
Y894200D03*
Y914200D03*
X306966Y868900D03*
X307966Y939400D03*
X318462Y858900D03*
Y878900D03*
X319462Y929400D03*
Y949400D03*
X521372Y982854D03*
X532868Y972854D03*
Y992854D03*
X754354Y1417617D03*
X765850Y1407617D03*
Y1427617D03*
X780265Y883294D03*
X781479Y933808D03*
X791761Y873294D03*
Y893294D03*
X792975Y923808D03*
Y943808D03*
X915799Y506429D03*
X927295Y496429D03*
Y516429D03*
X989695Y705383D03*
X1001191Y695383D03*
Y715383D03*
X1287323Y999634D03*
X1298819Y989634D03*
Y1009634D03*
X1404030Y954473D03*
X1392534Y964473D03*
X1404030Y974473D03*
X1430174Y976075D03*
X1441670Y966075D03*
Y986075D03*
X1552266Y980400D03*
X1563762Y970400D03*
Y990400D03*
X1584776Y906608D03*
X1573280Y916608D03*
X1584776Y926608D03*
X1623653Y881353D03*
X1623084Y952120D03*
X1635149Y871353D03*
Y891353D03*
X1634580Y942120D03*
Y962120D03*
G54D23*
X14360Y160100D03*
X60595Y455494D03*
X110758Y117621D03*
X213120D03*
X315482D03*
X465483D03*
X515681Y452494D03*
X567845Y117621D03*
X670207D03*
X772569D03*
X922569D03*
X974768Y455494D03*
X1024931Y117621D03*
X1127293D03*
X1229655D03*
X1379656D03*
X1429855Y452494D03*
X1482018Y117621D03*
X1584380D03*
X1686742D03*
G54D125*
X361815Y1221308D03*
X818902D03*
X1275988D03*
X1733075D03*
G54D161*
X429086Y432227D03*
X924412Y448568D03*
X1343259Y432227D03*
X1800346D03*
G36*
G01X248233Y1606137D02*
G02X235433Y1618942I-12800J5D01*
G02X248233Y1606147I0J-12800D01*
G01X243683D01*
G03X235433Y1597891I-8250J-5D01*
G03X243683Y1606137I0J8251D01*
G01X248233D01*
G37*
G36*
G01X594690D02*
G02X581890Y1618942I-12800J5D01*
G02X594690Y1606147I0J-12800D01*
G01X590140D01*
G03X581890Y1597891I-8250J-5D01*
G03X590140Y1606137I0J8251D01*
G01X594690D01*
G37*
G36*
G01X1271855D02*
G02X1259055Y1618942I-12800J5D01*
G02X1271855Y1606147I0J-12800D01*
G01X1267305D01*
G03X1259055Y1597891I-8250J-5D01*
G03X1267305Y1606137I0J8251D01*
G01X1271855D01*
G37*
G36*
G01X1618312D02*
G02X1605512Y1618942I-12800J5D01*
G02X1618312Y1606147I0J-12800D01*
G01X1613762D01*
G03X1605512Y1597891I-8250J-5D01*
G03X1613762Y1606137I0J8251D01*
G01X1618312D01*
G37*
G54D41*
X17644Y1480986D03*
X10952D03*
X17644Y1489648D03*
X10952D03*
G54D260*
X1796437Y818780D03*
Y826457D03*
Y829016D03*
Y821339D03*
Y823898D03*
G54D143*
X406996Y1543915D03*
X921343Y363254D03*
G54D215*
X889303Y691560D03*
X895751Y696678D03*
X889303Y694119D03*
X895751Y691560D03*
X889303Y696678D03*
X895751Y694119D03*
G54D224*
X938357Y798194D03*
X943475D03*
X938357Y804886D03*
X943475D03*
G54D14*
X14751Y66681D03*
X7271D03*
X11011Y75343D03*
X117708Y153296D03*
X125188D03*
X121448Y161958D03*
X133095Y450750D03*
X140575D03*
X136835Y459412D03*
X197929Y99259D03*
X194189Y107921D03*
X201669D03*
X227550Y153296D03*
X220070D03*
X223810Y161958D03*
X296551Y107921D03*
X300291Y99259D03*
X304031Y107921D03*
X322432Y153296D03*
X326172Y161958D03*
X328945Y560043D03*
X329912Y153296D03*
X332685Y551381D03*
X336425Y560043D03*
X402653Y99259D03*
X398913Y107921D03*
X406393D03*
X472433Y153296D03*
X479913D03*
X476173Y161958D03*
X552654Y99259D03*
X548914Y107921D03*
X556394D03*
X582275Y153296D03*
X574795D03*
X578535Y161958D03*
X597661Y450750D03*
X590181D03*
X593921Y459412D03*
X651276Y107921D03*
X655016Y99259D03*
X658756Y107921D03*
X684637Y153296D03*
X677157D03*
X680897Y161958D03*
X757378Y99259D03*
X753638Y107921D03*
X761118D03*
X779519Y153296D03*
X783259Y161958D03*
X786999Y153296D03*
X789771Y551381D03*
X786031Y560043D03*
X793511D03*
X859740Y99259D03*
X856000Y107921D03*
X863480D03*
X929519Y153296D03*
X936999D03*
X933259Y161958D03*
X1009740Y99259D03*
X1006000Y107921D03*
X1013480D03*
X1039361Y153296D03*
X1031881D03*
X1035621Y161958D03*
X1054748Y450750D03*
X1047268D03*
X1051008Y459412D03*
X1108362Y107921D03*
X1112102Y99259D03*
X1115842Y107921D03*
X1141723Y153296D03*
X1134243D03*
X1137983Y161958D03*
X1214464Y99259D03*
X1210724Y107921D03*
X1218204D03*
X1236605Y153296D03*
X1244085D03*
X1240345Y161958D03*
X1246858Y551381D03*
X1243118Y560043D03*
X1250598D03*
X1316826Y99259D03*
X1313086Y107921D03*
X1320566D03*
X1394086Y153296D03*
X1386606D03*
X1390346Y161958D03*
X1466827Y99259D03*
X1463087Y107921D03*
X1470567D03*
X1496448Y153296D03*
X1488968D03*
X1492708Y161958D03*
X1511835Y450750D03*
X1504355D03*
X1508095Y459412D03*
X1569189Y99259D03*
X1565449Y107921D03*
X1572929D03*
X1591330Y153296D03*
X1595070Y161958D03*
X1598810Y153296D03*
X1671551Y99259D03*
X1667811Y107921D03*
X1675291D03*
X1693692Y153296D03*
X1701172D03*
X1697432Y161958D03*
X1703945Y551381D03*
X1700205Y560043D03*
X1707685D03*
X1773913Y99259D03*
X1770173Y107921D03*
X1777653D03*
G54D170*
X488765Y663326D03*
Y671200D03*
X493883Y663326D03*
X491324D03*
Y671200D03*
X493883D03*
X519753Y769259D03*
X517194D03*
X514635D03*
Y777133D03*
X517194D03*
X519753D03*
X829725Y727177D03*
Y735051D03*
X848284Y727177D03*
Y735051D03*
X845725Y727177D03*
Y735051D03*
X832284Y727177D03*
Y735051D03*
X834843Y727177D03*
Y735051D03*
X850843Y727177D03*
Y735051D03*
X1096264Y1574807D03*
Y1566933D03*
X1098823Y1574807D03*
Y1566933D03*
X1093705Y1574807D03*
Y1566933D03*
X1301348Y948224D03*
Y956098D03*
X1318000Y955937D03*
Y948063D03*
X1315441Y955937D03*
Y948063D03*
X1303907Y948224D03*
Y956098D03*
X1306466Y948224D03*
Y956098D03*
X1329500Y948063D03*
Y955937D03*
X1326941Y948063D03*
Y955937D03*
X1332059Y948063D03*
Y955937D03*
X1320559D03*
Y948063D03*
G54D134*
X393536Y780320D03*
X395505D03*
X397473D03*
X399442D03*
X401410D03*
X403379D03*
X405347D03*
X407316D03*
X409284D03*
X411253D03*
X413221D03*
X415190D03*
X417158D03*
X419127D03*
X421095D03*
X423064D03*
X1766236Y912920D03*
X1768205D03*
X1770173D03*
X1772142D03*
X1774110D03*
X1776079D03*
X1778047D03*
X1780016D03*
X1781984D03*
X1783953D03*
X1785921D03*
X1787890D03*
X1789858D03*
X1791827D03*
X1793795D03*
X1795764D03*
G54D233*
X942586Y1475447D03*
G54D206*
X855862Y1447668D03*
Y1457510D03*
Y1451605D03*
Y1455542D03*
Y1449636D03*
Y1453573D03*
X873480Y1447668D03*
Y1451605D03*
Y1457510D03*
Y1453573D03*
Y1455542D03*
Y1449636D03*
X897862Y1447668D03*
Y1457510D03*
Y1451605D03*
Y1455542D03*
Y1449636D03*
Y1453573D03*
X915480Y1447668D03*
Y1451605D03*
Y1457510D03*
Y1453573D03*
Y1455542D03*
Y1449636D03*
G54D32*
X9837Y252371D03*
Y272371D03*
X8427Y284118D03*
X16396Y1464612D03*
X16307Y1496782D03*
X12724Y1501619D03*
X29115Y97667D03*
X24931Y102495D03*
X30844Y241681D03*
X31787Y289272D03*
Y285272D03*
X28491Y527726D03*
Y548726D03*
X30209Y621311D03*
X35247Y1078372D03*
X38057Y177606D03*
X38322Y495982D03*
X50510Y529269D03*
X49541Y688473D03*
X51680Y1124923D03*
X41902Y1193263D03*
X48941Y1192250D03*
X51428Y1213709D03*
X60320Y483388D03*
X57209Y608311D03*
X56266Y843118D03*
X64601Y1071656D03*
Y1075656D03*
Y1067656D03*
Y1083656D03*
Y1087656D03*
Y1079656D03*
X58302Y1209720D03*
X85241Y141247D03*
X78262D03*
X74292Y147540D03*
X84631Y678107D03*
Y682107D03*
X84233Y1021048D03*
X94903Y145768D03*
X91528Y1021177D03*
X101839Y172665D03*
Y180665D03*
Y176665D03*
Y168665D03*
Y184665D03*
Y188665D03*
X101934Y200864D03*
Y208864D03*
Y212864D03*
Y216864D03*
Y221864D03*
X101931Y225719D03*
X112199Y248371D03*
X108321Y1027361D03*
X131477Y97667D03*
X127293Y102495D03*
X121722Y134838D03*
Y138838D03*
X133206Y241681D03*
X151117Y378600D03*
Y459600D03*
X151205Y554555D03*
X151237Y562567D03*
X151205Y558555D03*
X150517Y631421D03*
X180624Y141247D03*
X176654Y147540D03*
X183349Y80140D03*
Y76140D03*
Y84140D03*
X194060Y76587D03*
Y72587D03*
X197265Y145768D03*
X187603Y141247D03*
X204201Y172665D03*
Y180665D03*
Y176665D03*
Y168665D03*
Y184665D03*
Y188665D03*
X204296Y208864D03*
Y212864D03*
Y216864D03*
Y221864D03*
X204293Y225719D03*
X214561Y248371D03*
X229655Y102495D03*
X224084Y134838D03*
Y138838D03*
X230781Y388718D03*
X218317Y462800D03*
X218517Y549800D03*
X227117Y549700D03*
X218517Y562800D03*
Y558800D03*
X218917Y621400D03*
Y625400D03*
X227554Y1494361D03*
X227560Y1482442D03*
Y1490442D03*
X229565Y1514578D03*
X220032Y1515642D03*
X219732Y1522542D03*
X229565Y1526578D03*
Y1522578D03*
X233839Y97667D03*
X235568Y241681D03*
X246583Y1514169D03*
Y1510142D03*
X249217Y445873D03*
Y449873D03*
Y462859D03*
X248402Y546712D03*
X248782Y675889D03*
X279016Y147540D03*
X283886Y27156D03*
X285711Y84140D03*
Y76140D03*
Y80140D03*
X289965Y141247D03*
X282986D03*
X287032Y317873D03*
X296422Y76587D03*
Y72587D03*
X299627Y145768D03*
X306563Y180665D03*
Y172665D03*
Y176665D03*
Y168665D03*
Y184665D03*
X299608Y196286D03*
X306563Y188665D03*
X306658Y208864D03*
Y212864D03*
Y216864D03*
Y221864D03*
X306655Y225719D03*
X325423Y15806D03*
Y19806D03*
Y11806D03*
Y27806D03*
Y23806D03*
Y31806D03*
X326446Y134838D03*
Y138838D03*
X316923Y248371D03*
X317425Y350850D03*
X315602Y541912D03*
Y622912D03*
X336201Y97667D03*
X332017Y102495D03*
X337930Y241681D03*
X347542Y454334D03*
X350873Y1171120D03*
X361493Y406532D03*
X361837Y447357D03*
X370541Y458309D03*
Y454309D03*
Y462309D03*
X376117Y750000D03*
X374417Y786400D03*
X372949Y939976D03*
Y943812D03*
Y947812D03*
X388073Y84140D03*
Y80140D03*
Y76140D03*
X386931Y401923D03*
X388185Y466409D03*
Y474382D03*
Y487382D03*
Y482382D03*
Y478382D03*
X389687Y864408D03*
X384534Y1539700D03*
Y1543700D03*
Y1551700D03*
Y1559700D03*
X408925Y180665D03*
Y172665D03*
Y176665D03*
Y168665D03*
Y184665D03*
Y188665D03*
X401601Y196620D03*
X409020Y208864D03*
Y212864D03*
Y216864D03*
Y221864D03*
X409017Y225719D03*
X399818Y471560D03*
Y475560D03*
X400717Y789000D03*
X398926Y860535D03*
Y864409D03*
X398868Y868286D03*
X396842Y948536D03*
X397037Y971780D03*
X409207Y1098826D03*
X404632Y1442942D03*
X416920Y26534D03*
X417015Y22627D03*
X416992Y30483D03*
X416955Y834800D03*
X417221Y1523296D03*
X424741Y1546372D03*
X439966Y141247D03*
X432987D03*
X429017Y147540D03*
X440690Y435101D03*
Y439101D03*
Y443101D03*
Y447101D03*
Y452601D03*
X434608Y620456D03*
X442353Y711199D03*
X441335Y1098826D03*
X431741Y1550158D03*
X449628Y145768D03*
X453636Y468809D03*
X443154Y620456D03*
X450494Y634279D03*
X443525Y640876D03*
X450489Y642588D03*
X445608Y1026266D03*
X454108Y1024766D03*
X466924Y248371D03*
X467908Y461864D03*
X462920Y491669D03*
Y499669D03*
Y503669D03*
Y507669D03*
Y512669D03*
X474794Y1098826D03*
X486202Y97667D03*
X482018Y102495D03*
X476447Y134838D03*
Y138838D03*
X487931Y241681D03*
X475324Y347995D03*
Y352495D03*
X475427Y360089D03*
X485324Y347995D03*
Y352495D03*
X485427Y360089D03*
X475427Y364589D03*
Y369089D03*
Y373589D03*
X485427Y364589D03*
Y369089D03*
Y373589D03*
X475427Y378089D03*
Y382589D03*
Y387089D03*
Y391589D03*
X485427Y378089D03*
Y382589D03*
X476635Y468784D03*
Y472784D03*
Y476784D03*
X485577Y527726D03*
Y548726D03*
X487295Y621311D03*
X478923Y648968D03*
X495408Y495982D03*
X499697Y655149D03*
X495451Y685006D03*
Y689006D03*
Y697006D03*
Y693006D03*
X506258Y844649D03*
X501108Y1000766D03*
Y1016266D03*
Y1012266D03*
X506922Y1098826D03*
X517406Y483388D03*
X507596Y529269D03*
X514295Y608311D03*
X510787Y969933D03*
X510739Y973885D03*
X538074Y80140D03*
Y76140D03*
Y84140D03*
X535349Y141247D03*
X531379Y147540D03*
X535703Y381723D03*
X532084Y394309D03*
X539541Y779889D03*
X525197Y1103717D03*
X548785Y76587D03*
Y72587D03*
X542328Y141247D03*
X551990Y145768D03*
X545703Y386223D03*
Y390723D03*
X552698Y738558D03*
X544719Y746514D03*
X548615Y1021177D03*
X541320Y1021048D03*
X558926Y180665D03*
Y172665D03*
Y176665D03*
Y168665D03*
Y184665D03*
Y188665D03*
X559021Y208864D03*
Y212864D03*
Y216864D03*
Y221864D03*
X559018Y225719D03*
X569286Y248371D03*
X567537Y743122D03*
X561304Y754992D03*
X572131Y776700D03*
Y780700D03*
X564862Y1026933D03*
X572274Y1526224D03*
X588564Y97667D03*
X584380Y102495D03*
X578809Y134838D03*
Y138838D03*
X573320Y957207D03*
X585449Y1497687D03*
Y1493687D03*
X582232Y1514042D03*
X585449Y1501687D03*
X581483Y1505724D03*
X590293Y241681D03*
X608203Y378600D03*
Y459600D03*
X608291Y554555D03*
Y558555D03*
X608323Y562567D03*
X607603Y631421D03*
X633741Y147540D03*
X640436Y76140D03*
Y84140D03*
Y80140D03*
X651147Y76587D03*
Y72587D03*
X644690Y141247D03*
X637711D03*
X653363Y759137D03*
Y767137D03*
Y763137D03*
Y779137D03*
Y775137D03*
Y771137D03*
Y783137D03*
Y787137D03*
X654352Y145768D03*
X661288Y180665D03*
Y172665D03*
Y176665D03*
Y168665D03*
Y184665D03*
Y188665D03*
X661383Y208864D03*
Y212864D03*
Y216864D03*
Y221864D03*
X661380Y225719D03*
X658059Y660402D03*
X662080Y689694D03*
X666863Y763137D03*
Y779137D03*
Y771137D03*
Y787137D03*
X681171Y134838D03*
Y138838D03*
X671648Y248371D03*
X675403Y462800D03*
X675603Y549800D03*
X684203Y549700D03*
X676003Y621400D03*
Y625400D03*
X690926Y97667D03*
X686742Y102495D03*
X692655Y241681D03*
X687867Y388718D03*
X706303Y445873D03*
Y449873D03*
Y462859D03*
X705488Y546712D03*
X705868Y675889D03*
X717306Y691609D03*
X704102Y709303D03*
X707107Y728050D03*
X724863Y760137D03*
X742798Y84140D03*
Y76140D03*
Y80140D03*
X747052Y141247D03*
X740073D03*
X736103Y147540D03*
X744118Y317873D03*
X736247Y1622015D03*
X753509Y72562D03*
Y76587D03*
X756714Y145768D03*
X763650Y180665D03*
Y172665D03*
Y176665D03*
Y168665D03*
Y184665D03*
Y188665D03*
X756326Y196620D03*
X763745Y200864D03*
Y208864D03*
Y212864D03*
Y216864D03*
Y221864D03*
X783533Y134838D03*
Y138838D03*
X774010Y248371D03*
X774511Y350850D03*
X772688Y541912D03*
Y622912D03*
X780278Y1443445D03*
X780266Y1435432D03*
X771727Y1454305D03*
X793288Y97667D03*
X789104Y102495D03*
X795017Y241681D03*
X788641Y442510D03*
Y450510D03*
Y446510D03*
X811994Y305368D03*
Y309368D03*
X803994Y305368D03*
Y309368D03*
X811994Y313368D03*
X803994D03*
X811994Y317368D03*
Y321368D03*
Y325368D03*
X803994Y317368D03*
Y321368D03*
Y325368D03*
X811994Y329368D03*
X803994D03*
X811994Y333368D03*
X803994Y337368D03*
Y333368D03*
X811994Y346368D03*
X803994D03*
X811994Y350368D03*
X811991Y354741D03*
X804628Y448334D03*
X808841Y840919D03*
X807960Y1171120D03*
X807146Y1404769D03*
X805011Y1484354D03*
X818900Y441389D03*
X827627Y456309D03*
Y448309D03*
Y452309D03*
X817080Y742502D03*
X827017Y766500D03*
Y784500D03*
Y802500D03*
Y820500D03*
X820494Y933571D03*
X831221Y1440849D03*
Y1448849D03*
X825927Y1462461D03*
X831239Y1454525D03*
X845160Y76140D03*
Y80140D03*
Y84140D03*
X845271Y461382D03*
Y469382D03*
Y473382D03*
Y482382D03*
Y477382D03*
X838359Y827459D03*
X846157Y827686D03*
X840781Y843790D03*
Y847490D03*
X842826Y835459D03*
Y851459D03*
X840254Y863413D03*
X840381Y855395D03*
X840254Y867413D03*
X842261Y1461959D03*
X855871Y76587D03*
Y72587D03*
X858688Y196620D03*
X862262Y340454D03*
X850491Y414760D03*
X861748Y414533D03*
X850491Y418760D03*
X863971Y487303D03*
Y483303D03*
X860778Y701170D03*
Y709170D03*
X860578Y722670D03*
X861517Y756000D03*
Y760000D03*
Y764000D03*
Y778000D03*
Y782000D03*
Y774000D03*
Y792000D03*
Y796000D03*
Y800000D03*
Y814000D03*
Y810000D03*
X853848Y827468D03*
X861517Y818000D03*
X853776Y835459D03*
X866012Y180665D03*
Y172665D03*
Y176665D03*
Y168665D03*
Y184665D03*
Y188665D03*
X866107Y208864D03*
Y212864D03*
Y216864D03*
Y221864D03*
X872494Y309368D03*
Y305368D03*
Y313368D03*
Y325368D03*
Y321368D03*
Y317368D03*
Y329368D03*
Y333368D03*
X880494Y341342D03*
Y345342D03*
X869430Y549771D03*
X869585Y562703D03*
Y570703D03*
Y566703D03*
Y578703D03*
Y582828D03*
X878778Y694970D03*
Y690970D03*
X873245Y794227D03*
X897052Y141247D03*
X890073D03*
X886103Y147540D03*
X888404Y341537D03*
X882257Y415264D03*
X883778Y727178D03*
Y722770D03*
X881937Y1087375D03*
X885592Y1202266D03*
X892631Y1201253D03*
X895118Y1222712D03*
X883761Y1444859D03*
Y1460859D03*
Y1476859D03*
Y1468859D03*
X906714Y145768D03*
X899277Y358369D03*
Y354369D03*
Y374369D03*
Y366369D03*
X906978Y687770D03*
Y691770D03*
X907778Y718970D03*
X903851Y948607D03*
X911291Y1076659D03*
Y1080659D03*
Y1084659D03*
Y1088659D03*
Y1092659D03*
Y1096659D03*
X898370Y1133926D03*
X901992Y1218723D03*
X917084Y310985D03*
X917903Y547348D03*
X926169Y557641D03*
Y569578D03*
Y573578D03*
Y577578D03*
Y581578D03*
X927723Y798271D03*
X922357Y1449536D03*
X921721Y1468100D03*
X943288Y97667D03*
X939104Y102495D03*
X933533Y134838D03*
Y138838D03*
X945683Y226852D03*
X936016Y451442D03*
Y455442D03*
Y459442D03*
Y463442D03*
Y468942D03*
X942664Y527726D03*
Y548726D03*
X944382Y621311D03*
X940603Y792330D03*
X944644Y864862D03*
X944581Y883146D03*
X936345Y891216D03*
X945914Y1087375D03*
X952495Y495982D03*
X949545Y782467D03*
X949701Y799233D03*
X949470Y786366D03*
X952081Y899890D03*
X962347Y1133926D03*
X949569Y1202122D03*
X956608Y1201253D03*
X959095Y1222712D03*
X974493Y483388D03*
X964683Y529269D03*
X971382Y608311D03*
X973602Y831799D03*
X973608Y827907D03*
X975268Y1076659D03*
Y1088659D03*
Y1084659D03*
Y1080659D03*
Y1092659D03*
Y1096659D03*
X965969Y1218723D03*
X992435Y141247D03*
X988465Y147540D03*
X994694Y314653D03*
X979642Y328472D03*
Y335472D03*
X981720Y825159D03*
Y829159D03*
Y833159D03*
X995160Y84140D03*
Y76140D03*
Y80140D03*
X1005871Y72587D03*
Y76587D03*
X999414Y141247D03*
X1009076Y145768D03*
X1005701Y1021177D03*
X1011021Y1357938D03*
X1011009Y1368835D03*
X1011004Y1380797D03*
X1016012Y180665D03*
Y172665D03*
Y176665D03*
Y168665D03*
Y184665D03*
Y188665D03*
X1016107Y200864D03*
Y208864D03*
Y212864D03*
Y216864D03*
Y221864D03*
X1016104Y225719D03*
X1026372Y248371D03*
X1016412Y754546D03*
Y771974D03*
Y775974D03*
X1016375Y815046D03*
X1016412Y825981D03*
Y818974D03*
X1015220Y833659D03*
X1015720Y848680D03*
X1014936Y954222D03*
X1021948Y1026933D03*
X1041466Y102495D03*
X1035895Y134838D03*
Y138838D03*
X1040180Y1309487D03*
X1035957Y1357372D03*
X1035900Y1361287D03*
X1035908Y1365009D03*
X1045650Y97667D03*
X1047379Y241681D03*
X1055742Y310574D03*
X1055629Y343509D03*
X1055221Y356151D03*
Y368276D03*
X1054504Y1311436D03*
X1054550Y1315605D03*
X1048453Y1323611D03*
X1058352Y1456486D03*
X1065290Y378600D03*
Y459600D03*
X1065378Y554555D03*
Y558555D03*
X1065410Y562567D03*
X1064690Y631421D03*
X1090827Y147540D03*
X1097522Y76140D03*
Y80140D03*
Y84140D03*
X1108233Y72587D03*
Y76587D03*
X1101776Y141247D03*
X1094797D03*
X1111438Y145768D03*
X1118374Y180665D03*
Y172665D03*
Y176665D03*
Y168665D03*
Y188665D03*
Y184665D03*
X1118469Y200864D03*
Y208864D03*
Y212864D03*
Y216864D03*
Y221864D03*
X1118466Y225719D03*
X1115146Y660402D03*
X1119167Y689694D03*
X1138257Y134838D03*
Y138838D03*
X1128734Y248371D03*
X1132490Y462800D03*
X1132690Y549800D03*
X1133090Y621400D03*
Y625400D03*
X1148012Y97667D03*
X1143828Y102495D03*
X1149741Y241681D03*
X1144954Y388718D03*
X1141290Y549700D03*
X1163390Y445873D03*
Y449873D03*
Y462859D03*
X1162575Y546712D03*
X1162955Y675889D03*
X1179853Y339103D03*
X1199884Y84140D03*
Y76140D03*
Y80140D03*
X1204138Y141247D03*
X1197159D03*
X1193189Y147540D03*
X1201205Y317873D03*
X1210595Y72587D03*
Y76587D03*
X1213800Y145768D03*
X1220736Y180665D03*
Y172665D03*
Y176665D03*
Y168665D03*
Y184665D03*
Y188665D03*
X1213412Y196620D03*
X1220831Y200864D03*
Y208864D03*
Y212864D03*
Y216864D03*
Y221864D03*
X1220828Y225719D03*
X1231096Y248371D03*
X1231598Y350850D03*
X1229775Y541912D03*
Y622912D03*
X1250374Y97667D03*
X1246190Y102495D03*
X1240619Y134838D03*
Y138838D03*
X1252103Y241681D03*
X1247632Y1531342D03*
X1259017Y327000D03*
X1261715Y454334D03*
X1268807Y914949D03*
Y918956D03*
X1265046Y1171120D03*
X1257150Y1519459D03*
X1275666Y406532D03*
X1276010Y447357D03*
X1284714Y458309D03*
Y454309D03*
Y462309D03*
X1282031Y776576D03*
Y772576D03*
Y784576D03*
X1278017Y914000D03*
X1302246Y84140D03*
Y76140D03*
Y80140D03*
X1301104Y401923D03*
X1302358Y466409D03*
Y474382D03*
Y487382D03*
Y482382D03*
Y478382D03*
X1295583Y796321D03*
X1288017Y827500D03*
Y831500D03*
Y823500D03*
Y835500D03*
Y859500D03*
Y855500D03*
X1288012Y877783D03*
Y881783D03*
Y889767D03*
X1291017Y919500D03*
X1315774Y196620D03*
X1313991Y471560D03*
Y475560D03*
X1331093Y26534D03*
X1331165Y30483D03*
X1331188Y22627D03*
X1323098Y168665D03*
Y176665D03*
Y172665D03*
Y180665D03*
Y184665D03*
Y188665D03*
X1323193Y200864D03*
Y208864D03*
Y212864D03*
Y216864D03*
Y221864D03*
X1323190Y225719D03*
X1321517Y558500D03*
Y562500D03*
Y574500D03*
Y578500D03*
X1329517Y594500D03*
X1321517D03*
Y605000D03*
Y621000D03*
Y609000D03*
Y625000D03*
X1329517Y641000D03*
X1321517Y653500D03*
Y641000D03*
Y649500D03*
Y665500D03*
Y669500D03*
Y685500D03*
X1329517D03*
X1321517Y700500D03*
Y696500D03*
Y716500D03*
Y712500D03*
Y732500D03*
X1329517D03*
X1323381Y1098826D03*
X1347160Y141247D03*
X1343190Y147540D03*
X1339310Y773675D03*
X1354139Y141247D03*
X1363801Y145768D03*
X1354863Y435101D03*
Y439101D03*
Y443101D03*
Y447101D03*
Y452601D03*
X1359782Y1026266D03*
X1368282Y1024766D03*
X1355509Y1098826D03*
X1381097Y248371D03*
X1377968Y320871D03*
Y325371D03*
Y343371D03*
Y338871D03*
Y334371D03*
Y329871D03*
Y347871D03*
Y361371D03*
Y356871D03*
Y352371D03*
X1400375Y97667D03*
X1396191Y102495D03*
X1390620Y134838D03*
Y138838D03*
X1387968Y320871D03*
Y325371D03*
Y329871D03*
Y343371D03*
Y338871D03*
Y334371D03*
Y352371D03*
Y347871D03*
X1399751Y527726D03*
Y548726D03*
X1385258Y569000D03*
Y565000D03*
Y561000D03*
X1385604Y581317D03*
X1385258Y615500D03*
Y611500D03*
Y607500D03*
X1385603Y623692D03*
X1391517Y652000D03*
X1399517Y656000D03*
X1391517D03*
Y660000D03*
X1391017Y675000D03*
X1399017D03*
X1391517Y699000D03*
X1399517D03*
X1391517Y703000D03*
Y707000D03*
X1399017Y722000D03*
X1391017D03*
X1388968Y1098826D03*
X1402104Y241681D03*
X1409582Y495982D03*
X1401469Y621311D03*
X1412517Y681000D03*
Y685000D03*
Y697000D03*
Y701000D03*
Y717000D03*
Y725000D03*
Y729000D03*
Y741000D03*
Y745000D03*
Y761000D03*
X1408017Y844000D03*
Y860000D03*
Y876000D03*
Y872000D03*
Y888000D03*
Y892000D03*
Y904000D03*
X1407831Y911137D03*
Y915186D03*
X1411085Y988403D03*
X1415282Y1000766D03*
Y1016266D03*
Y1012266D03*
X1416681Y1548217D03*
X1416039Y1569486D03*
X1431580Y483388D03*
X1421770Y529269D03*
X1428469Y608311D03*
X1420517Y717000D03*
X1429517Y766500D03*
X1420517Y761000D03*
X1429517Y770500D03*
Y782500D03*
Y786500D03*
Y802500D03*
Y814500D03*
Y810500D03*
Y830500D03*
Y826500D03*
Y846500D03*
X1425050Y943390D03*
X1432611Y1001519D03*
X1421096Y1098826D03*
X1423494Y1498545D03*
X1426456Y1520364D03*
X1449522Y141247D03*
X1445552Y147540D03*
X1434700Y359673D03*
X1437517Y802500D03*
Y846500D03*
X1435973Y951902D03*
X1440129Y1001518D03*
X1439371Y1103717D03*
X1451602Y26393D03*
Y30393D03*
X1451318Y39193D03*
X1452247Y84140D03*
Y76140D03*
Y80140D03*
X1462958Y72587D03*
Y76587D03*
X1456501Y141247D03*
X1453224Y356861D03*
X1458713Y928177D03*
X1461865Y932887D03*
X1455493Y1021048D03*
X1462788Y1021177D03*
X1466163Y145768D03*
X1473099Y168665D03*
Y176665D03*
Y172665D03*
Y180665D03*
Y184665D03*
Y188665D03*
X1473194Y200864D03*
Y208864D03*
Y212864D03*
Y216864D03*
Y221864D03*
X1473191Y225719D03*
X1480063Y327200D03*
Y322700D03*
Y340700D03*
Y331700D03*
Y345200D03*
Y358700D03*
Y354200D03*
Y349700D03*
X1482017Y681630D03*
Y677630D03*
Y697630D03*
Y689630D03*
Y693630D03*
Y706500D03*
Y750500D03*
X1466717Y939543D03*
X1466681Y943496D03*
X1471017Y972000D03*
X1479035Y1026933D03*
X1493139Y19043D03*
Y15043D03*
Y23043D03*
Y31043D03*
Y27043D03*
Y35043D03*
X1492982Y138838D03*
Y134838D03*
X1483459Y248371D03*
X1490063Y322700D03*
Y327200D03*
Y331700D03*
Y340700D03*
Y349700D03*
Y345200D03*
X1490030Y368576D03*
X1490017Y706500D03*
X1482517Y731500D03*
Y723500D03*
Y735500D03*
Y743500D03*
Y739500D03*
X1490017Y750500D03*
X1502737Y97667D03*
X1498553Y102495D03*
X1504466Y241681D03*
X1499517Y765000D03*
Y781000D03*
Y773000D03*
Y777000D03*
X1507017Y792000D03*
X1499017D03*
X1499517Y785000D03*
Y809000D03*
Y817000D03*
Y825000D03*
Y821000D03*
Y829000D03*
X1507017Y836000D03*
X1499017D03*
X1504300Y907240D03*
X1522377Y378600D03*
Y459600D03*
X1522465Y554555D03*
Y558555D03*
X1522497Y562567D03*
X1521777Y631421D03*
X1538225Y352053D03*
X1554609Y84140D03*
Y76140D03*
Y80140D03*
X1547914Y147540D03*
X1558863Y141247D03*
X1551884D03*
X1548396Y352363D03*
X1551231Y956600D03*
X1565320Y72587D03*
Y76587D03*
X1568525Y145768D03*
X1575461Y168665D03*
Y176665D03*
Y172665D03*
Y180665D03*
Y184665D03*
Y188665D03*
X1575556Y200864D03*
Y208864D03*
Y212864D03*
Y216864D03*
Y221864D03*
X1575553Y225719D03*
X1571717Y336200D03*
X1572233Y660402D03*
X1576254Y689694D03*
X1595344Y134838D03*
Y138838D03*
X1585821Y248371D03*
X1589577Y462800D03*
X1589777Y549800D03*
Y558800D03*
Y562800D03*
X1590177Y621400D03*
Y625400D03*
X1590799Y1446488D03*
X1605099Y97667D03*
X1600915Y102495D03*
X1606828Y241681D03*
X1602041Y388718D03*
X1598377Y549700D03*
X1601629Y1471973D03*
X1603620Y1539334D03*
X1603608Y1543373D03*
X1616814Y344252D03*
Y340252D03*
X1620477Y445873D03*
Y449873D03*
Y462859D03*
X1619662Y546712D03*
X1620042Y675889D03*
X1656971Y84140D03*
Y80140D03*
Y76140D03*
X1654246Y141247D03*
X1650276Y147540D03*
X1658292Y317873D03*
X1667682Y72587D03*
Y76587D03*
X1661225Y141247D03*
X1670887Y145768D03*
X1670499Y196620D03*
X1677823Y168665D03*
Y176665D03*
Y172665D03*
Y180665D03*
Y188665D03*
Y184665D03*
X1677918Y200864D03*
Y208864D03*
Y212864D03*
Y216864D03*
Y221864D03*
X1677915Y225719D03*
X1688183Y248371D03*
X1688685Y350850D03*
X1686862Y541912D03*
Y622912D03*
X1707461Y97667D03*
X1703277Y102495D03*
X1697706Y134838D03*
Y138838D03*
X1709190Y241681D03*
X1718802Y454334D03*
X1722133Y1171120D03*
X1732753Y406532D03*
X1733097Y447357D03*
X1741801Y458309D03*
Y454309D03*
Y462309D03*
X1758191Y401923D03*
X1750125Y884649D03*
X1749359Y915451D03*
X1754217Y931100D03*
X1759333Y80140D03*
Y76140D03*
Y84140D03*
X1770044Y72587D03*
Y76587D03*
X1772861Y196620D03*
X1759445Y466409D03*
X1771078Y467560D03*
X1759445Y474382D03*
Y487382D03*
Y482382D03*
X1771078Y475560D03*
X1759445Y478382D03*
X1761024Y824383D03*
Y820883D03*
X1780185Y168665D03*
Y176665D03*
Y172665D03*
Y180665D03*
Y184665D03*
Y188665D03*
X1789705Y196531D03*
X1780280Y200864D03*
Y208864D03*
Y212864D03*
Y216864D03*
Y221864D03*
X1780277Y225719D03*
X1778485Y924546D03*
X1789580Y985060D03*
X1789894Y1087861D03*
X1783147Y1462700D03*
X1800588Y1201739D03*
X1793549Y1202756D03*
X1803075Y1223198D03*
X1800038Y1444543D03*
X1799915Y1476733D03*
X1811950Y435101D03*
Y439101D03*
Y443101D03*
Y447101D03*
Y452601D03*
X1819248Y1077145D03*
Y1081145D03*
Y1089145D03*
Y1085145D03*
Y1093145D03*
Y1097145D03*
X1810327Y1134412D03*
X1809949Y1219209D03*
G54D107*
X112430Y1205118D03*
X109601Y1207947D03*
X103591Y1213957D03*
X115265Y1226217D03*
X123749Y1217733D03*
X132235Y1209248D03*
X349826Y401783D03*
X569517Y1205118D03*
X566688Y1207947D03*
X560678Y1213957D03*
X572352Y1226217D03*
X580836Y1217733D03*
X589322Y1209248D03*
X1026603Y1205118D03*
X1023774Y1207947D03*
X1017764Y1213957D03*
X1037922Y1217733D03*
X1029438Y1226217D03*
X1046408Y1209248D03*
X1263999Y401783D03*
X1480861Y1207947D03*
X1474851Y1213957D03*
X1483690Y1205118D03*
X1495009Y1217733D03*
X1486525Y1226217D03*
X1503495Y1209248D03*
X1721086Y401783D03*
G54D251*
X1030635Y824546D03*
G54D242*
X989651Y1556274D03*
X1015635D03*
G54D50*
X31623Y1463463D03*
X30543Y1479284D03*
X71404Y1452463D03*
X405498Y1524334D03*
X906950Y322671D03*
X905870Y335995D03*
X918458Y317736D03*
G54D152*
X425820Y750005D03*
Y748036D03*
Y765753D03*
Y763784D03*
Y761816D03*
Y759847D03*
Y757879D03*
Y755910D03*
Y753942D03*
Y751973D03*
Y777564D03*
Y775595D03*
Y773627D03*
Y771658D03*
Y769690D03*
Y767721D03*
X1798520Y880636D03*
Y896384D03*
Y894416D03*
Y892447D03*
Y890479D03*
Y888510D03*
Y886542D03*
Y884573D03*
Y882605D03*
Y910164D03*
Y908195D03*
Y906227D03*
Y904258D03*
Y902290D03*
Y900321D03*
Y898353D03*
G54D270*
G01X-20602Y-468335D02*
Y-543335D01*
X479398D01*
Y-468335D01*
X-20602D01*
G01X-8602Y-533335D02*
Y-538335D01*
G01X-10059Y-533335D02*
X-7145D01*
G01X-2235Y-538335D02*
X-4769D01*
Y-533335D01*
X-2235D01*
G01X-3249Y-535752D02*
X-4769D01*
G01X331Y-533335D02*
Y-538335D01*
X2865D01*
G01X6698Y-538502D02*
X6571Y-538418D01*
Y-538252D01*
X6698Y-538168D01*
X6825Y-538252D01*
Y-538418D01*
X6698Y-538502D01*
G01Y-536252D02*
X6571Y-536168D01*
Y-536002D01*
X6698Y-535918D01*
X6825Y-536002D01*
Y-536168D01*
X6698Y-536252D01*
G01X11481Y-540002D02*
X10848Y-539168D01*
X10531Y-538335D01*
Y-535002D01*
X10848Y-534168D01*
X11481Y-533335D01*
G01X16898D02*
X16391Y-533502D01*
X16011Y-533918D01*
X15758Y-534418D01*
X15568Y-535085D01*
X15505Y-535835D01*
X15568Y-536585D01*
X15758Y-537252D01*
X16011Y-537752D01*
X16391Y-538168D01*
X16898Y-538335D01*
X17405Y-538168D01*
X17785Y-537752D01*
X18038Y-537252D01*
X18228Y-536585D01*
X18291Y-535835D01*
X18228Y-535085D01*
X18038Y-534418D01*
X17785Y-533918D01*
X17405Y-533502D01*
X16898Y-533335D01*
G01X20605Y-537335D02*
X20985Y-537918D01*
X21491Y-538252D01*
X22061Y-538335D01*
X22568Y-538252D01*
X23075Y-537835D01*
X23391Y-537335D01*
X23455Y-536835D01*
X23328Y-536252D01*
X22885Y-535835D01*
X22441Y-535668D01*
X21871D01*
G01X22441D02*
X22821Y-535418D01*
X23138Y-535002D01*
X23265Y-534502D01*
X23138Y-534002D01*
X22821Y-533585D01*
X22251Y-533335D01*
X21681Y-533418D01*
X21111Y-533752D01*
G01X27415Y-540002D02*
X28048Y-539168D01*
X28365Y-538335D01*
Y-535002D01*
X28048Y-534168D01*
X27415Y-533335D01*
G01X30805Y-537335D02*
X31185Y-537918D01*
X31691Y-538252D01*
X32261Y-538335D01*
X32768Y-538252D01*
X33275Y-537835D01*
X33591Y-537335D01*
X33655Y-536835D01*
X33528Y-536252D01*
X33085Y-535835D01*
X32641Y-535668D01*
X32071D01*
G01X32641D02*
X33021Y-535418D01*
X33338Y-535002D01*
X33465Y-534502D01*
X33338Y-534002D01*
X33021Y-533585D01*
X32451Y-533335D01*
X31881Y-533418D01*
X31311Y-533752D01*
G01X36095Y-534168D02*
X36475Y-533668D01*
X36918Y-533418D01*
X37425Y-533335D01*
X38058Y-533502D01*
X38501Y-533918D01*
X38628Y-534418D01*
X38565Y-534918D01*
X38311Y-535335D01*
X37045Y-536168D01*
X36475Y-536752D01*
X36095Y-537585D01*
X35968Y-538335D01*
X38628D01*
G01X42271D02*
X42398Y-537252D01*
X42588Y-536335D01*
X42841Y-535502D01*
X43158Y-534585D01*
X43665Y-533335D01*
X41131D01*
G01X46675Y-536668D02*
X48321D01*
G01X51395Y-534168D02*
X51775Y-533668D01*
X52218Y-533418D01*
X52725Y-533335D01*
X53358Y-533502D01*
X53801Y-533918D01*
X53928Y-534418D01*
X53865Y-534918D01*
X53611Y-535335D01*
X52345Y-536168D01*
X51775Y-536752D01*
X51395Y-537585D01*
X51268Y-538335D01*
X53928D01*
G01X56305Y-537335D02*
X56685Y-537918D01*
X57191Y-538252D01*
X57761Y-538335D01*
X58268Y-538252D01*
X58775Y-537835D01*
X59091Y-537335D01*
X59155Y-536835D01*
X59028Y-536252D01*
X58585Y-535835D01*
X58141Y-535668D01*
X57571D01*
G01X58141D02*
X58521Y-535418D01*
X58838Y-535002D01*
X58965Y-534502D01*
X58838Y-534002D01*
X58521Y-533585D01*
X57951Y-533335D01*
X57381Y-533418D01*
X56811Y-533752D01*
G01X63558Y-538335D02*
Y-533335D01*
X61215Y-536918D01*
X64381D01*
G01X66505Y-537585D02*
X66885Y-538002D01*
X67328Y-538252D01*
X67898Y-538335D01*
X68468Y-538168D01*
X68911Y-537835D01*
X69228Y-537252D01*
X69291Y-536585D01*
X69165Y-535918D01*
X68848Y-535502D01*
X68405Y-535168D01*
X67961Y-535085D01*
X67518Y-535168D01*
X66948Y-535502D01*
X67138Y-533335D01*
X68848D01*
G01X76895Y-538335D02*
Y-533335D01*
X79301D01*
G01X78415Y-535752D02*
X76895D01*
G01X81615Y-538335D02*
X83198Y-533335D01*
X84781Y-538335D01*
G01X84211Y-536585D02*
X82185D01*
G01X86968Y-538335D02*
X89628Y-533335D01*
G01X86968D02*
X89628Y-538335D01*
G01X93398Y-538502D02*
X93271Y-538418D01*
Y-538252D01*
X93398Y-538168D01*
X93525Y-538252D01*
Y-538418D01*
X93398Y-538502D01*
G01Y-536252D02*
X93271Y-536168D01*
Y-536002D01*
X93398Y-535918D01*
X93525Y-536002D01*
Y-536168D01*
X93398Y-536252D01*
G01X98181Y-540002D02*
X97548Y-539168D01*
X97231Y-538335D01*
Y-535002D01*
X97548Y-534168D01*
X98181Y-533335D01*
G01X103598D02*
X103091Y-533502D01*
X102711Y-533918D01*
X102458Y-534418D01*
X102268Y-535085D01*
X102205Y-535835D01*
X102268Y-536585D01*
X102458Y-537252D01*
X102711Y-537752D01*
X103091Y-538168D01*
X103598Y-538335D01*
X104105Y-538168D01*
X104485Y-537752D01*
X104738Y-537252D01*
X104928Y-536585D01*
X104991Y-535835D01*
X104928Y-535085D01*
X104738Y-534418D01*
X104485Y-533918D01*
X104105Y-533502D01*
X103598Y-533335D01*
G01X107305Y-537335D02*
X107685Y-537918D01*
X108191Y-538252D01*
X108761Y-538335D01*
X109268Y-538252D01*
X109775Y-537835D01*
X110091Y-537335D01*
X110155Y-536835D01*
X110028Y-536252D01*
X109585Y-535835D01*
X109141Y-535668D01*
X108571D01*
G01X109141D02*
X109521Y-535418D01*
X109838Y-535002D01*
X109965Y-534502D01*
X109838Y-534002D01*
X109521Y-533585D01*
X108951Y-533335D01*
X108381Y-533418D01*
X107811Y-533752D01*
G01X114115Y-540002D02*
X114748Y-539168D01*
X115065Y-538335D01*
Y-535002D01*
X114748Y-534168D01*
X114115Y-533335D01*
G01X117505Y-537335D02*
X117885Y-537918D01*
X118391Y-538252D01*
X118961Y-538335D01*
X119468Y-538252D01*
X119975Y-537835D01*
X120291Y-537335D01*
X120355Y-536835D01*
X120228Y-536252D01*
X119785Y-535835D01*
X119341Y-535668D01*
X118771D01*
G01X119341D02*
X119721Y-535418D01*
X120038Y-535002D01*
X120165Y-534502D01*
X120038Y-534002D01*
X119721Y-533585D01*
X119151Y-533335D01*
X118581Y-533418D01*
X118011Y-533752D01*
G01X122921Y-537752D02*
X123365Y-538168D01*
X123871Y-538335D01*
X124378Y-538168D01*
X124821Y-537668D01*
X125138Y-536918D01*
X125265Y-536168D01*
Y-535252D01*
X125138Y-534502D01*
X124821Y-533835D01*
X124441Y-533502D01*
X123998Y-533335D01*
X123491Y-533502D01*
X123111Y-533835D01*
X122858Y-534335D01*
X122731Y-535002D01*
X122858Y-535585D01*
X123175Y-536168D01*
X123555Y-536502D01*
X123998Y-536585D01*
X124505Y-536418D01*
X124885Y-536002D01*
X125265Y-535252D01*
G01X128971Y-538335D02*
X129098Y-537252D01*
X129288Y-536335D01*
X129541Y-535502D01*
X129858Y-534585D01*
X130365Y-533335D01*
X127831D01*
G01X133375Y-536668D02*
X135021D01*
G01X137905Y-537335D02*
X138285Y-537918D01*
X138791Y-538252D01*
X139361Y-538335D01*
X139868Y-538252D01*
X140375Y-537835D01*
X140691Y-537335D01*
X140755Y-536835D01*
X140628Y-536252D01*
X140185Y-535835D01*
X139741Y-535668D01*
X139171D01*
G01X139741D02*
X140121Y-535418D01*
X140438Y-535002D01*
X140565Y-534502D01*
X140438Y-534002D01*
X140121Y-533585D01*
X139551Y-533335D01*
X138981Y-533418D01*
X138411Y-533752D01*
G01X143195Y-536252D02*
X143638Y-535668D01*
X144018Y-535335D01*
X144525Y-535168D01*
X144968Y-535335D01*
X145285Y-535668D01*
X145538Y-536168D01*
X145601Y-536752D01*
X145538Y-537252D01*
X145285Y-537752D01*
X144905Y-538168D01*
X144461Y-538335D01*
X143955Y-538168D01*
X143511Y-537668D01*
X143258Y-536918D01*
X143195Y-536085D01*
X143321Y-535002D01*
X143511Y-534418D01*
X143828Y-533835D01*
X144271Y-533418D01*
X144715Y-533335D01*
X145158Y-533502D01*
X145475Y-533918D01*
G01X149498Y-538335D02*
Y-533335D01*
X148738Y-534335D01*
G01Y-538335D02*
X150258D01*
G01X155358D02*
Y-533335D01*
X153015Y-536918D01*
X156181D01*
G01X174398Y-468335D02*
Y-543335D01*
G01Y-518335D02*
X277398D01*
Y-493335D01*
G01X174398D02*
X277398D01*
G01Y-468335D02*
Y-543335D01*
G01X279398Y-468335D02*
Y-543335D01*
G01X284905Y-528335D02*
Y-523335D01*
X286171D01*
X286678Y-523585D01*
X287058Y-523918D01*
X287375Y-524418D01*
X287628Y-525002D01*
X287691Y-525835D01*
X287628Y-526668D01*
X287375Y-527252D01*
X287058Y-527752D01*
X286678Y-528085D01*
X286171Y-528335D01*
X284905D01*
G01X289815D02*
X291398Y-523335D01*
X292981Y-528335D01*
G01X292411Y-526585D02*
X290385D01*
G01X296498Y-523335D02*
Y-528335D01*
G01X295041Y-523335D02*
X297955D01*
G01X302865Y-528335D02*
X300331D01*
Y-523335D01*
X302865D01*
G01X301851Y-525752D02*
X300331D01*
G01X306698Y-528502D02*
X306571Y-528418D01*
Y-528252D01*
X306698Y-528168D01*
X306825Y-528252D01*
Y-528418D01*
X306698Y-528502D01*
G01Y-526252D02*
X306571Y-526168D01*
Y-526002D01*
X306698Y-525918D01*
X306825Y-526002D01*
Y-526168D01*
X306698Y-526252D01*
G01X279398Y-518335D02*
X479398D01*
G01X285031Y-503335D02*
Y-498335D01*
X286551D01*
X287058Y-498585D01*
X287438Y-499168D01*
X287565Y-499835D01*
X287438Y-500502D01*
X287121Y-501002D01*
X286551Y-501252D01*
X285031D01*
G01X290258Y-503502D02*
X292538Y-498335D01*
G01X295041Y-503335D02*
Y-498335D01*
X297955Y-503335D01*
Y-498335D01*
G01X301598Y-503502D02*
X301471Y-503418D01*
Y-503252D01*
X301598Y-503168D01*
X301725Y-503252D01*
Y-503418D01*
X301598Y-503502D01*
G01Y-501252D02*
X301471Y-501168D01*
Y-501002D01*
X301598Y-500918D01*
X301725Y-501002D01*
Y-501168D01*
X301598Y-501252D01*
G01X279398Y-493335D02*
X479398D01*
G01X285031Y-478335D02*
Y-473335D01*
X286551D01*
X287058Y-473585D01*
X287438Y-474168D01*
X287565Y-474835D01*
X287438Y-475502D01*
X287121Y-476002D01*
X286551Y-476252D01*
X285031D01*
G01X290131Y-478335D02*
Y-473335D01*
X291715D01*
X292221Y-473585D01*
X292538Y-473918D01*
X292665Y-474585D01*
X292538Y-475252D01*
X292158Y-475668D01*
X291715Y-475918D01*
X290131D01*
G01X291715D02*
X292665Y-478335D01*
G01X296498D02*
X295991Y-478252D01*
X295548Y-477918D01*
X295168Y-477418D01*
X294915Y-476835D01*
X294788Y-476168D01*
Y-475502D01*
X294915Y-474835D01*
X295168Y-474252D01*
X295548Y-473752D01*
X295991Y-473418D01*
X296498Y-473335D01*
X297005Y-473418D01*
X297448Y-473752D01*
X297828Y-474252D01*
X298081Y-474835D01*
X298208Y-475502D01*
Y-476168D01*
X298081Y-476835D01*
X297828Y-477418D01*
X297448Y-477918D01*
X297005Y-478252D01*
X296498Y-478335D01*
G01X300331Y-477335D02*
X300648Y-477835D01*
X301028Y-478168D01*
X301471Y-478335D01*
X301978Y-478168D01*
X302358Y-477835D01*
X302738Y-477335D01*
X302865Y-476668D01*
Y-473335D01*
G01X307965Y-478335D02*
X305431D01*
Y-473335D01*
X307965D01*
G01X306951Y-475752D02*
X305431D01*
G01X313191Y-473752D02*
X312811Y-473502D01*
X312368Y-473335D01*
X311861D01*
X311291Y-473585D01*
X310848Y-474002D01*
X310531Y-474502D01*
X310278Y-475335D01*
X310215Y-476085D01*
X310341Y-476835D01*
X310531Y-477335D01*
X310911Y-477835D01*
X311355Y-478168D01*
X311798Y-478335D01*
X312241D01*
X312685Y-478168D01*
X313065Y-477918D01*
X313381Y-477585D01*
G01X316898Y-473335D02*
Y-478335D01*
G01X315441Y-473335D02*
X318355D01*
G01X321998Y-478502D02*
X321871Y-478418D01*
Y-478252D01*
X321998Y-478168D01*
X322125Y-478252D01*
Y-478418D01*
X321998Y-478502D01*
G01Y-476252D02*
X321871Y-476168D01*
Y-476002D01*
X321998Y-475918D01*
X322125Y-476002D01*
Y-476168D01*
X321998Y-476252D01*
G01X394258Y-543563D02*
Y-518563D01*
G01X397031Y-520835D02*
Y-525835D01*
X399565D01*
G01X402638Y-520835D02*
X404158D01*
G01X403398D02*
Y-525835D01*
G01X402638D02*
X404158D01*
G01X409005Y-523168D02*
X409258Y-522918D01*
X409448Y-522502D01*
X409575Y-521918D01*
X409448Y-521418D01*
X409195Y-521085D01*
X408751Y-520835D01*
X407041D01*
Y-525835D01*
X409131D01*
X409575Y-525502D01*
X409828Y-525002D01*
X409955Y-524418D01*
X409828Y-523835D01*
X409448Y-523335D01*
X409005Y-523168D01*
X407041D01*
G01X413598Y-526002D02*
X413471Y-525918D01*
Y-525752D01*
X413598Y-525668D01*
X413725Y-525752D01*
Y-525918D01*
X413598Y-526002D01*
G01Y-523752D02*
X413471Y-523668D01*
Y-523502D01*
X413598Y-523418D01*
X413725Y-523502D01*
Y-523668D01*
X413598Y-523752D01*
G01X437258Y-518563D02*
Y-543563D01*
G01X437398Y-518335D02*
Y-543335D01*
G01X441298Y-520835D02*
Y-525835D01*
G01X439841Y-520835D02*
X442755D01*
G01X446398Y-525835D02*
X446018Y-525752D01*
X445638Y-525418D01*
X445385Y-524835D01*
X445258Y-524168D01*
X445385Y-523502D01*
X445638Y-522918D01*
X446018Y-522585D01*
X446398Y-522502D01*
X446778Y-522585D01*
X447158Y-522918D01*
X447411Y-523502D01*
X447475Y-524168D01*
X447411Y-524835D01*
X447158Y-525418D01*
X446778Y-525752D01*
X446398Y-525835D01*
G01X451498D02*
X451118Y-525752D01*
X450738Y-525418D01*
X450485Y-524835D01*
X450358Y-524168D01*
X450485Y-523502D01*
X450738Y-522918D01*
X451118Y-522585D01*
X451498Y-522502D01*
X451878Y-522585D01*
X452258Y-522918D01*
X452511Y-523502D01*
X452575Y-524168D01*
X452511Y-524835D01*
X452258Y-525418D01*
X451878Y-525752D01*
X451498Y-525835D01*
G01X456598D02*
Y-520835D01*
G01X461698Y-526002D02*
X461571Y-525918D01*
Y-525752D01*
X461698Y-525668D01*
X461825Y-525752D01*
Y-525918D01*
X461698Y-526002D01*
G01Y-523752D02*
X461571Y-523668D01*
Y-523502D01*
X461698Y-523418D01*
X461825Y-523502D01*
Y-523668D01*
X461698Y-523752D01*
G01X437398Y-493335D02*
Y-518335D01*
G01X440031Y-500835D02*
Y-495835D01*
X441615D01*
X442121Y-496085D01*
X442438Y-496418D01*
X442565Y-497085D01*
X442438Y-497752D01*
X442058Y-498168D01*
X441615Y-498418D01*
X440031D01*
G01X441615D02*
X442565Y-500835D01*
G01X447665D02*
X445131D01*
Y-495835D01*
X447665D01*
G01X446651Y-498252D02*
X445131D01*
G01X449915Y-495835D02*
X451498Y-500835D01*
X453081Y-495835D01*
G01X456598Y-501002D02*
X456471Y-500918D01*
Y-500752D01*
X456598Y-500668D01*
X456725Y-500752D01*
Y-500918D01*
X456598Y-501002D01*
G01Y-498752D02*
X456471Y-498668D01*
Y-498502D01*
X456598Y-498418D01*
X456725Y-498502D01*
Y-498668D01*
X456598Y-498752D01*
G01X445411Y-546502D02*
X445518Y-546377D01*
X445598Y-546168D01*
X445651Y-545877D01*
X445598Y-545627D01*
X445491Y-545460D01*
X445305Y-545335D01*
X444585D01*
Y-547835D01*
X445465D01*
X445651Y-547668D01*
X445758Y-547418D01*
X445811Y-547127D01*
X445758Y-546835D01*
X445598Y-546585D01*
X445411Y-546502D01*
X444585D01*
G01X447878Y-547835D02*
Y-546168D01*
G01Y-546460D02*
X447771Y-546293D01*
X447611Y-546210D01*
X447425Y-546168D01*
X447238Y-546252D01*
X447078Y-546418D01*
X446971Y-546668D01*
X446918Y-547002D01*
X446971Y-547335D01*
X447078Y-547585D01*
X447238Y-547752D01*
X447425Y-547835D01*
X447611Y-547793D01*
X447771Y-547668D01*
X447878Y-547502D01*
G01X449198Y-547543D02*
X449331Y-547710D01*
X449518Y-547835D01*
X449678D01*
X449838Y-547752D01*
X449945Y-547627D01*
X449998Y-547460D01*
X449971Y-547210D01*
X449865Y-547085D01*
X449385Y-546835D01*
X449278Y-546543D01*
X449331Y-546335D01*
X449438Y-546210D01*
X449598Y-546168D01*
X449758Y-546210D01*
X449918Y-546335D01*
G01X451398Y-546710D02*
X452251D01*
X452171Y-546418D01*
X452038Y-546252D01*
X451851Y-546168D01*
X451665Y-546210D01*
X451505Y-546335D01*
X451398Y-546627D01*
X451345Y-546877D01*
Y-547127D01*
X451398Y-547377D01*
X451531Y-547627D01*
X451691Y-547793D01*
X451878Y-547835D01*
X452065Y-547752D01*
X452251Y-547502D01*
G01X453518Y-547835D02*
Y-545335D01*
G01Y-546585D02*
X453651Y-546335D01*
X453811Y-546210D01*
X453971Y-546168D01*
X454211Y-546252D01*
X454371Y-546418D01*
X454478Y-546710D01*
Y-547043D01*
X454425Y-547377D01*
X454318Y-547627D01*
X454131Y-547793D01*
X453971Y-547835D01*
X453811Y-547793D01*
X453651Y-547668D01*
X453518Y-547460D01*
G01X456198Y-547835D02*
X456038Y-547793D01*
X455878Y-547627D01*
X455771Y-547335D01*
X455718Y-547002D01*
X455771Y-546668D01*
X455878Y-546377D01*
X456038Y-546210D01*
X456198Y-546168D01*
X456358Y-546210D01*
X456518Y-546377D01*
X456625Y-546668D01*
X456651Y-547002D01*
X456625Y-547335D01*
X456518Y-547627D01*
X456358Y-547793D01*
X456198Y-547835D01*
G01X458878D02*
Y-546168D01*
G01Y-546460D02*
X458771Y-546293D01*
X458611Y-546210D01*
X458425Y-546168D01*
X458238Y-546252D01*
X458078Y-546418D01*
X457971Y-546668D01*
X457918Y-547002D01*
X457971Y-547335D01*
X458078Y-547585D01*
X458238Y-547752D01*
X458425Y-547835D01*
X458611Y-547793D01*
X458771Y-547668D01*
X458878Y-547502D01*
G01X460225Y-547835D02*
Y-546168D01*
G01Y-546502D02*
X460358Y-546335D01*
X460491Y-546210D01*
X460678Y-546168D01*
X460811Y-546210D01*
X460971Y-546335D01*
G01X463278Y-545335D02*
Y-547835D01*
G01Y-547460D02*
X463171Y-547668D01*
X463011Y-547793D01*
X462825Y-547835D01*
X462611Y-547752D01*
X462451Y-547543D01*
X462345Y-547293D01*
X462318Y-547002D01*
X462345Y-546710D01*
X462451Y-546460D01*
X462611Y-546252D01*
X462825Y-546168D01*
X463011Y-546210D01*
X463145Y-546293D01*
X463278Y-546460D01*
G01X466665Y-547835D02*
Y-545335D01*
X467331D01*
X467545Y-545460D01*
X467678Y-545627D01*
X467731Y-545960D01*
X467678Y-546293D01*
X467518Y-546502D01*
X467331Y-546627D01*
X466665D01*
G01X467331D02*
X467731Y-547835D01*
G01X468998Y-546710D02*
X469851D01*
X469771Y-546418D01*
X469638Y-546252D01*
X469451Y-546168D01*
X469265Y-546210D01*
X469105Y-546335D01*
X468998Y-546627D01*
X468945Y-546877D01*
Y-547127D01*
X468998Y-547377D01*
X469131Y-547627D01*
X469291Y-547793D01*
X469478Y-547835D01*
X469665Y-547752D01*
X469851Y-547502D01*
G01X471118Y-546168D02*
X471598Y-547835D01*
X472078Y-546168D01*
G01X473798Y-547918D02*
X473745Y-547877D01*
Y-547793D01*
X473798Y-547752D01*
X473851Y-547793D01*
Y-547877D01*
X473798Y-547918D01*
G01X475545Y-547543D02*
X475731Y-547752D01*
X475945Y-547835D01*
X476158Y-547752D01*
X476345Y-547502D01*
X476478Y-547127D01*
X476531Y-546752D01*
Y-546293D01*
X476478Y-545918D01*
X476345Y-545585D01*
X476185Y-545418D01*
X475998Y-545335D01*
X475785Y-545418D01*
X475625Y-545585D01*
X475518Y-545835D01*
X475465Y-546168D01*
X475518Y-546460D01*
X475651Y-546752D01*
X475811Y-546918D01*
X475998Y-546960D01*
X476211Y-546877D01*
X476371Y-546668D01*
X476531Y-546293D01*
G01X478411Y-546502D02*
X478518Y-546377D01*
X478598Y-546168D01*
X478651Y-545877D01*
X478598Y-545627D01*
X478491Y-545460D01*
X478305Y-545335D01*
X477585D01*
Y-547835D01*
X478465D01*
X478651Y-547668D01*
X478758Y-547418D01*
X478811Y-547127D01*
X478758Y-546835D01*
X478598Y-546585D01*
X478411Y-546502D01*
X477585D01*
G01X-1490433Y-1677216D02*
Y3837819D01*
X4496476D01*
Y-1677216D01*
X-1490433D01*
G01X-7782Y-515685D02*
X-6215D01*
Y-517575D01*
X-6685Y-518205D01*
X-7234Y-518625D01*
X-8017Y-518835D01*
X-8800Y-518625D01*
X-9349Y-518205D01*
X-9819Y-517575D01*
X-10132Y-516840D01*
X-10289Y-516000D01*
Y-515265D01*
X-10132Y-514635D01*
X-9819Y-513900D01*
X-9349Y-513270D01*
X-8879Y-512850D01*
X-8252Y-512535D01*
X-7704D01*
X-7077Y-512745D01*
X-6607Y-513165D01*
G01X-3675Y-512535D02*
Y-517050D01*
X-3362Y-517995D01*
X-2735Y-518625D01*
X-1952Y-518835D01*
X-1169Y-518625D01*
X-542Y-517995D01*
X-229Y-517050D01*
Y-512535D01*
G01X3408D02*
X5288D01*
G01X4348D02*
Y-518835D01*
G01X3408D02*
X5288D01*
G01X9003Y-517995D02*
X9630Y-518520D01*
X10335Y-518835D01*
X10961D01*
X11588Y-518520D01*
X12058Y-517995D01*
X12293Y-517260D01*
X12136Y-516525D01*
X11745Y-515895D01*
X11040Y-515475D01*
X10100Y-515265D01*
X9551Y-514845D01*
X9316Y-514110D01*
X9473Y-513375D01*
X9865Y-512850D01*
X10413Y-512535D01*
X10961D01*
X11510Y-512745D01*
X11980Y-513270D01*
G01X15303Y-518835D02*
Y-512535D01*
G01X18593D02*
Y-518835D01*
G01Y-515685D02*
X15303D01*
G01X21290Y-518835D02*
X23248Y-512535D01*
X25206Y-518835D01*
G01X24501Y-516630D02*
X21995D01*
G01X27746Y-518835D02*
Y-512535D01*
X31350Y-518835D01*
Y-512535D01*
G01X40425Y-518835D02*
Y-512535D01*
X41991D01*
X42618Y-512850D01*
X43088Y-513270D01*
X43480Y-513900D01*
X43793Y-514635D01*
X43871Y-515685D01*
X43793Y-516735D01*
X43480Y-517470D01*
X43088Y-518100D01*
X42618Y-518520D01*
X41991Y-518835D01*
X40425D01*
G01X47508Y-512535D02*
X49388D01*
G01X48448D02*
Y-518835D01*
G01X47508D02*
X49388D01*
G01X53103Y-517995D02*
X53730Y-518520D01*
X54435Y-518835D01*
X55061D01*
X55688Y-518520D01*
X56158Y-517995D01*
X56393Y-517260D01*
X56236Y-516525D01*
X55845Y-515895D01*
X55140Y-515475D01*
X54200Y-515265D01*
X53651Y-514845D01*
X53416Y-514110D01*
X53573Y-513375D01*
X53965Y-512850D01*
X54513Y-512535D01*
X55061D01*
X55610Y-512745D01*
X56080Y-513270D01*
G01X61048Y-512535D02*
Y-518835D01*
G01X59246Y-512535D02*
X62850D01*
G01X67348Y-519045D02*
X67191Y-518940D01*
Y-518730D01*
X67348Y-518625D01*
X67505Y-518730D01*
Y-518940D01*
X67348Y-519045D01*
G01X73491Y-519990D02*
X73805Y-518625D01*
G01X79948Y-512535D02*
Y-518835D01*
G01X78146Y-512535D02*
X81750D01*
G01X84290Y-518835D02*
X86248Y-512535D01*
X88206Y-518835D01*
G01X87501Y-516630D02*
X84995D01*
G01X92548Y-518835D02*
X91921Y-518730D01*
X91373Y-518310D01*
X90903Y-517680D01*
X90590Y-516945D01*
X90433Y-516105D01*
Y-515265D01*
X90590Y-514425D01*
X90903Y-513690D01*
X91373Y-513060D01*
X91921Y-512640D01*
X92548Y-512535D01*
X93175Y-512640D01*
X93723Y-513060D01*
X94193Y-513690D01*
X94506Y-514425D01*
X94663Y-515265D01*
Y-516105D01*
X94506Y-516945D01*
X94193Y-517680D01*
X93723Y-518310D01*
X93175Y-518730D01*
X92548Y-518835D01*
G01X98848D02*
Y-516000D01*
X97281Y-512535D01*
G01X100415D02*
X98848Y-516000D01*
G01X103425Y-512535D02*
Y-517050D01*
X103738Y-517995D01*
X104365Y-518625D01*
X105148Y-518835D01*
X105931Y-518625D01*
X106558Y-517995D01*
X106871Y-517050D01*
Y-512535D01*
G01X109490Y-518835D02*
X111448Y-512535D01*
X113406Y-518835D01*
G01X112701Y-516630D02*
X110195D01*
G01X115946Y-518835D02*
Y-512535D01*
X119550Y-518835D01*
Y-512535D01*
G01X-6529Y-523060D02*
X-6999Y-522745D01*
X-7547Y-522535D01*
X-8174D01*
X-8879Y-522850D01*
X-9427Y-523375D01*
X-9819Y-524005D01*
X-10132Y-525055D01*
X-10210Y-526000D01*
X-10054Y-526945D01*
X-9819Y-527575D01*
X-9349Y-528205D01*
X-8800Y-528625D01*
X-8252Y-528835D01*
X-7704D01*
X-7155Y-528625D01*
X-6685Y-528310D01*
X-6294Y-527890D01*
G01X-2892Y-522535D02*
X-1012D01*
G01X-1952D02*
Y-528835D01*
G01X-2892D02*
X-1012D01*
G01X4348Y-522535D02*
Y-528835D01*
G01X2546Y-522535D02*
X6150D01*
G01X10648Y-528835D02*
Y-526000D01*
X9081Y-522535D01*
G01X12215D02*
X10648Y-526000D01*
G01X21525Y-527575D02*
X21995Y-528310D01*
X22621Y-528730D01*
X23326Y-528835D01*
X23953Y-528730D01*
X24580Y-528205D01*
X24971Y-527575D01*
X25050Y-526945D01*
X24893Y-526210D01*
X24345Y-525685D01*
X23796Y-525475D01*
X23091D01*
G01X23796D02*
X24266Y-525160D01*
X24658Y-524635D01*
X24815Y-524005D01*
X24658Y-523375D01*
X24266Y-522850D01*
X23561Y-522535D01*
X22856Y-522640D01*
X22151Y-523060D01*
G01X27825Y-527575D02*
X28295Y-528310D01*
X28921Y-528730D01*
X29626Y-528835D01*
X30253Y-528730D01*
X30880Y-528205D01*
X31271Y-527575D01*
X31350Y-526945D01*
X31193Y-526210D01*
X30645Y-525685D01*
X30096Y-525475D01*
X29391D01*
G01X30096D02*
X30566Y-525160D01*
X30958Y-524635D01*
X31115Y-524005D01*
X30958Y-523375D01*
X30566Y-522850D01*
X29861Y-522535D01*
X29156Y-522640D01*
X28451Y-523060D01*
G01X34125Y-527575D02*
X34595Y-528310D01*
X35221Y-528730D01*
X35926Y-528835D01*
X36553Y-528730D01*
X37180Y-528205D01*
X37571Y-527575D01*
X37650Y-526945D01*
X37493Y-526210D01*
X36945Y-525685D01*
X36396Y-525475D01*
X35691D01*
G01X36396D02*
X36866Y-525160D01*
X37258Y-524635D01*
X37415Y-524005D01*
X37258Y-523375D01*
X36866Y-522850D01*
X36161Y-522535D01*
X35456Y-522640D01*
X34751Y-523060D01*
G01X41991Y-528835D02*
X42148Y-527470D01*
X42383Y-526315D01*
X42696Y-525265D01*
X43088Y-524110D01*
X43715Y-522535D01*
X40581D01*
G01X48291Y-528835D02*
X48448Y-527470D01*
X48683Y-526315D01*
X48996Y-525265D01*
X49388Y-524110D01*
X50015Y-522535D01*
X46881D01*
G01X54591Y-529990D02*
X54905Y-528625D01*
G01X61048Y-522535D02*
Y-528835D01*
G01X59246Y-522535D02*
X62850D01*
G01X65390Y-528835D02*
X67348Y-522535D01*
X69306Y-528835D01*
G01X68601Y-526630D02*
X66095D01*
G01X72708Y-522535D02*
X74588D01*
G01X73648D02*
Y-528835D01*
G01X72708D02*
X74588D01*
G01X77598Y-522535D02*
X78695Y-528835D01*
X79948Y-522535D01*
X81201Y-528835D01*
X82298Y-522535D01*
G01X84290Y-528835D02*
X86248Y-522535D01*
X88206Y-528835D01*
G01X87501Y-526630D02*
X84995D01*
G01X90746Y-528835D02*
Y-522535D01*
X94350Y-528835D01*
Y-522535D01*
G01X104756Y-530935D02*
X103973Y-529885D01*
X103581Y-528835D01*
Y-524635D01*
X103973Y-523585D01*
X104756Y-522535D01*
G01X116181Y-528835D02*
Y-522535D01*
X118140D01*
X118766Y-522850D01*
X119158Y-523270D01*
X119315Y-524110D01*
X119158Y-524950D01*
X118688Y-525475D01*
X118140Y-525790D01*
X116181D01*
G01X118140D02*
X119315Y-528835D01*
G01X124048Y-529045D02*
X123891Y-528940D01*
Y-528730D01*
X124048Y-528625D01*
X124205Y-528730D01*
Y-528940D01*
X124048Y-529045D01*
G01X130348Y-528835D02*
X129721Y-528730D01*
X129173Y-528310D01*
X128703Y-527680D01*
X128390Y-526945D01*
X128233Y-526105D01*
Y-525265D01*
X128390Y-524425D01*
X128703Y-523690D01*
X129173Y-523060D01*
X129721Y-522640D01*
X130348Y-522535D01*
X130975Y-522640D01*
X131523Y-523060D01*
X131993Y-523690D01*
X132306Y-524425D01*
X132463Y-525265D01*
Y-526105D01*
X132306Y-526945D01*
X131993Y-527680D01*
X131523Y-528310D01*
X130975Y-528730D01*
X130348Y-528835D01*
G01X136648Y-529045D02*
X136491Y-528940D01*
Y-528730D01*
X136648Y-528625D01*
X136805Y-528730D01*
Y-528940D01*
X136648Y-529045D01*
G01X144671Y-523060D02*
X144201Y-522745D01*
X143653Y-522535D01*
X143026D01*
X142321Y-522850D01*
X141773Y-523375D01*
X141381Y-524005D01*
X141068Y-525055D01*
X140990Y-526000D01*
X141146Y-526945D01*
X141381Y-527575D01*
X141851Y-528205D01*
X142400Y-528625D01*
X142948Y-528835D01*
X143496D01*
X144045Y-528625D01*
X144515Y-528310D01*
X144906Y-527890D01*
G01X149248Y-529045D02*
X149091Y-528940D01*
Y-528730D01*
X149248Y-528625D01*
X149405Y-528730D01*
Y-528940D01*
X149248Y-529045D01*
G01X155940Y-530935D02*
X156723Y-529885D01*
X157115Y-528835D01*
Y-524635D01*
X156723Y-523585D01*
X155940Y-522535D01*
G01X-10054Y-508835D02*
Y-502535D01*
X-6450Y-508835D01*
Y-502535D01*
G01X-1952Y-508835D02*
X-2579Y-508730D01*
X-3127Y-508310D01*
X-3597Y-507680D01*
X-3910Y-506945D01*
X-4067Y-506105D01*
Y-505265D01*
X-3910Y-504425D01*
X-3597Y-503690D01*
X-3127Y-503060D01*
X-2579Y-502640D01*
X-1952Y-502535D01*
X-1325Y-502640D01*
X-777Y-503060D01*
X-307Y-503690D01*
X6Y-504425D01*
X163Y-505265D01*
Y-506105D01*
X6Y-506945D01*
X-307Y-507680D01*
X-777Y-508310D01*
X-1325Y-508730D01*
X-1952Y-508835D01*
G01X4348Y-509045D02*
X4191Y-508940D01*
Y-508730D01*
X4348Y-508625D01*
X4505Y-508730D01*
Y-508940D01*
X4348Y-509045D01*
G01X9160Y-503585D02*
X9630Y-502955D01*
X10178Y-502640D01*
X10805Y-502535D01*
X11588Y-502745D01*
X12136Y-503270D01*
X12293Y-503900D01*
X12215Y-504530D01*
X11901Y-505055D01*
X10335Y-506105D01*
X9630Y-506840D01*
X9160Y-507890D01*
X9003Y-508835D01*
X12293D01*
G01X16948D02*
Y-502535D01*
X16008Y-503795D01*
G01Y-508835D02*
X17888D01*
G01X23248D02*
Y-502535D01*
X22308Y-503795D01*
G01Y-508835D02*
X24188D01*
G01X29391Y-509990D02*
X29705Y-508625D01*
G01X33498Y-502535D02*
X34595Y-508835D01*
X35848Y-502535D01*
X37101Y-508835D01*
X38198Y-502535D01*
G01X43715Y-508835D02*
X40581D01*
Y-502535D01*
X43715D01*
G01X42461Y-505580D02*
X40581D01*
G01X46646Y-508835D02*
Y-502535D01*
X50250Y-508835D01*
Y-502535D01*
G01X53103Y-508835D02*
Y-502535D01*
G01X56393D02*
Y-508835D01*
G01Y-505685D02*
X53103D01*
G01X59325Y-502535D02*
Y-507050D01*
X59638Y-507995D01*
X60265Y-508625D01*
X61048Y-508835D01*
X61831Y-508625D01*
X62458Y-507995D01*
X62771Y-507050D01*
Y-502535D01*
G01X65390Y-508835D02*
X67348Y-502535D01*
X69306Y-508835D01*
G01X68601Y-506630D02*
X66095D01*
G01X78460Y-503585D02*
X78930Y-502955D01*
X79478Y-502640D01*
X80105Y-502535D01*
X80888Y-502745D01*
X81436Y-503270D01*
X81593Y-503900D01*
X81515Y-504530D01*
X81201Y-505055D01*
X79635Y-506105D01*
X78930Y-506840D01*
X78460Y-507890D01*
X78303Y-508835D01*
X81593D01*
G01X84446D02*
Y-502535D01*
X88050Y-508835D01*
Y-502535D01*
G01X90825Y-508835D02*
Y-502535D01*
X92391D01*
X93018Y-502850D01*
X93488Y-503270D01*
X93880Y-503900D01*
X94193Y-504635D01*
X94271Y-505685D01*
X94193Y-506735D01*
X93880Y-507470D01*
X93488Y-508100D01*
X93018Y-508520D01*
X92391Y-508835D01*
X90825D01*
G01X103581D02*
Y-502535D01*
X105540D01*
X106166Y-502850D01*
X106558Y-503270D01*
X106715Y-504110D01*
X106558Y-504950D01*
X106088Y-505475D01*
X105540Y-505790D01*
X103581D01*
G01X105540D02*
X106715Y-508835D01*
G01X109725D02*
Y-502535D01*
X111291D01*
X111918Y-502850D01*
X112388Y-503270D01*
X112780Y-503900D01*
X113093Y-504635D01*
X113171Y-505685D01*
X113093Y-506735D01*
X112780Y-507470D01*
X112388Y-508100D01*
X111918Y-508520D01*
X111291Y-508835D01*
X109725D01*
G01X117748Y-509045D02*
X117591Y-508940D01*
Y-508730D01*
X117748Y-508625D01*
X117905Y-508730D01*
Y-508940D01*
X117748Y-509045D01*
G01X14048Y-498135D02*
X11528Y-497718D01*
X9323Y-496052D01*
X7433Y-493552D01*
X6173Y-490635D01*
X5543Y-487302D01*
Y-483968D01*
X6173Y-480635D01*
X7433Y-477718D01*
X9323Y-475219D01*
X11528Y-473552D01*
X14048Y-473135D01*
X16568Y-473552D01*
X18773Y-475219D01*
X20663Y-477718D01*
X21923Y-480635D01*
X22553Y-483968D01*
Y-487302D01*
X21923Y-490635D01*
X20663Y-493552D01*
X18773Y-496052D01*
X16568Y-497718D01*
X14048Y-498135D01*
G01X16568Y-491468D02*
X20348Y-498135D01*
G01X33893Y-481469D02*
Y-493135D01*
X35153Y-496052D01*
X37043Y-497718D01*
X39248Y-498135D01*
X41453Y-497718D01*
X43343Y-496052D01*
X44603Y-493135D01*
G01Y-498135D02*
Y-481469D01*
G01X70118Y-498135D02*
Y-481469D01*
G01Y-484385D02*
X68858Y-482719D01*
X66968Y-481885D01*
X64763Y-481469D01*
X62558Y-482302D01*
X60668Y-483968D01*
X59408Y-486469D01*
X58778Y-489802D01*
X59408Y-493135D01*
X60668Y-495636D01*
X62558Y-497302D01*
X64763Y-498135D01*
X66968Y-497718D01*
X68858Y-496469D01*
X70118Y-494802D01*
G01X84293Y-498135D02*
Y-481469D01*
G01Y-485635D02*
X85553Y-483552D01*
X87443Y-481885D01*
X89963Y-481469D01*
X92168Y-481885D01*
X94058Y-483552D01*
X95003Y-486469D01*
Y-498135D01*
G01X114848Y-473135D02*
Y-498135D01*
G01X110438Y-481469D02*
X119258D01*
G01X145718Y-498135D02*
Y-481469D01*
G01Y-484385D02*
X144458Y-482719D01*
X142568Y-481885D01*
X140363Y-481469D01*
X138158Y-482302D01*
X136268Y-483968D01*
X135008Y-486469D01*
X134378Y-489802D01*
X135008Y-493135D01*
X136268Y-495636D01*
X138158Y-497302D01*
X140363Y-498135D01*
X142568Y-497718D01*
X144458Y-496469D01*
X145718Y-494802D01*
G01X185398Y-477835D02*
Y-485835D01*
X189398D01*
G01X197198D02*
Y-480502D01*
G01Y-481435D02*
X196798Y-480902D01*
X196198Y-480635D01*
X195498Y-480502D01*
X194798Y-480768D01*
X194198Y-481302D01*
X193798Y-482102D01*
X193598Y-483168D01*
X193798Y-484235D01*
X194198Y-485035D01*
X194798Y-485568D01*
X195498Y-485835D01*
X196198Y-485702D01*
X196798Y-485302D01*
X197198Y-484769D01*
G01X201298Y-488235D02*
X201898Y-488502D01*
X202698Y-488235D01*
X203198Y-487702D01*
X203598Y-487035D01*
X204198Y-484902D01*
X205498Y-480502D01*
G01X202298D02*
X204198Y-484902D01*
G01X209898Y-482235D02*
X213098D01*
X212798Y-481302D01*
X212298Y-480768D01*
X211598Y-480502D01*
X210898Y-480635D01*
X210298Y-481035D01*
X209898Y-481968D01*
X209698Y-482769D01*
Y-483568D01*
X209898Y-484368D01*
X210398Y-485168D01*
X210998Y-485702D01*
X211698Y-485835D01*
X212398Y-485568D01*
X213098Y-484769D01*
G01X217998Y-485835D02*
Y-480502D01*
G01Y-481568D02*
X218498Y-481035D01*
X218998Y-480635D01*
X219698Y-480502D01*
X220198Y-480635D01*
X220798Y-481035D01*
G01X211398Y-535835D02*
Y-532235D01*
X209398Y-527835D01*
G01X213398D02*
X211398Y-532235D01*
G01X217698Y-530502D02*
Y-534235D01*
X218098Y-535168D01*
X218698Y-535702D01*
X219398Y-535835D01*
X220098Y-535702D01*
X220698Y-535168D01*
X221098Y-534235D01*
G01Y-535835D02*
Y-530502D01*
G01X225698Y-535835D02*
Y-530502D01*
G01Y-531835D02*
X226098Y-531168D01*
X226698Y-530635D01*
X227498Y-530502D01*
X228198Y-530635D01*
X228798Y-531168D01*
X229098Y-532102D01*
Y-535835D01*
G01X237198D02*
Y-530502D01*
G01Y-531435D02*
X236798Y-530902D01*
X236198Y-530635D01*
X235498Y-530502D01*
X234798Y-530768D01*
X234198Y-531302D01*
X233798Y-532102D01*
X233598Y-533168D01*
X233798Y-534235D01*
X234198Y-535035D01*
X234798Y-535568D01*
X235498Y-535835D01*
X236198Y-535702D01*
X236798Y-535302D01*
X237198Y-534769D01*
G01X218898Y-502835D02*
Y-510835D01*
G01X216598Y-502835D02*
X221198D01*
G01X226898Y-510835D02*
X226098Y-510702D01*
X225398Y-510168D01*
X224798Y-509368D01*
X224398Y-508435D01*
X224198Y-507368D01*
Y-506302D01*
X224398Y-505235D01*
X224798Y-504302D01*
X225398Y-503502D01*
X226098Y-502968D01*
X226898Y-502835D01*
X227698Y-502968D01*
X228398Y-503502D01*
X228998Y-504302D01*
X229398Y-505235D01*
X229598Y-506302D01*
Y-507368D01*
X229398Y-508435D01*
X228998Y-509368D01*
X228398Y-510168D01*
X227698Y-510702D01*
X226898Y-510835D01*
G01X232898D02*
Y-502835D01*
X235298D01*
X236098Y-503235D01*
X236698Y-504168D01*
X236898Y-505235D01*
X236698Y-506302D01*
X236198Y-507102D01*
X235298Y-507502D01*
X232898D01*
G01X238898Y-485835D02*
Y-477835D01*
X237698Y-479435D01*
G01Y-485835D02*
X240098D01*
G01X311998Y-529168D02*
X312598Y-528368D01*
X313298Y-527968D01*
X314098Y-527835D01*
X315098Y-528102D01*
X315798Y-528768D01*
X315998Y-529568D01*
X315898Y-530369D01*
X315498Y-531035D01*
X313498Y-532368D01*
X312598Y-533302D01*
X311998Y-534635D01*
X311798Y-535835D01*
X315998D01*
G01X321898Y-527835D02*
X321098Y-528102D01*
X320498Y-528768D01*
X320098Y-529568D01*
X319798Y-530635D01*
X319698Y-531835D01*
X319798Y-533035D01*
X320098Y-534102D01*
X320498Y-534902D01*
X321098Y-535568D01*
X321898Y-535835D01*
X322698Y-535568D01*
X323298Y-534902D01*
X323698Y-534102D01*
X323998Y-533035D01*
X324098Y-531835D01*
X323998Y-530635D01*
X323698Y-529568D01*
X323298Y-528768D01*
X322698Y-528102D01*
X321898Y-527835D01*
G01X327998Y-529168D02*
X328598Y-528368D01*
X329298Y-527968D01*
X330098Y-527835D01*
X331098Y-528102D01*
X331798Y-528768D01*
X331998Y-529568D01*
X331898Y-530369D01*
X331498Y-531035D01*
X329498Y-532368D01*
X328598Y-533302D01*
X327998Y-534635D01*
X327798Y-535835D01*
X331998D01*
G01X335698Y-534235D02*
X336298Y-535168D01*
X337098Y-535702D01*
X337998Y-535835D01*
X338798Y-535702D01*
X339598Y-535035D01*
X340098Y-534235D01*
X340198Y-533435D01*
X339998Y-532502D01*
X339298Y-531835D01*
X338598Y-531568D01*
X337698D01*
G01X338598D02*
X339198Y-531168D01*
X339698Y-530502D01*
X339898Y-529702D01*
X339698Y-528902D01*
X339198Y-528235D01*
X338298Y-527835D01*
X337398Y-527968D01*
X336498Y-528502D01*
G01X344098Y-536102D02*
X347698Y-527835D01*
G01X353898D02*
X353098Y-528102D01*
X352498Y-528768D01*
X352098Y-529568D01*
X351798Y-530635D01*
X351698Y-531835D01*
X351798Y-533035D01*
X352098Y-534102D01*
X352498Y-534902D01*
X353098Y-535568D01*
X353898Y-535835D01*
X354698Y-535568D01*
X355298Y-534902D01*
X355698Y-534102D01*
X355998Y-533035D01*
X356098Y-531835D01*
X355998Y-530635D01*
X355698Y-529568D01*
X355298Y-528768D01*
X354698Y-528102D01*
X353898Y-527835D01*
G01X361898Y-535835D02*
Y-527835D01*
X360698Y-529435D01*
G01Y-535835D02*
X363098D01*
G01X368098Y-536102D02*
X371698Y-527835D01*
G01X377898D02*
X377098Y-528102D01*
X376498Y-528768D01*
X376098Y-529568D01*
X375798Y-530635D01*
X375698Y-531835D01*
X375798Y-533035D01*
X376098Y-534102D01*
X376498Y-534902D01*
X377098Y-535568D01*
X377898Y-535835D01*
X378698Y-535568D01*
X379298Y-534902D01*
X379698Y-534102D01*
X379998Y-533035D01*
X380098Y-531835D01*
X379998Y-530635D01*
X379698Y-529568D01*
X379298Y-528768D01*
X378698Y-528102D01*
X377898Y-527835D01*
G01X384198Y-534902D02*
X384898Y-535568D01*
X385698Y-535835D01*
X386498Y-535568D01*
X387198Y-534769D01*
X387698Y-533568D01*
X387898Y-532368D01*
Y-530902D01*
X387698Y-529702D01*
X387198Y-528635D01*
X386598Y-528102D01*
X385898Y-527835D01*
X385098Y-528102D01*
X384498Y-528635D01*
X384098Y-529435D01*
X383898Y-530502D01*
X384098Y-531435D01*
X384598Y-532368D01*
X385198Y-532902D01*
X385898Y-533035D01*
X386698Y-532769D01*
X387298Y-532102D01*
X387898Y-530902D01*
G01X311698Y-510835D02*
Y-502835D01*
X313698D01*
X314498Y-503235D01*
X315098Y-503768D01*
X315598Y-504568D01*
X315998Y-505502D01*
X316098Y-506835D01*
X315998Y-508168D01*
X315598Y-509102D01*
X315098Y-509902D01*
X314498Y-510435D01*
X313698Y-510835D01*
X311698D01*
G01X319398D02*
X321898Y-502835D01*
X324398Y-510835D01*
G01X323498Y-508035D02*
X320298D01*
G01X329898Y-502835D02*
X329098Y-503102D01*
X328498Y-503768D01*
X328098Y-504568D01*
X327798Y-505635D01*
X327698Y-506835D01*
X327798Y-508035D01*
X328098Y-509102D01*
X328498Y-509902D01*
X329098Y-510568D01*
X329898Y-510835D01*
X330698Y-510568D01*
X331298Y-509902D01*
X331698Y-509102D01*
X331998Y-508035D01*
X332098Y-506835D01*
X331998Y-505635D01*
X331698Y-504568D01*
X331298Y-503768D01*
X330698Y-503102D01*
X329898Y-502835D01*
G01X335998Y-510835D02*
Y-502835D01*
X339798D01*
G01X338398Y-506702D02*
X335998D01*
G01X345898Y-502835D02*
X345098Y-503102D01*
X344498Y-503768D01*
X344098Y-504568D01*
X343798Y-505635D01*
X343698Y-506835D01*
X343798Y-508035D01*
X344098Y-509102D01*
X344498Y-509902D01*
X345098Y-510568D01*
X345898Y-510835D01*
X346698Y-510568D01*
X347298Y-509902D01*
X347698Y-509102D01*
X347998Y-508035D01*
X348098Y-506835D01*
X347998Y-505635D01*
X347698Y-504568D01*
X347298Y-503768D01*
X346698Y-503102D01*
X345898Y-502835D01*
G01X353898D02*
Y-510835D01*
G01X351598Y-502835D02*
X356198D01*
G01X363898Y-510835D02*
X359898D01*
Y-502835D01*
X363898D01*
G01X362298Y-506702D02*
X359898D01*
G01X370698Y-506568D02*
X371098Y-506168D01*
X371398Y-505502D01*
X371598Y-504568D01*
X371398Y-503768D01*
X370998Y-503235D01*
X370298Y-502835D01*
X367598D01*
Y-510835D01*
X370898D01*
X371598Y-510302D01*
X371998Y-509502D01*
X372198Y-508568D01*
X371998Y-507635D01*
X371398Y-506835D01*
X370698Y-506568D01*
X367598D01*
G01X376698Y-502835D02*
X379098D01*
G01X377898D02*
Y-510835D01*
G01X376698D02*
X379098D01*
G01X383998D02*
Y-502835D01*
X387798D01*
G01X386398Y-506702D02*
X383998D01*
G01X393898Y-502835D02*
X393098Y-503102D01*
X392498Y-503768D01*
X392098Y-504568D01*
X391798Y-505635D01*
X391698Y-506835D01*
X391798Y-508035D01*
X392098Y-509102D01*
X392498Y-509902D01*
X393098Y-510568D01*
X393898Y-510835D01*
X394698Y-510568D01*
X395298Y-509902D01*
X395698Y-509102D01*
X395998Y-508035D01*
X396098Y-506835D01*
X395998Y-505635D01*
X395698Y-504568D01*
X395298Y-503768D01*
X394698Y-503102D01*
X393898Y-502835D01*
G01X329498Y-485835D02*
Y-477835D01*
X333298D01*
G01X331898Y-481702D02*
X329498D01*
G01X339398Y-477835D02*
X338598Y-478102D01*
X337998Y-478768D01*
X337598Y-479568D01*
X337298Y-480635D01*
X337198Y-481835D01*
X337298Y-483035D01*
X337598Y-484102D01*
X337998Y-484902D01*
X338598Y-485568D01*
X339398Y-485835D01*
X340198Y-485568D01*
X340798Y-484902D01*
X341198Y-484102D01*
X341498Y-483035D01*
X341598Y-481835D01*
X341498Y-480635D01*
X341198Y-479568D01*
X340798Y-478768D01*
X340198Y-478102D01*
X339398Y-477835D01*
G01X347398D02*
Y-485835D01*
G01X345098Y-477835D02*
X349698D01*
G01X352398Y-488502D02*
X358398D01*
G01X361898Y-482235D02*
X365098D01*
X364798Y-481302D01*
X364298Y-480768D01*
X363598Y-480502D01*
X362898Y-480635D01*
X362298Y-481035D01*
X361898Y-481968D01*
X361698Y-482769D01*
Y-483568D01*
X361898Y-484368D01*
X362398Y-485168D01*
X362998Y-485702D01*
X363698Y-485835D01*
X364398Y-485568D01*
X365098Y-484769D01*
G01X369898Y-480502D02*
X372898Y-485835D01*
G01Y-480502D02*
X369898Y-485835D01*
G01X377598Y-488502D02*
Y-480502D01*
G01Y-481702D02*
X378098Y-481035D01*
X378598Y-480635D01*
X379398Y-480502D01*
X380098Y-480635D01*
X380798Y-481302D01*
X381098Y-482235D01*
X381198Y-483168D01*
X381098Y-484102D01*
X380798Y-485035D01*
X380198Y-485568D01*
X379398Y-485835D01*
X378698Y-485702D01*
X377998Y-485302D01*
X377598Y-484769D01*
G01X389198Y-485835D02*
Y-480502D01*
G01Y-481435D02*
X388798Y-480902D01*
X388198Y-480635D01*
X387498Y-480502D01*
X386798Y-480768D01*
X386198Y-481302D01*
X385798Y-482102D01*
X385598Y-483168D01*
X385798Y-484235D01*
X386198Y-485035D01*
X386798Y-485568D01*
X387498Y-485835D01*
X388198Y-485702D01*
X388798Y-485302D01*
X389198Y-484769D01*
G01X393698Y-485835D02*
Y-480502D01*
G01Y-481835D02*
X394098Y-481168D01*
X394698Y-480635D01*
X395498Y-480502D01*
X396198Y-480635D01*
X396798Y-481168D01*
X397098Y-482102D01*
Y-485835D01*
G01X405198Y-477835D02*
Y-485835D01*
G01Y-484635D02*
X404798Y-485302D01*
X404198Y-485702D01*
X403498Y-485835D01*
X402698Y-485568D01*
X402098Y-484902D01*
X401698Y-484102D01*
X401598Y-483168D01*
X401698Y-482235D01*
X402098Y-481435D01*
X402698Y-480768D01*
X403498Y-480502D01*
X404198Y-480635D01*
X404698Y-480902D01*
X405198Y-481435D01*
G01X409898Y-482235D02*
X413098D01*
X412798Y-481302D01*
X412298Y-480768D01*
X411598Y-480502D01*
X410898Y-480635D01*
X410298Y-481035D01*
X409898Y-481968D01*
X409698Y-482769D01*
Y-483568D01*
X409898Y-484368D01*
X410398Y-485168D01*
X410998Y-485702D01*
X411698Y-485835D01*
X412398Y-485568D01*
X413098Y-484769D01*
G01X417998Y-485835D02*
Y-480502D01*
G01Y-481568D02*
X418498Y-481035D01*
X418998Y-480635D01*
X419698Y-480502D01*
X420198Y-480635D01*
X420798Y-481035D01*
G01X424398Y-488502D02*
X430398D01*
G01X433598Y-485835D02*
Y-477835D01*
G01Y-481835D02*
X434098Y-481035D01*
X434698Y-480635D01*
X435298Y-480502D01*
X436198Y-480768D01*
X436798Y-481302D01*
X437198Y-482235D01*
Y-483302D01*
X436998Y-484368D01*
X436598Y-485168D01*
X435898Y-485702D01*
X435298Y-485835D01*
X434698Y-485702D01*
X434098Y-485302D01*
X433598Y-484635D01*
G01X445198Y-477835D02*
Y-485835D01*
G01Y-484635D02*
X444798Y-485302D01*
X444198Y-485702D01*
X443498Y-485835D01*
X442698Y-485568D01*
X442098Y-484902D01*
X441698Y-484102D01*
X441598Y-483168D01*
X441698Y-482235D01*
X442098Y-481435D01*
X442698Y-480768D01*
X443498Y-480502D01*
X444198Y-480635D01*
X444698Y-480902D01*
X445198Y-481435D01*
G01X400398Y-538835D02*
Y-530835D01*
X399198Y-532435D01*
G01Y-538835D02*
X401598D01*
G01X406498Y-535502D02*
X407198Y-534568D01*
X407798Y-534035D01*
X408598Y-533768D01*
X409298Y-534035D01*
X409798Y-534568D01*
X410198Y-535368D01*
X410298Y-536302D01*
X410198Y-537102D01*
X409798Y-537902D01*
X409198Y-538568D01*
X408498Y-538835D01*
X407698Y-538568D01*
X406998Y-537769D01*
X406598Y-536568D01*
X406498Y-535235D01*
X406698Y-533502D01*
X406998Y-532568D01*
X407498Y-531635D01*
X408198Y-530968D01*
X408898Y-530835D01*
X409598Y-531102D01*
X410098Y-531768D01*
G01X416398Y-539102D02*
X416198Y-538968D01*
Y-538702D01*
X416398Y-538568D01*
X416598Y-538702D01*
Y-538968D01*
X416398Y-539102D01*
G01X422498Y-535502D02*
X423198Y-534568D01*
X423798Y-534035D01*
X424598Y-533768D01*
X425298Y-534035D01*
X425798Y-534568D01*
X426198Y-535368D01*
X426298Y-536302D01*
X426198Y-537102D01*
X425798Y-537902D01*
X425198Y-538568D01*
X424498Y-538835D01*
X423698Y-538568D01*
X422998Y-537769D01*
X422598Y-536568D01*
X422498Y-535235D01*
X422698Y-533502D01*
X422998Y-532568D01*
X423498Y-531635D01*
X424198Y-530968D01*
X424898Y-530835D01*
X425598Y-531102D01*
X426098Y-531768D01*
G01X421502Y1110233D02*
Y1108887D01*
X423340Y1104449D01*
Y1104335D01*
G01X422532Y1101917D02*
Y1103527D01*
X423340Y1104335D01*
G01X445398Y-538835D02*
Y-530835D01*
X444198Y-532435D01*
G01Y-538835D02*
X446598D01*
G01X453198D02*
X453398Y-537102D01*
X453698Y-535635D01*
X454098Y-534302D01*
X454598Y-532835D01*
X455398Y-530835D01*
X451398D01*
G01X461398Y-539102D02*
X461198Y-538968D01*
Y-538702D01*
X461398Y-538568D01*
X461598Y-538702D01*
Y-538968D01*
X461398Y-539102D01*
G01X467498Y-532168D02*
X468098Y-531368D01*
X468798Y-530968D01*
X469598Y-530835D01*
X470598Y-531102D01*
X471298Y-531768D01*
X471498Y-532568D01*
X471398Y-533369D01*
X470998Y-534035D01*
X468998Y-535368D01*
X468098Y-536302D01*
X467498Y-537635D01*
X467298Y-538835D01*
X471498D01*
G01X452591Y1020766D02*
X463015D01*
X464116Y1019665D01*
X466046D01*
G01Y1021240D02*
X464293D01*
X463267Y1022266D01*
X453449D01*
X451904Y1023811D01*
G01X453630Y1110233D02*
Y1108887D01*
X455468Y1104449D01*
Y1104335D01*
G01X454660Y1101917D02*
Y1103527D01*
X455468Y1104335D01*
G01X465498Y-513835D02*
Y-505835D01*
X469298D01*
G01X467898Y-509702D02*
X465498D01*
G01X475018Y992568D02*
X471465D01*
X469423Y994610D01*
Y997941D01*
X468961Y998403D01*
Y1003752D01*
X469983Y1004774D01*
Y1007854D01*
G01X467345Y996480D02*
Y1004999D01*
X468408Y1006062D01*
Y1007854D01*
G01X459885Y1018860D02*
X462979D01*
X463749Y1018090D01*
X466046D01*
G01X462185Y1016825D02*
X463799D01*
X464108Y1016516D01*
X466046D01*
G01X480711Y999941D02*
Y1004351D01*
X479432Y1005630D01*
Y1007854D01*
G01X477857Y1004375D02*
Y1007854D01*
G01X487089Y1110233D02*
Y1108887D01*
X488927Y1104449D01*
Y1104335D01*
G01X488119Y1101917D02*
Y1103527D01*
X488927Y1104335D01*
G01X519217Y1110233D02*
Y1108887D01*
X521055Y1104449D01*
Y1104335D01*
G01X520247Y1101917D02*
Y1103527D01*
X521055Y1104335D01*
G01X790989Y1455695D02*
X791731D01*
X792182Y1455244D01*
X795791D01*
G01X915480Y1453573D02*
X917744D01*
G01X1335676Y1110233D02*
Y1108887D01*
X1337514Y1104449D01*
Y1104335D01*
G01X1336706Y1101917D02*
Y1103527D01*
X1337514Y1104335D01*
G01X1366078Y1023811D02*
X1367623Y1022266D01*
X1377205D01*
X1378231Y1021240D01*
X1380220D01*
G01X1366765Y1020766D02*
X1376945D01*
X1378046Y1019665D01*
X1380220D01*
G01X1374059Y1018860D02*
X1377153D01*
X1377923Y1018090D01*
X1380220D01*
G01X1376359Y1016825D02*
X1377973D01*
X1378282Y1016516D01*
X1380220D01*
G01X1367804Y1110233D02*
Y1108887D01*
X1369642Y1104449D01*
Y1104335D01*
G01X1368834Y1101917D02*
Y1103527D01*
X1369642Y1104335D01*
G01X1402293Y1101917D02*
Y1103527D01*
X1403101Y1104335D01*
G01D02*
Y1104449D01*
X1401263Y1108887D01*
Y1110233D01*
G01X1433391D02*
Y1108887D01*
X1435229Y1104449D01*
Y1104335D01*
G01X1434421Y1101917D02*
Y1103527D01*
X1435229Y1104335D01*
G54D126*
X359716Y1223407D03*
X816803D03*
X1273889D03*
X1730976D03*
G54D42*
X23622Y1604724D03*
X62205Y765197D03*
X74016Y333464D03*
X102224Y70866D03*
X409488Y1604724D03*
X433130Y70866D03*
X463387Y286221D03*
X463386Y765197D03*
X661674Y23622D03*
X785039Y1547638D03*
X890217Y23622D03*
X920473Y765196D03*
X1055905Y1547637D03*
X1118760Y23622D03*
X1347303Y70866D03*
X1377559Y286220D03*
Y765197D03*
X1431457Y1604724D03*
X1575846Y23622D03*
X1766929Y333464D03*
X1778740Y765197D03*
X1795010Y23622D03*
X1817323Y1604724D03*
G54D252*
X1091661Y1521648D03*
Y1540152D03*
X1099339Y1521648D03*
X1096780D03*
X1094220D03*
Y1540152D03*
X1096780D03*
X1099339D03*
G54D171*
X491935Y1037680D03*
X1406109D03*
G54D261*
X1803917Y823898D03*
G54D162*
X436004Y566055D03*
Y610547D03*
G54D225*
X932117Y806210D03*
Y802470D03*
G54D24*
X19478Y160100D03*
X65713Y455494D03*
X115876Y117621D03*
X218238D03*
X320600D03*
X470601D03*
X520799Y452494D03*
X572963Y117621D03*
X675325D03*
X777687D03*
X927687D03*
X979886Y455494D03*
X1030049Y117621D03*
X1132411D03*
X1234773D03*
X1384774D03*
X1434973Y452494D03*
X1487136Y117621D03*
X1589498D03*
X1691860D03*
G54D180*
X656650Y694797D03*
X659209D03*
X656650Y702277D03*
X661768D03*
X659209D03*
X661768Y694797D03*
X781059Y1605740D03*
X778500D03*
X781059Y1598260D03*
X775941D03*
X778500D03*
X775941Y1605740D03*
X1113737Y694797D03*
X1116296D03*
X1113737Y702277D03*
X1118855D03*
X1116296D03*
X1118855Y694797D03*
X1570824D03*
X1573383D03*
X1570824Y702277D03*
X1575942D03*
X1573383D03*
X1575942Y694797D03*
G54D33*
X19075Y281129D03*
Y287035D03*
X26161D03*
Y281129D03*
X42690Y454376D03*
X48596D03*
X42690Y461462D03*
X48596D03*
X108643Y136742D03*
X115729Y142648D03*
Y136742D03*
X108643Y142648D03*
X211005Y136742D03*
Y142648D03*
X218091D03*
Y136742D03*
X243078Y633786D03*
Y640872D03*
X248984Y633786D03*
Y640872D03*
X313367Y136742D03*
X320453Y142648D03*
Y136742D03*
X313367Y142648D03*
X463368Y136742D03*
X470454Y142648D03*
Y136742D03*
X463368Y142648D03*
X482532Y421374D03*
X488438D03*
X482532Y428460D03*
X488438D03*
X497776Y451376D03*
Y458462D03*
X503682D03*
Y451376D03*
X565730Y136742D03*
Y142648D03*
X572816D03*
Y136742D03*
X668092D03*
Y142648D03*
X675178D03*
Y136742D03*
X700164Y633786D03*
Y640872D03*
X706070Y633786D03*
Y640872D03*
X770454Y136742D03*
X777540Y142648D03*
Y136742D03*
X770454Y142648D03*
X920454Y136742D03*
X927540Y142648D03*
Y136742D03*
X920454Y142648D03*
X946064Y242721D03*
X940158D03*
X946064Y249807D03*
X940158D03*
X956863Y454376D03*
Y461462D03*
X962769Y454376D03*
Y461462D03*
X1022816Y136742D03*
Y142648D03*
X1029902D03*
Y136742D03*
X1125178D03*
X1132264Y142648D03*
Y136742D03*
X1125178Y142648D03*
X1157251Y633786D03*
Y640872D03*
X1163157Y633786D03*
Y640872D03*
X1227540Y136742D03*
X1234626Y142648D03*
Y136742D03*
X1227540Y142648D03*
X1295453Y938043D03*
Y930957D03*
X1289547D03*
Y938043D03*
X1377541Y136742D03*
X1384627Y142648D03*
Y136742D03*
X1377541Y142648D03*
X1411950Y451376D03*
Y458462D03*
X1417856D03*
Y451376D03*
X1432499Y1508327D03*
X1426593D03*
Y1515413D03*
X1432499D03*
X1479903Y136742D03*
Y142648D03*
X1486989D03*
Y136742D03*
X1582265D03*
X1589351Y142648D03*
Y136742D03*
X1582265Y142648D03*
X1603363Y1456276D03*
X1597457D03*
Y1463362D03*
X1603363D03*
X1620244Y633786D03*
X1614338D03*
X1620244Y640872D03*
X1614338D03*
X1684627Y136742D03*
X1691713Y142648D03*
Y136742D03*
X1684627Y142648D03*
G54D117*
X294959Y19408D03*
Y14408D03*
Y29408D03*
Y24408D03*
X315825Y14408D03*
Y19408D03*
Y29408D03*
Y24408D03*
X1462675Y17645D03*
Y32645D03*
Y27645D03*
Y22645D03*
X1483541Y17645D03*
Y32645D03*
Y22645D03*
Y27645D03*
G54D144*
X406996Y1534417D03*
X403059D03*
X405028D03*
X401090D03*
X408964D03*
X406996Y1553413D03*
X408964D03*
X405028D03*
X403059D03*
X401090D03*
X412902Y1534417D03*
X410933D03*
Y1553413D03*
X412902D03*
X927249Y353756D03*
X921343D03*
X917406D03*
X925280D03*
X919375D03*
X915437D03*
X923311D03*
X921343Y372752D03*
X923311D03*
X919375D03*
X917406D03*
X915437D03*
X925280D03*
X927249D03*
G54D207*
X877727Y722060D03*
Y727178D03*
X870727D03*
Y722060D03*
Y724619D03*
G54D153*
X421962Y875715D03*
G54D60*
X48154Y487775D03*
Y489743D03*
Y491712D03*
Y493680D03*
Y495649D03*
Y497617D03*
X38323Y534519D03*
Y536487D03*
Y538456D03*
X50135D03*
Y536487D03*
Y534519D03*
X38323Y540424D03*
Y542393D03*
Y544361D03*
X50135D03*
Y542393D03*
Y540424D03*
X59966Y489743D03*
Y487775D03*
Y497617D03*
Y495649D03*
Y493680D03*
Y491712D03*
X83256Y209229D03*
Y211197D03*
Y213166D03*
Y215134D03*
Y217103D03*
Y219071D03*
X95068Y213166D03*
Y211197D03*
Y209229D03*
Y219071D03*
Y217103D03*
Y215134D03*
X197430Y213166D03*
Y211197D03*
Y209229D03*
X185618D03*
Y211197D03*
Y213166D03*
X197430Y219071D03*
Y217103D03*
Y215134D03*
X185618D03*
Y217103D03*
Y219071D03*
X287980Y209229D03*
Y211197D03*
Y213166D03*
Y215134D03*
Y217103D03*
Y219071D03*
X299792Y213166D03*
Y211197D03*
Y209229D03*
Y219071D03*
Y217103D03*
Y215134D03*
X369178Y472606D03*
Y474574D03*
Y476543D03*
Y478511D03*
Y480480D03*
Y482448D03*
X390342Y209229D03*
Y211197D03*
Y213166D03*
Y215134D03*
Y217103D03*
Y219071D03*
X380990Y474574D03*
Y472606D03*
Y482448D03*
Y480480D03*
Y478511D03*
Y476543D03*
X402154Y213166D03*
Y211197D03*
Y209229D03*
Y219071D03*
Y217103D03*
Y215134D03*
X442798Y493720D03*
Y495688D03*
Y497657D03*
Y499625D03*
Y501594D03*
Y503562D03*
X454610D03*
Y501594D03*
Y499625D03*
Y497657D03*
Y495688D03*
Y493720D03*
X505240Y487775D03*
Y489743D03*
Y491712D03*
Y493680D03*
Y495649D03*
Y497617D03*
X495409Y534519D03*
Y536487D03*
Y538456D03*
X507221D03*
Y536487D03*
Y534519D03*
X495409Y540424D03*
Y542393D03*
Y544361D03*
X507221D03*
Y542393D03*
Y540424D03*
X517052Y489743D03*
Y487775D03*
Y497617D03*
Y495649D03*
Y493680D03*
Y491712D03*
X552155Y213166D03*
Y211197D03*
Y209229D03*
X540343D03*
Y211197D03*
Y213166D03*
X552155Y219071D03*
Y217103D03*
Y215134D03*
X540343D03*
Y217103D03*
Y219071D03*
X642705Y209229D03*
Y211197D03*
Y213166D03*
Y215134D03*
Y217103D03*
Y219071D03*
X654517Y213166D03*
Y211197D03*
Y209229D03*
Y219071D03*
Y217103D03*
Y215134D03*
X745067Y209229D03*
Y211197D03*
Y213166D03*
Y215134D03*
Y217103D03*
Y219071D03*
X756879Y213166D03*
Y211197D03*
Y209229D03*
Y219071D03*
Y217103D03*
Y215134D03*
X826264Y467606D03*
Y469574D03*
Y471543D03*
Y473511D03*
Y475480D03*
Y477448D03*
X847429Y209229D03*
Y211197D03*
Y213166D03*
Y215134D03*
Y217103D03*
Y219071D03*
X838076Y473511D03*
Y471543D03*
Y469574D03*
Y467606D03*
Y477448D03*
Y475480D03*
X859241Y213166D03*
Y211197D03*
Y209229D03*
Y219071D03*
Y217103D03*
Y215134D03*
X962327Y487775D03*
Y489743D03*
Y491712D03*
Y493680D03*
Y495649D03*
Y497617D03*
X952496Y534519D03*
Y536487D03*
Y538456D03*
Y540424D03*
Y542393D03*
Y544361D03*
X974139Y489743D03*
Y487775D03*
Y497617D03*
Y495649D03*
Y493680D03*
Y491712D03*
X964308Y538456D03*
Y536487D03*
Y534519D03*
Y544361D03*
Y542393D03*
Y540424D03*
X1009241Y213166D03*
Y211197D03*
Y209229D03*
X997429D03*
Y211197D03*
Y213166D03*
X1009241Y219071D03*
Y217103D03*
Y215134D03*
X997429D03*
Y217103D03*
Y219071D03*
X1099791Y209229D03*
Y211197D03*
Y213166D03*
Y215134D03*
Y217103D03*
Y219071D03*
X1111603Y213166D03*
Y211197D03*
Y209229D03*
Y219071D03*
Y217103D03*
Y215134D03*
X1202153Y209229D03*
Y211197D03*
Y213166D03*
Y215134D03*
Y217103D03*
Y219071D03*
X1213965Y213166D03*
Y211197D03*
Y209229D03*
Y219071D03*
Y217103D03*
Y215134D03*
X1283351Y472606D03*
Y474574D03*
Y476543D03*
Y478511D03*
Y480480D03*
Y482448D03*
X1295163Y474574D03*
Y472606D03*
Y482448D03*
Y480480D03*
Y478511D03*
Y476543D03*
X1316327Y213166D03*
Y211197D03*
Y209229D03*
X1304515D03*
Y211197D03*
Y213166D03*
X1316327Y219071D03*
Y217103D03*
Y215134D03*
X1304515D03*
Y217103D03*
Y219071D03*
X1409583Y534519D03*
Y536487D03*
Y538456D03*
Y540424D03*
Y542393D03*
Y544361D03*
X1419414Y487775D03*
Y489743D03*
X1431226D03*
Y487775D03*
X1419414Y491712D03*
Y493680D03*
Y495649D03*
Y497617D03*
X1431226D03*
Y495649D03*
Y493680D03*
Y491712D03*
X1421395Y538456D03*
Y536487D03*
Y534519D03*
Y544361D03*
Y542393D03*
Y540424D03*
X1454516Y209229D03*
Y211197D03*
Y213166D03*
Y215134D03*
Y217103D03*
Y219071D03*
X1466328Y213166D03*
Y211197D03*
Y209229D03*
Y219071D03*
Y217103D03*
Y215134D03*
X1556878Y209229D03*
Y211197D03*
Y213166D03*
Y215134D03*
Y217103D03*
Y219071D03*
X1568690Y213166D03*
Y211197D03*
Y209229D03*
Y219071D03*
Y217103D03*
Y215134D03*
X1659240Y209229D03*
Y211197D03*
Y213166D03*
Y215134D03*
Y217103D03*
Y219071D03*
X1671052Y213166D03*
Y211197D03*
Y209229D03*
Y219071D03*
Y217103D03*
Y215134D03*
X1740438Y472606D03*
Y474574D03*
Y476543D03*
Y478511D03*
Y480480D03*
Y482448D03*
X1752250Y474574D03*
Y472606D03*
Y482448D03*
Y480480D03*
Y478511D03*
Y476543D03*
X1773414Y213166D03*
Y211197D03*
Y209229D03*
X1761602D03*
Y211197D03*
Y213166D03*
X1773414Y219071D03*
Y217103D03*
Y215134D03*
X1761602D03*
Y217103D03*
Y219071D03*
G54D108*
X111700Y1210046D03*
X114529Y1207217D03*
X105690Y1216056D03*
X117364Y1228316D03*
X125848Y1219832D03*
X134334Y1211347D03*
X351925Y403882D03*
X568787Y1210046D03*
X571616Y1207217D03*
X562777Y1216056D03*
X582935Y1219832D03*
X574451Y1228316D03*
X591421Y1211347D03*
X1025873Y1210046D03*
X1019863Y1216056D03*
X1028702Y1207217D03*
X1040021Y1219832D03*
X1031537Y1228316D03*
X1048507Y1211347D03*
X1266098Y403882D03*
X1476950Y1216056D03*
X1497108Y1219832D03*
X1482960Y1210046D03*
X1485789Y1207217D03*
X1488624Y1228316D03*
X1505594Y1211347D03*
X1723185Y403882D03*
G54D15*
X12786Y82445D03*
X10292Y96728D03*
X14292D03*
X15948Y135809D03*
X11999Y135881D03*
X19855Y135904D03*
X12709Y170319D03*
X18826Y232994D03*
X11781Y1529404D03*
X10852Y1538639D03*
X6560Y1547628D03*
X18434Y1548699D03*
X20709Y170319D03*
X36201Y233076D03*
X24091Y233063D03*
X27966Y233051D03*
X29127Y1198716D03*
X27222Y1438644D03*
X48643Y445436D03*
X41643Y467436D03*
X46192Y636328D03*
X42192D03*
X50192D03*
X36692D03*
X40700Y1086663D03*
X58224Y467576D03*
X66224D03*
X53643Y467436D03*
X67684Y599742D03*
X54192Y636328D03*
X63988Y625184D03*
X57553Y1202752D03*
X53056Y1206881D03*
X54339Y1487989D03*
X60013Y1550212D03*
X66291Y1628319D03*
X73381Y88546D03*
X69381D03*
X77711Y173090D03*
X73711D03*
X77938Y184347D03*
X76877Y216699D03*
X80766Y259627D03*
X75819Y285000D03*
X79819D03*
X83819D03*
X83684Y599742D03*
X79684D03*
X71684D03*
X75684D03*
X73968Y662609D03*
X75049Y828235D03*
Y835649D03*
X70941Y1586782D03*
X74291Y1628319D03*
X78291D03*
X82291D03*
X70291D03*
X89845Y275318D03*
X87684Y599742D03*
X91057Y1025319D03*
X86291Y1628319D03*
X107607Y127840D03*
X117607D03*
X106796Y147846D03*
X121661Y127845D03*
X121840Y142954D03*
X120926Y232951D03*
X126453Y233063D03*
X130328Y233051D03*
X127235Y452598D03*
X138563Y233076D03*
X146400Y452317D03*
X175743Y88546D03*
X171743D03*
X179743D03*
X180073Y173090D03*
X176073D03*
X180300Y184347D03*
X179239Y216699D03*
X178181Y285000D03*
X182181D03*
X183752Y88546D03*
X183128Y259627D03*
X192207Y275318D03*
X186181Y285000D03*
X210482Y88821D03*
X214389Y88916D03*
X206533Y88893D03*
X211969Y127840D03*
X209158Y147846D03*
X219969Y127840D03*
X224023Y127845D03*
X224202Y142954D03*
X223288Y232951D03*
X228815Y233063D03*
X217939Y611981D03*
X221809Y611993D03*
X221084Y1479997D03*
X229753Y1534232D03*
X240925Y233076D03*
X232690Y233051D03*
X243278Y620880D03*
X247278D03*
X236498Y1475657D03*
X237753Y1534232D03*
X251278Y620880D03*
X278105Y88546D03*
X274105D03*
X278435Y173090D03*
X282105Y88546D03*
X286114D03*
X282435Y173090D03*
X282662Y184347D03*
X281601Y216699D03*
X285490Y259627D03*
X294569Y275318D03*
X280543Y285000D03*
X284543D03*
X288543D03*
X280500Y855731D03*
Y865831D03*
X286300Y890931D03*
Y901231D03*
X282300Y926431D03*
X282400Y936531D03*
X308895Y88893D03*
X312331Y127840D03*
X311520Y147867D03*
X312263Y311832D03*
X304543Y328959D03*
X316751Y88916D03*
X312844Y88821D03*
X322331Y127840D03*
X326385Y127845D03*
X326564Y142954D03*
X325650Y232951D03*
X331177Y233063D03*
X343287Y233076D03*
X335052Y233051D03*
X342285Y562229D03*
X341748Y1137221D03*
X341455Y1182062D03*
X342152Y1203535D03*
X338322Y1190987D03*
X347591Y394025D03*
X357748Y1137221D03*
X353748D03*
X349748D03*
X345471Y1181992D03*
X346387Y1203497D03*
X350402Y1203535D03*
X354402D03*
X358402D03*
X350400Y1195511D03*
X354400D03*
X358400D03*
X376467Y88546D03*
X377237Y373772D03*
X366486Y379665D03*
X370486D03*
X368587Y403558D03*
X364326Y481975D03*
X361748Y1137221D03*
X366157Y1147029D03*
X366133Y1165309D03*
X366400Y1195511D03*
X366402Y1203535D03*
X362402D03*
X362400Y1195511D03*
X386112Y30710D03*
X380467Y88546D03*
X388476D03*
X384467D03*
X384797Y173090D03*
X380797D03*
X385024Y184347D03*
X383963Y216699D03*
X387852Y259627D03*
X382905Y285000D03*
X386905D03*
X390905D03*
X379800Y772117D03*
X378472Y790286D03*
X391614Y933168D03*
X408680Y40035D03*
X396680D03*
X396931Y275318D03*
X398237Y373573D03*
X394553Y392919D03*
X401165Y445554D03*
X395390Y872787D03*
X399052Y881290D03*
X402966Y881391D03*
X403159Y1119914D03*
X409461Y1563526D03*
X405461D03*
X415677Y312778D03*
X423551D03*
X419277D03*
X424479Y362174D03*
X416318Y362166D03*
X421459Y625843D03*
X420400Y795631D03*
X412100D03*
X413461Y1563526D03*
X435025Y312778D03*
X431425D03*
X427151D03*
X435574Y439056D03*
X429673Y456118D03*
X433673D03*
X438157Y503126D03*
X431285Y1120913D03*
X435287Y1119914D03*
X444779Y633973D03*
X455619Y1252512D03*
X472332Y127840D03*
X464332D03*
X461521Y147846D03*
X461091Y1024783D03*
X463413Y1120913D03*
X468746Y1119914D03*
X460574Y1252513D03*
X476386Y127845D03*
X476565Y142954D03*
X481178Y233063D03*
X475651Y232951D03*
X485053Y233051D03*
X488485Y412434D03*
X481485Y434434D03*
X488745Y677434D03*
X488091Y992283D03*
X493288Y233076D03*
X493485Y434434D03*
X503729Y442436D03*
X496729Y464436D03*
X503278Y636328D03*
X499278D03*
X507278D03*
X493778D03*
X491373Y654714D03*
X493914Y677452D03*
X505464Y670170D03*
X492091Y992283D03*
X500874Y1119914D03*
X496872Y1120913D03*
X521310Y464576D03*
X513310D03*
X508729Y464436D03*
X511278Y636328D03*
X521074Y625184D03*
X517464Y670170D03*
X513464D03*
X509464D03*
X517412Y758924D03*
X514576Y786320D03*
X519763Y786247D03*
X538477Y88546D03*
X530468D03*
X534468D03*
X526468D03*
X534798Y173090D03*
X530798D03*
X535025Y184347D03*
X533964Y216699D03*
X537853Y259627D03*
X532906Y285000D03*
X536906D03*
X528770Y599742D03*
X532770D03*
X536770D03*
X524770D03*
X537964Y670170D03*
X533964D03*
X529964D03*
X525964D03*
X529000Y1120913D03*
X546932Y275318D03*
X540906Y285000D03*
X544770Y599742D03*
X540770D03*
X542400Y844831D03*
X548144Y1025319D03*
X569114Y88916D03*
X565207Y88821D03*
X561258Y88893D03*
X564694Y127840D03*
X563883Y147846D03*
X567958Y1532332D03*
X574694Y127840D03*
X578748Y127845D03*
X578927Y142954D03*
X578013Y232951D03*
X583540Y233063D03*
X587415Y233051D03*
X584321Y452598D03*
X574504Y750401D03*
X587858Y1520832D03*
X579758Y1520732D03*
X575809Y1535518D03*
X583809D03*
X595650Y233076D03*
X603486Y452317D03*
X592103Y942324D03*
Y949738D03*
X591858Y1526932D03*
X595809Y1535518D03*
X632830Y88546D03*
X636830D03*
X628830D03*
X637160Y173090D03*
X633160D03*
X637387Y184347D03*
X636326Y216699D03*
X635268Y285000D03*
X640839Y88546D03*
X640215Y259627D03*
X649294Y275318D03*
X639268Y285000D03*
X643268D03*
X663620Y88893D03*
X667569Y88821D03*
X669056Y127840D03*
X666245Y147846D03*
X658064Y653253D03*
X662064D03*
X671476Y88916D03*
X677056Y127840D03*
X681110Y127845D03*
X681289Y142954D03*
X680375Y232951D03*
X685902Y233063D03*
X698012Y233076D03*
X689777Y233051D03*
X700364Y620880D03*
X693163Y697165D03*
X704364Y620880D03*
X708364D03*
X731192Y88546D03*
X720260Y696639D03*
X732170Y1622107D03*
X743201Y88546D03*
X739192D03*
X735192D03*
X739522Y173090D03*
X735522D03*
X739749Y184347D03*
X738688Y216699D03*
X742577Y259627D03*
X737630Y285000D03*
X741630D03*
X745630D03*
X751140Y1583827D03*
X735392Y1599282D03*
X744924Y1611885D03*
X743331Y1630736D03*
X765982Y88893D03*
X751656Y275318D03*
X761629Y328959D03*
X755187Y1583841D03*
X759452Y1613859D03*
X773838Y88916D03*
X769931Y88821D03*
X769418Y127840D03*
X779418D03*
X783472Y127845D03*
X783651Y142954D03*
X768607Y147846D03*
X782737Y232951D03*
X769349Y311832D03*
X774844Y1619487D03*
X778358Y1630218D03*
X788264Y233063D03*
X792139Y233051D03*
X799371Y562229D03*
X798835Y1137221D03*
X798542Y1182062D03*
X795159Y1188708D03*
X795418Y1203435D03*
X796972Y1394695D03*
X800374Y233076D03*
X813821Y735388D03*
X816027Y867772D03*
X806835Y1137221D03*
X814835D03*
X810835D03*
X802558Y1181992D03*
X815487Y1195511D03*
X811487D03*
X807487D03*
X815489Y1203535D03*
X811489D03*
X807489D03*
X803604Y1203492D03*
X802333Y1195028D03*
X806148Y1377700D03*
X810148D03*
X805009Y1469602D03*
X821412Y476975D03*
X830484Y741243D03*
X826484D03*
X822831Y836758D03*
X818831D03*
X820027Y867772D03*
X819629Y892647D03*
X828909Y908560D03*
X830913Y926694D03*
X818835Y1137221D03*
X823244Y1147029D03*
X823220Y1165309D03*
X823489Y1203535D03*
X819487Y1195511D03*
X823487D03*
X819489Y1203535D03*
X833554Y88546D03*
X837554D03*
X845563D03*
X841554D03*
X841884Y173090D03*
X837884D03*
X842111Y184347D03*
X841050Y216699D03*
X844939Y259627D03*
X839992Y285000D03*
X843992D03*
X847992D03*
X846098Y411754D03*
X834484Y741243D03*
X846484D03*
X838484D03*
X842484D03*
X833112Y826730D03*
X832726Y840571D03*
X836311Y874105D03*
X844946Y908560D03*
X840909D03*
X836909D03*
X832909D03*
X838829Y926694D03*
X834829D03*
X845395D03*
X836423Y959211D03*
X832423D03*
X854018Y275318D03*
X863086Y377017D03*
X849680Y689131D03*
X854484Y741243D03*
X850484D03*
X852628Y909606D03*
X860628D03*
X849544Y1451276D03*
X872293Y88821D03*
X876200Y88916D03*
X868344Y88893D03*
X878500Y197442D03*
X879740Y257226D03*
X868086Y377017D03*
X876736Y385797D03*
X867586Y387517D03*
X869342Y411559D03*
X875916Y803407D03*
X879916Y813557D03*
X876628Y909606D03*
X868628D03*
X872817Y1207719D03*
X889879Y409260D03*
X896491Y461895D03*
X896431Y536585D03*
X891933Y612685D03*
X884045Y747252D03*
X887916Y803407D03*
X883916D03*
Y813557D03*
X887916D03*
X891916Y803407D03*
X884628Y909606D03*
X887390Y1095666D03*
X896746Y1215884D03*
X891844Y1452176D03*
X897736Y385797D03*
X903431Y536585D03*
X911416Y803407D03*
X910900Y909517D03*
X906128Y956107D03*
X901243Y1211755D03*
X908852Y1225025D03*
X912726D03*
X929418Y127840D03*
X921418D03*
X918607Y147846D03*
X927072Y381424D03*
X923072D03*
X919072D03*
X924999Y472459D03*
X928999D03*
X917250Y551637D03*
X927916Y803407D03*
X923790D03*
X919664D03*
X915716D03*
X914500Y909517D03*
X918100D03*
X924628Y909606D03*
X928628D03*
X925697Y1454343D03*
X921868Y1454373D03*
X933472Y127845D03*
X933651Y142954D03*
X938930Y218234D03*
X942805Y218222D03*
X938657Y364728D03*
X930900Y455397D03*
X931916Y811557D03*
X943916D03*
X945035Y830274D03*
X943735Y844674D03*
X936616Y895121D03*
X932716D03*
X936628Y909606D03*
X944628D03*
X940628D03*
X932628D03*
X936794Y1207719D03*
X951040Y218247D03*
X955816Y467436D03*
X960365Y636328D03*
X956365D03*
X950865D03*
X947556Y702142D03*
X955950Y728555D03*
X948935Y830274D03*
X950335Y823374D03*
X958682Y831445D03*
X958200Y838617D03*
X950100Y850517D03*
X954000D03*
X954124Y880087D03*
X954567Y930336D03*
X957671Y985760D03*
X951367Y1095666D03*
X960723Y1215884D03*
X962816Y445436D03*
X972397Y467496D03*
X967816Y467436D03*
X968365Y636328D03*
X978161Y625184D03*
X964365Y636328D03*
X973712Y716606D03*
X965220Y1211755D03*
X983554Y88546D03*
X987554D03*
X991554D03*
X991884Y173090D03*
X987884D03*
X992111Y184347D03*
X991050Y216699D03*
X989992Y285000D03*
X993992D03*
X990405Y318267D03*
X984045Y361101D03*
X980045D03*
X980397Y467576D03*
X981857Y599742D03*
X989857D03*
X993857D03*
X985857D03*
X991990Y768491D03*
X987990D03*
X990051Y813860D03*
X995563Y88546D03*
X994939Y259627D03*
X1004018Y275318D03*
X997992Y285000D03*
X1004635Y302768D03*
X1008635D03*
X997857Y599742D03*
X1001857D03*
X1003990Y768491D03*
X999990D03*
X1005230Y1025319D03*
X1018344Y88893D03*
X1022293Y88821D03*
X1026200Y88916D03*
X1021780Y127840D03*
X1020969Y147846D03*
X1021259Y1313539D03*
X1024115Y1330906D03*
X1031780Y127840D03*
X1035834Y127845D03*
X1036013Y142954D03*
X1035099Y232951D03*
X1040626Y233063D03*
X1033786Y302768D03*
X1037386D03*
X1041496D03*
X1041408Y452598D03*
X1033719Y939339D03*
Y946753D03*
X1052736Y233076D03*
X1044501Y233051D03*
X1060573Y452317D03*
X1066260Y1442483D03*
X1085916Y88546D03*
X1089916D03*
X1090246Y173090D03*
X1086904Y1593298D03*
X1090469Y1582502D03*
X1083735Y1603715D03*
Y1611651D03*
X1085474Y1631942D03*
X1093916Y88546D03*
X1097925D03*
X1094246Y173090D03*
X1094473Y184347D03*
X1093412Y216699D03*
X1097301Y259627D03*
X1106380Y275318D03*
X1092354Y285000D03*
X1096354D03*
X1100354D03*
X1098376Y1554275D03*
X1093376D03*
X1098904Y1593298D03*
X1094904D03*
X1100233Y1582525D03*
X1104612Y1603694D03*
X1097474Y1631942D03*
X1124655Y88821D03*
X1120706Y88893D03*
X1123331Y147846D03*
X1115151Y653253D03*
X1119151D03*
X1128562Y88916D03*
X1134142Y127840D03*
X1126142D03*
X1138196Y127845D03*
X1138375Y142954D03*
X1137461Y232951D03*
X1142988Y233063D03*
X1155098Y233076D03*
X1146863Y233051D03*
X1152485Y767659D03*
X1157451Y620880D03*
X1161451D03*
X1165451D03*
X1168485Y767527D03*
X1160485Y767659D03*
X1164485D03*
X1188278Y88546D03*
X1180715Y778985D03*
X1196278Y88546D03*
X1200287D03*
X1192278D03*
X1196608Y173090D03*
X1192608D03*
X1196835Y184347D03*
X1195774Y216699D03*
X1199663Y259627D03*
X1194716Y285000D03*
X1198716D03*
X1202716D03*
X1208742Y275318D03*
X1218716Y328959D03*
X1227017Y88821D03*
X1230924Y88916D03*
X1223068Y88893D03*
X1236504Y127840D03*
X1226504D03*
X1225693Y147846D03*
X1226436Y311832D03*
X1240558Y127845D03*
X1240737Y142954D03*
X1239823Y232951D03*
X1245350Y233063D03*
X1249225Y233051D03*
X1251302Y1198942D03*
X1257460Y233076D03*
X1261764Y394025D03*
X1256458Y562229D03*
X1263921Y1137221D03*
X1267921D03*
X1255921D03*
X1255628Y1182062D03*
X1259644Y1181992D03*
X1264575Y1203535D03*
X1268575D03*
X1264573Y1195511D03*
X1268573D03*
X1260535Y1203540D03*
X1260771Y1193837D03*
X1280659Y379665D03*
X1284659D03*
X1282760Y403558D03*
X1278499Y481975D03*
X1284655Y895017D03*
X1275493Y924010D03*
X1279493D03*
X1283493D03*
X1271493D03*
X1275921Y1137221D03*
X1271921D03*
X1280330Y1147029D03*
X1280306Y1165309D03*
X1276575Y1203535D03*
X1280573Y1195511D03*
X1276573D03*
X1280575Y1203535D03*
X1272575D03*
X1272573Y1195511D03*
X1300285Y30710D03*
X1298640Y88546D03*
X1294640D03*
X1302649D03*
X1290640D03*
X1298970Y173090D03*
X1294970D03*
X1299197Y184347D03*
X1298136Y216699D03*
X1302025Y259627D03*
X1297078Y285000D03*
X1301078D03*
X1291500Y321517D03*
X1291410Y373772D03*
X1292000Y895017D03*
X1289500Y944017D03*
X1296500Y964017D03*
X1310853Y40035D03*
X1311104Y275318D03*
X1305078Y285000D03*
X1318262Y315870D03*
X1312410Y373573D03*
X1308726Y392919D03*
X1315338Y445554D03*
X1318500Y920017D03*
X1314500D03*
X1317000Y931017D03*
X1318500Y962017D03*
X1311000Y964017D03*
X1315000D03*
X1317333Y1119914D03*
X1322853Y40035D03*
X1329736Y315870D03*
X1334010D03*
X1321862D03*
X1326136D03*
X1320903Y365258D03*
X1329064Y365266D03*
X1327584Y779122D03*
X1330500Y920017D03*
X1334500D03*
X1326500Y931017D03*
X1337610Y315870D03*
X1349747Y439056D03*
X1343846Y456118D03*
X1347846D03*
X1345000Y790517D03*
X1348917D03*
X1342500Y920017D03*
X1338500D03*
X1345948Y946120D03*
X1349948D03*
X1336000Y931017D03*
X1345459Y1120913D03*
X1349461Y1119914D03*
X1352817Y790517D03*
X1365000Y806517D03*
X1361000D03*
X1357000D03*
X1365948Y946120D03*
X1357948D03*
X1353948D03*
X1378505Y127840D03*
X1375694Y147846D03*
X1380500Y590517D03*
Y637017D03*
Y681517D03*
Y728517D03*
X1373000Y806517D03*
X1381000D03*
X1369000D03*
X1377017Y806515D03*
X1369948Y946120D03*
X1382560Y934338D03*
X1378503Y934337D03*
X1375265Y1024783D03*
X1377587Y1120913D03*
X1382920Y1119914D03*
X1386505Y127840D03*
X1390559Y127845D03*
X1390738Y142954D03*
X1389824Y232951D03*
X1395351Y233063D03*
X1399226Y233051D03*
X1394537Y806196D03*
X1398517Y806234D03*
X1407461Y233076D03*
X1410903Y464436D03*
X1413452Y636328D03*
X1407952D03*
X1402517Y806234D03*
X1406483D03*
X1402265Y992283D03*
X1406265D03*
X1411046Y1120913D03*
X1415048Y1119914D03*
X1407747Y1543477D03*
X1407255Y1566155D03*
X1417903Y442436D03*
X1427484Y464576D03*
X1422903Y464436D03*
X1425452Y636328D03*
X1417452D03*
X1421452D03*
X1432258Y1407832D03*
X1444641Y88546D03*
X1440641D03*
X1448641D03*
X1448971Y173090D03*
X1444971D03*
X1449198Y184347D03*
X1448137Y216699D03*
X1447079Y285000D03*
X1435484Y464576D03*
X1442944Y599742D03*
X1438944D03*
X1446944D03*
X1435248Y625184D03*
X1437980Y1028464D03*
X1443174Y1120913D03*
X1436258Y1407832D03*
X1437293Y1540507D03*
X1436801Y1563185D03*
X1452650Y88546D03*
X1452026Y259627D03*
X1461105Y275318D03*
X1451079Y285000D03*
X1455079D03*
X1454944Y599742D03*
X1458944D03*
X1450944D03*
X1462317Y1025319D03*
X1479380Y88821D03*
X1475431Y88893D03*
X1478867Y127840D03*
X1478056Y147846D03*
X1471500Y713017D03*
Y757017D03*
X1483287Y88916D03*
X1488867Y127840D03*
X1492921Y127845D03*
X1493100Y142954D03*
X1492186Y232951D03*
X1497713Y233063D03*
X1488500Y798517D03*
Y842517D03*
X1509823Y233076D03*
X1501588Y233051D03*
X1498495Y452598D03*
X1517660Y452317D03*
X1547003Y88546D03*
X1543003D03*
X1555012D03*
X1551003D03*
X1551333Y173090D03*
X1547333D03*
X1551560Y184347D03*
X1550499Y216699D03*
X1554388Y259627D03*
X1549441Y285000D03*
X1553441D03*
X1557441D03*
X1577793Y88893D03*
X1563467Y275318D03*
X1572238Y653253D03*
X1576238D03*
X1585649Y88916D03*
X1581742Y88821D03*
X1591229Y127840D03*
X1583229D03*
X1595283Y127845D03*
X1595462Y142954D03*
X1580418Y147846D03*
X1594548Y232951D03*
X1587746Y1457649D03*
X1594264Y1470032D03*
X1600075Y233063D03*
X1603950Y233051D03*
X1601500Y1509017D03*
X1598000D03*
X1608500D03*
X1610858Y1520332D03*
X1612185Y233076D03*
X1614538Y620880D03*
X1618538D03*
X1622538D03*
X1653365Y88546D03*
X1657374D03*
X1645365D03*
X1649365D03*
X1653695Y173090D03*
X1649695D03*
X1653922Y184347D03*
X1652861Y216699D03*
X1656750Y259627D03*
X1651803Y285000D03*
X1655803D03*
X1659803D03*
X1665829Y275318D03*
X1675803Y328959D03*
X1680155Y88893D03*
X1684104Y88821D03*
X1688011Y88916D03*
X1683591Y127840D03*
X1682780Y147846D03*
X1683523Y311832D03*
X1693591Y127840D03*
X1697645Y127845D03*
X1697824Y142954D03*
X1702437Y233063D03*
X1696910Y232951D03*
X1706312Y233051D03*
X1714547Y233076D03*
X1718851Y394025D03*
X1713545Y562229D03*
X1721008Y1137221D03*
X1725008D03*
X1713008D03*
X1712715Y1182062D03*
X1716731Y1181992D03*
X1721662Y1203535D03*
X1725662D03*
X1721660Y1195511D03*
X1725660D03*
X1709820Y1196607D03*
X1717568Y1203335D03*
X1741746Y379665D03*
X1737746D03*
X1739847Y403558D03*
X1735586Y481975D03*
X1733008Y1137221D03*
X1729008D03*
X1737417Y1147029D03*
X1737393Y1165309D03*
X1729662Y1203535D03*
X1733662D03*
X1737660Y1195511D03*
X1729660D03*
X1733660D03*
X1737662Y1203535D03*
X1751727Y88546D03*
X1755727D03*
X1747727D03*
X1756057Y173090D03*
X1752057D03*
X1756284Y184347D03*
X1755223Y216699D03*
X1754165Y285000D03*
X1758165D03*
X1748497Y373772D03*
X1750900Y904917D03*
X1756422Y1634821D03*
X1759736Y88546D03*
X1759112Y259627D03*
X1768191Y275318D03*
X1762165Y285000D03*
X1769497Y373573D03*
X1765813Y392919D03*
X1772425Y445554D03*
X1761072Y1593284D03*
X1765072D03*
X1772422Y1634821D03*
X1768422D03*
X1760422D03*
X1764422D03*
X1782517Y88893D03*
X1786466Y88821D03*
X1790373Y88916D03*
X1776071Y833411D03*
X1789537Y924594D03*
X1780774Y1208205D03*
X1778227Y1440625D03*
X1778104Y1472815D03*
X1776422Y1634821D03*
X1806834Y439056D03*
X1800933Y456118D03*
X1804933D03*
X1797374Y924466D03*
X1795347Y1096152D03*
X1804703Y1216370D03*
X1800046Y1437663D03*
X1799923Y1469853D03*
X1809700Y907117D03*
X1808363Y970177D03*
Y977591D03*
X1809200Y1212241D03*
G54D243*
X1011187Y-43526D03*
Y-40126D03*
X1081187Y-79306D03*
Y-82706D03*
X1225405Y-79278D03*
Y-82678D03*
X1230761Y-43628D03*
Y-40228D03*
X1297687Y-40256D03*
Y-43656D03*
X1337687Y-79306D03*
Y-82706D03*
X1481905Y-79278D03*
Y-82678D03*
X1517261Y-40358D03*
Y-43758D03*
X1592187Y-79306D03*
Y-82706D03*
X1582187Y-43786D03*
Y-40386D03*
X1736405Y-79278D03*
Y-82678D03*
X1801761Y-43888D03*
Y-40488D03*
G54D51*
X40079Y1521641D03*
G54D135*
X412752Y898688D03*
Y921718D03*
G54D216*
X909360Y230906D03*
Y274606D03*
G54D234*
X942586Y1499857D03*
G54D280*
G01X148818Y1075196D02*
X150688Y1077066D01*
G01X145078Y1086417D02*
X143208Y1084547D01*
G01X148818Y1078936D02*
X146948Y1077066D01*
G01X145078Y1078936D02*
X146948Y1080806D01*
G01X148818Y1086417D02*
X146948Y1084547D01*
G01X148818Y1093897D02*
X146948Y1092027D01*
G01X145078Y1093897D02*
X143208Y1092027D01*
G01X145078Y1097637D02*
X143208Y1095767D01*
G01X148818Y1097637D02*
X146948Y1095767D01*
G01X148818Y1105117D02*
X146948Y1103247D01*
G01X143208D02*
X145078Y1105117D01*
G01Y1112598D02*
X143208Y1110728D01*
G01X145078Y1120078D02*
X143208Y1118208D01*
G01X148818Y1112598D02*
X146948Y1110728D01*
G01X148818Y1120078D02*
X146948Y1118208D01*
G01X148818Y1135039D02*
X146948Y1133169D01*
G01X145078Y1127558D02*
X143208Y1125688D01*
G01X145078Y1135039D02*
X143208Y1133169D01*
G01X148818Y1127558D02*
X146948Y1125688D01*
G01X145078Y1142519D02*
X143208Y1140649D01*
G01X148818Y1142519D02*
X146948Y1140649D01*
G01X145078Y1146259D02*
X143208Y1144389D01*
G01X145078Y1153740D02*
X143208Y1151870D01*
G01X148818Y1146259D02*
X146948Y1144389D01*
G01X148818Y1153740D02*
X146948Y1151870D01*
G01X145078Y1161220D02*
X143208Y1159350D01*
G01X148818Y1161220D02*
X146948Y1159350D01*
G01X146949Y1166830D02*
X145078Y1168700D01*
G01X148818D02*
X150688Y1170570D01*
G01X148818Y1176180D02*
X150688Y1174310D01*
G01X148818Y1176180D02*
X150688Y1178051D01*
G01X148818Y1176180D02*
X146947Y1174310D01*
G01X156299Y1075196D02*
X154429Y1073326D01*
G01X163779Y1075196D02*
X161909Y1073326D01*
G01X163779Y1078936D02*
X161909Y1077066D01*
G01X167519Y1082677D02*
X165649Y1080807D01*
G01X167519Y1090157D02*
X165649Y1088287D01*
G01X163779Y1090157D02*
X161909Y1088287D01*
G01X156299Y1078936D02*
X154429Y1077066D01*
G01X160039Y1082677D02*
X158169Y1080807D01*
G01X152559Y1082677D02*
X150689Y1080807D01*
G01X160039Y1086417D02*
X158169Y1084547D01*
G01X152559Y1086417D02*
X150689Y1084547D01*
G01X160039Y1090157D02*
X158169Y1088287D01*
G01X156299Y1090157D02*
X154429Y1088287D01*
G01X152559Y1090157D02*
X150689Y1088287D01*
G01X167519Y1086417D02*
X165649Y1084547D01*
G01X163779Y1093897D02*
X161909Y1092027D01*
G01X156299Y1093897D02*
X154429Y1092027D01*
G01X160039Y1101377D02*
X158169Y1099507D01*
G01X152559Y1101377D02*
X150689Y1099507D01*
G01X160039Y1105117D02*
X158169Y1103247D01*
G01X152559Y1105117D02*
X150689Y1103247D01*
G01X160039Y1108858D02*
X158169Y1106988D01*
G01X163779Y1097637D02*
X161909Y1095767D01*
G01X167519Y1101377D02*
X165649Y1099507D01*
G01X167519Y1105117D02*
X165649Y1103247D01*
G01X167519Y1108858D02*
X165649Y1106988D01*
G01X163779Y1108858D02*
X161909Y1106988D01*
G01X156299Y1108858D02*
X154429Y1106988D01*
G01X152559Y1108858D02*
X150689Y1106988D01*
G01X156299Y1097637D02*
X154429Y1095767D01*
G01X160039Y1112598D02*
X158169Y1110728D01*
G01X160039Y1116338D02*
X158169Y1114468D01*
G01X156299Y1116338D02*
X154429Y1114468D01*
G01X152559Y1116338D02*
X150689Y1114468D01*
G01X160039Y1120078D02*
X158169Y1118208D01*
G01X160039Y1123818D02*
X158169Y1121948D01*
G01X156299Y1123818D02*
X154429Y1121948D01*
G01X152559Y1123818D02*
X150689Y1121948D01*
G01X167519Y1116338D02*
X165649Y1114468D01*
G01X163779Y1116338D02*
X161909Y1114468D01*
G01X163779Y1123818D02*
X161909Y1125688D01*
G01X160039Y1127558D02*
X158169Y1125688D01*
G01X160039Y1131299D02*
X158169Y1129429D01*
G01X156299Y1131299D02*
X154429Y1129429D01*
G01X152559Y1131299D02*
X150689Y1129429D01*
G01X152559Y1138779D02*
X150689Y1136909D01*
G01X167519Y1131299D02*
X165649Y1129429D01*
G01X163779Y1131299D02*
X161909Y1129429D01*
G01X167519Y1138779D02*
X165649Y1136909D01*
G01X160039Y1142519D02*
X158169Y1140649D01*
G01X167519Y1142519D02*
X165649Y1140649D01*
G01X152559Y1142519D02*
X150689Y1140649D01*
G01X156299Y1142519D02*
X154429Y1140649D01*
G01X163779Y1142519D02*
X161909Y1140649D01*
G01X152559Y1153740D02*
X150689Y1151870D01*
G01X160039Y1157480D02*
X158169Y1155610D01*
G01X156299Y1157480D02*
X154429Y1155610D01*
G01X152559Y1157480D02*
X150689Y1155610D01*
G01X163779Y1146259D02*
X161909Y1144389D01*
G01X163779Y1149999D02*
X161909Y1148129D01*
G01X163779Y1153740D02*
X161909Y1151870D01*
G01X163779Y1157480D02*
X161909Y1155610D01*
G01X152559Y1146259D02*
X150689Y1144389D01*
G01X160039Y1149999D02*
X158169Y1151869D01*
G01X156299Y1149999D02*
X154429Y1151869D01*
G01X152559Y1149999D02*
X150689Y1148129D01*
G01X152559Y1161220D02*
X150689Y1159350D01*
G01X163779Y1161220D02*
X161909Y1159350D01*
G01X152559Y1172440D02*
X154429Y1174310D01*
G01X150688D02*
X152559Y1172440D01*
G01X154429Y1174310D02*
X156299Y1172440D01*
G01X160039D02*
X161909Y1174310D01*
G01X156299Y1172440D02*
X158169Y1174310D01*
G01X154429Y1166830D02*
X156299Y1164960D01*
G01D02*
X158169Y1166830D01*
G01D02*
X160039Y1164960D01*
G01X150688Y1166830D02*
X152559Y1164960D01*
G01Y1168700D02*
X154429Y1170570D01*
G01X158169Y1174310D02*
X160039Y1172440D01*
G01X163779D02*
X161909Y1174310D01*
G01X165649D02*
X163779Y1172440D01*
G01X165649Y1170570D02*
X163779Y1168700D01*
G01X165649Y1166830D02*
X163779Y1164960D01*
G01X167519Y1183661D02*
X165649Y1181791D01*
G01D02*
X167519Y1179921D01*
G01X163779D02*
X165649Y1181791D01*
G01D02*
X163779Y1183661D01*
G01X160039D02*
X161909Y1181791D01*
G01X163779Y1183661D02*
X161909Y1181791D01*
G01D02*
X163779Y1179921D01*
G01D02*
X161909Y1178051D01*
G01D02*
X163779Y1176180D01*
G01X161909Y1178051D02*
X160039Y1179921D01*
G01X150688Y1178051D02*
X152559Y1176180D01*
G01X150688Y1178051D02*
X152559Y1179921D01*
G01X150688Y1174310D02*
X152559Y1176180D01*
G01X154429Y1174310D02*
X152559Y1176180D01*
G01X161909Y1174310D02*
X163779Y1176180D01*
G01D02*
X165649Y1174310D01*
G01Y1178050D02*
X163779Y1176180D01*
G01X171259Y1108858D02*
X169389Y1106988D01*
G01X167519Y1123818D02*
X169389Y1121948D01*
G01X178740Y1116338D02*
X176870Y1114468D01*
G01X178740Y1120078D02*
X176870Y1118208D01*
G01X178740Y1123818D02*
X176870Y1121948D01*
G01X174999Y1112598D02*
X173129Y1110728D01*
G01X171259Y1112598D02*
X169389Y1110728D01*
G01X182480Y1116338D02*
X180610Y1114468D01*
G01X182480Y1120078D02*
X180610Y1118208D01*
G01X182480Y1123818D02*
X180610Y1121948D01*
G01X182480Y1138779D02*
X180610Y1136909D01*
G01X174999Y1135039D02*
X173129Y1133169D01*
G01X171259Y1135039D02*
X169389Y1133169D01*
G01X178740Y1127558D02*
X176870Y1125688D01*
G01X178740Y1131299D02*
X176870Y1129429D01*
G01X178740Y1135039D02*
X176870Y1133169D01*
G01X178740Y1135039D02*
X180610Y1133169D01*
G01X178740Y1138779D02*
X176870Y1136909D01*
G01X174999Y1127558D02*
X173129Y1129428D01*
G01X171259Y1127558D02*
X169389Y1129428D01*
G01X182480Y1127558D02*
X180610Y1125688D01*
G01X182480Y1131299D02*
X180610Y1129429D01*
G01Y1133169D02*
X182480Y1135039D01*
G01Y1142519D02*
X180610Y1140649D01*
G01X171259Y1142519D02*
X169389Y1140649D01*
G01X174999Y1142519D02*
X173129Y1140649D01*
G01X178740Y1142519D02*
X176870Y1140649D01*
G01X182480Y1149999D02*
X180610Y1148129D01*
G01X174999Y1146259D02*
X173129Y1144389D01*
G01X171259Y1146259D02*
X169389Y1144389D01*
G01X174999Y1149999D02*
X173129Y1148129D01*
G01X174999Y1157480D02*
X173129Y1155610D01*
G01X174999Y1153740D02*
X173129Y1151870D01*
G01X182480Y1157480D02*
X180610Y1155610D01*
G01X182480Y1153740D02*
X180610Y1151870D01*
G01X182480Y1146259D02*
X180610Y1144389D01*
G01X178740Y1146259D02*
X176870Y1144389D01*
G01X178740Y1149999D02*
X176870Y1148129D01*
G01X178740Y1153740D02*
X176870Y1151870D01*
G01X178740Y1168700D02*
X180610Y1166830D01*
G01D02*
X182480Y1168700D01*
G01X180610Y1166830D02*
X182480Y1164960D01*
G01X178740Y1168700D02*
X180610Y1170570D01*
G01X174999Y1172440D02*
X173129Y1174310D01*
G01X174999Y1168700D02*
X173129Y1170570D01*
G01X174999Y1164960D02*
X173129Y1166830D01*
G01X180610Y1170570D02*
X182480Y1172440D01*
G01Y1168700D02*
X180610Y1170570D01*
G01X178740Y1168700D02*
X176870Y1170570D01*
G01D02*
X174999Y1168700D01*
G01Y1161220D02*
X173129Y1159350D01*
G01Y1166830D02*
X174999Y1168700D01*
G01X173129Y1170570D02*
X174999Y1172440D01*
G01X182480Y1161220D02*
X180610Y1159350D01*
G01D02*
X178740Y1157480D01*
G01X176870Y1174310D02*
X178740Y1172440D01*
G01Y1161220D02*
X176870Y1159350D01*
G01X178740Y1164960D02*
X176870Y1166830D01*
G01X174999Y1176180D02*
X173129Y1178051D01*
G01D02*
X174999Y1179921D01*
G01X173129Y1178051D02*
X171259Y1179921D01*
G01X174999D02*
X173129Y1181791D01*
G01D02*
X171259Y1179921D01*
G01Y1183661D02*
X173129Y1181791D01*
G01X182480Y1183661D02*
X180610Y1181791D01*
G01D02*
X182480Y1179921D01*
G01Y1172440D02*
X180610Y1174310D01*
G01X182480Y1176180D02*
X180610Y1178051D01*
G01Y1174310D02*
X182480Y1176180D01*
G01X173129Y1174310D02*
X174999Y1176180D01*
G01X180610Y1178051D02*
X182480Y1179921D01*
G01X176870Y1185531D02*
X178740Y1187401D01*
G01X171259D02*
X173129Y1185531D01*
G01X178740Y1183661D02*
X176870Y1185531D01*
G01X173129D02*
X171259Y1183661D01*
G01X178740Y1176180D02*
X176870Y1174310D01*
G01X178740Y1179921D02*
X176870Y1181791D01*
G01X178740Y1179921D02*
X176870Y1178051D01*
G01D02*
X178740Y1176180D01*
G01X197440Y1123818D02*
X195570Y1121948D01*
G01X193700Y1120078D02*
X191830Y1118208D01*
G01X189960Y1120078D02*
X188090Y1118208D01*
G01X186220Y1120078D02*
X184350Y1118208D01*
G01X193700Y1123818D02*
X191830Y1121948D01*
G01X189960Y1123818D02*
X188090Y1121948D01*
G01X186220Y1123818D02*
X184350Y1121948D01*
G01X197440Y1120078D02*
X195570Y1118208D01*
G01X197440Y1127558D02*
X195570Y1125688D01*
G01X197440Y1135039D02*
X199311Y1133169D01*
G01X197440Y1135039D02*
X195570Y1133169D01*
G01X197440Y1131299D02*
X195570Y1129429D01*
G01X197440Y1138779D02*
X195570Y1136909D01*
G01X193700Y1127558D02*
X191830Y1125688D01*
G01X189960Y1127558D02*
X188090Y1125688D01*
G01X186220Y1127558D02*
X184350Y1125688D01*
G01X189960Y1131299D02*
X188090Y1129429D01*
G01X186220Y1131299D02*
X184350Y1129429D01*
G01X189960Y1135039D02*
X188090Y1133169D01*
G01X186220Y1135039D02*
X184350Y1133169D01*
G01X189960Y1138779D02*
X188090Y1136909D01*
G01X195570Y1133169D02*
X197440Y1131299D01*
G01X195570Y1129429D02*
X197440Y1127558D01*
G01X195570Y1136909D02*
X197440Y1135039D01*
G01X193700Y1138779D02*
X191830Y1136909D01*
G01X186220Y1142519D02*
X184350Y1140649D01*
G01X189960Y1142519D02*
X188090Y1140649D01*
G01X197440Y1146259D02*
X199311Y1148129D01*
G01X197440Y1146259D02*
X195570Y1144389D01*
G01X197440Y1153740D02*
X199311Y1155610D01*
G01X193700Y1149999D02*
X191830Y1148129D01*
G01X193700Y1149999D02*
X195570Y1151869D01*
G01X189960Y1146259D02*
X188090Y1144389D01*
G01Y1151870D02*
X189960Y1153740D01*
G01D02*
X191830Y1155610D01*
G01D02*
X193700Y1157480D01*
G01X195570Y1151869D02*
X197440Y1153740D01*
G01X193700D02*
X191830Y1151869D01*
G01X197440Y1157480D02*
X195570Y1155610D01*
G01D02*
X193700Y1153740D01*
G01Y1146259D02*
X191830Y1144389D01*
G01X197440Y1149999D02*
X195570Y1148129D01*
G01D02*
X193700Y1146259D01*
G01X186220D02*
X184350Y1144389D01*
G01X186220Y1153740D02*
X184350Y1151870D01*
G01X189960Y1149999D02*
X188090Y1148129D01*
G01X193700Y1172440D02*
X191830Y1174310D01*
G01X197440Y1168700D02*
X195570Y1170570D01*
G01X197440Y1168700D02*
X199311Y1166830D01*
G01X189960Y1168700D02*
X188090Y1170570D01*
G01X189960Y1168700D02*
X191830Y1166830D01*
G01X197440Y1161220D02*
X195570Y1159350D01*
G01X189960Y1161220D02*
X188090Y1159350D01*
G01Y1170570D02*
X186220Y1172440D01*
G01X191830Y1166830D02*
X193700Y1164960D01*
G01X195570Y1159350D02*
X193700Y1157480D01*
G01X195570Y1170570D02*
X193700Y1172440D01*
G01X197440Y1157480D02*
X199311Y1159350D01*
G01X193700Y1168700D02*
X191830Y1170570D01*
G01X193700Y1168700D02*
X195570Y1166830D01*
G01D02*
X197440Y1164960D01*
G01X193700Y1161220D02*
X191830Y1159350D01*
G01X197440Y1172440D02*
X195570Y1174310D01*
G01X197440Y1172440D02*
X199311Y1170570D01*
G01X186220Y1161220D02*
X184350Y1159350D01*
G01Y1170570D02*
X186220Y1168700D01*
G01X188090Y1166830D02*
X189960Y1164960D01*
G01Y1172440D02*
X188090Y1174310D01*
G01X197440Y1183661D02*
X199311Y1181791D01*
G01X197440Y1187401D02*
X199311Y1189271D01*
G01X197440Y1191141D02*
X195570Y1189271D01*
G01D02*
X193700Y1187401D01*
G01X197440D02*
X195570Y1189271D01*
G01X193700Y1187401D02*
X195570Y1185531D01*
G01X193700Y1179921D02*
X195570Y1178051D01*
G01X186220Y1187401D02*
X188090Y1185531D01*
G01D02*
X189960Y1187401D01*
G01X188090Y1185531D02*
X189960Y1183661D01*
G01X186220Y1187401D02*
X184350Y1189271D01*
G01D02*
X182480Y1187401D01*
G01Y1191141D02*
X184350Y1189271D01*
G01D02*
X186220Y1191141D01*
G01X189960Y1183661D02*
X191830Y1181791D01*
G01X197440Y1176180D02*
X199311Y1174310D01*
G01X189960Y1176180D02*
X188090Y1178051D01*
G01D02*
X186220Y1179921D01*
G01X191830Y1181791D02*
X193700Y1179921D01*
G01X191830Y1174310D02*
X189960Y1176180D01*
G01X195570Y1185531D02*
X197440Y1183661D01*
G01X195570Y1178051D02*
X197440Y1176180D01*
G01X193700D02*
X191830Y1178051D01*
G01X195570Y1174310D02*
X193700Y1176180D01*
G01X191830Y1185531D02*
X193700Y1183661D01*
G01X197440Y1179921D02*
X195570Y1181791D01*
G01D02*
X193700Y1183661D01*
G01X189960Y1179921D02*
X188090Y1181791D01*
G01X186220Y1176180D02*
X184350Y1178051D01*
G01X197440Y1194881D02*
X199311Y1196751D01*
G01X197440Y1198621D02*
X195570Y1196751D01*
G01X197440Y1198621D02*
X195570Y1200491D01*
G01X197440Y1194881D02*
X195570Y1193011D01*
G01X189960Y1191141D02*
X188090Y1193011D01*
G01D02*
X186220Y1191141D01*
G01Y1194881D02*
X188090Y1193011D01*
G01X182480Y1191141D02*
X184350Y1193011D01*
G01D02*
X186220Y1191141D01*
G01Y1194881D02*
X184350Y1193011D01*
G01D02*
X182480Y1194881D01*
G01X189960D02*
X188090Y1196751D01*
G01D02*
X186220Y1194881D01*
G01X189960Y1198621D02*
X188090Y1196751D01*
G01D02*
X186220Y1198621D01*
G01X189960D02*
X191830Y1196751D01*
G01Y1200491D02*
X189960Y1198621D01*
G01X186220Y1194881D02*
X184350Y1196751D01*
G01D02*
X182480Y1194881D01*
G01X188090Y1200491D02*
X189960Y1198621D01*
G01Y1202362D02*
X188090Y1200491D01*
G01X199311Y1204232D02*
X197440Y1202362D01*
G01D02*
X195570Y1204232D01*
G01D02*
X197440Y1206102D01*
G01X193700D02*
X195570Y1204232D01*
G01X189960Y1206102D02*
X191830Y1204232D01*
G01D02*
X189960Y1202362D01*
G01X193700Y1206102D02*
X191830Y1204232D01*
G01D02*
X193700Y1202362D01*
G01X195570Y1204232D02*
X193700Y1202362D01*
G01X188090Y1204232D02*
X189960Y1202362D01*
G01Y1206102D02*
X188090Y1204232D01*
G01Y1193011D02*
X189960Y1194881D01*
G01X195570Y1196751D02*
X197440Y1194881D01*
G01X195570Y1193011D02*
X197440Y1191141D01*
G01X193700D02*
X191830Y1193011D01*
G01X199311Y1204232D02*
X197440Y1206102D01*
G01X199311Y1207972D02*
X197440Y1206102D01*
G01Y1209842D02*
X199311Y1207972D01*
G01X197440Y1206102D02*
X195570Y1207972D01*
G01D02*
X193700Y1206102D01*
G01X195570Y1207972D02*
X197440Y1209842D01*
G01X191830Y1207972D02*
X189960Y1206102D01*
G01X193700D02*
X191830Y1207972D01*
G01Y1219192D02*
X193700Y1217322D01*
G01X214271Y1114468D02*
X216141Y1116338D01*
G01X212401Y1120078D02*
X210531Y1121948D01*
G01D02*
X212401Y1123818D01*
G01X208661Y1120078D02*
X210531Y1121948D01*
G01X206791Y1118208D02*
X208661Y1120078D01*
G01X204921D02*
X203051Y1118208D01*
G01X204921Y1120078D02*
X206791Y1121948D01*
G01D02*
X208661Y1120078D01*
G01Y1123818D02*
X206791Y1121948D01*
G01D02*
X204921Y1123818D01*
G01D02*
X203051Y1121948D01*
G01X210531D02*
X208661Y1123818D01*
G01D02*
X210531Y1125688D01*
G01X204921Y1123818D02*
X206791Y1125688D01*
G01X212401Y1120078D02*
X214271Y1118208D01*
G01D02*
X216141Y1116338D01*
G01X214271Y1118208D02*
X216141Y1120078D01*
G01X214271Y1110728D02*
X216141Y1112598D01*
G01X212401Y1120078D02*
X214271Y1121948D01*
G01D02*
X216141Y1120078D01*
G01Y1123818D02*
X214271Y1121948D01*
G01D02*
X212401Y1123818D01*
G01X208661Y1120078D02*
X210531Y1118208D01*
G01Y1125688D02*
X212401Y1123818D01*
G01X206791Y1125688D02*
X208661Y1123818D01*
G01X201181Y1120078D02*
X199311Y1118208D01*
G01X201181Y1123818D02*
X199311Y1121948D01*
G01X210531Y1118208D02*
X212401Y1120078D01*
G01X216141Y1127558D02*
X214271Y1125688D01*
G01D02*
X216141Y1123818D01*
G01X214271Y1125688D02*
X212401Y1127558D01*
G01X210531Y1125688D02*
X208661Y1127558D01*
G01X206791Y1125688D02*
X208661Y1127558D01*
G01X204921D02*
X206791Y1125688D01*
G01X204921Y1127558D02*
X203051Y1125688D01*
G01X212401Y1127558D02*
X210531Y1125688D01*
G01X208661Y1135039D02*
X206791Y1133169D01*
G01X204921Y1135039D02*
X203051Y1133169D01*
G01X208661Y1135039D02*
X210531Y1133169D01*
G01X216141Y1135039D02*
X214271Y1133169D01*
G01X201181Y1127558D02*
X199311Y1125688D01*
G01X206791Y1133169D02*
X204921Y1135039D01*
G01X203051Y1133169D02*
X201181Y1135039D01*
G01X199311Y1133169D02*
X201181Y1135039D01*
G01X210531Y1133169D02*
X212401Y1135039D01*
G01X214271Y1133169D02*
X212401Y1135039D01*
G01X216141Y1138779D02*
X214271Y1136909D01*
G01X201181Y1138779D02*
X199311Y1136909D01*
G01X208661Y1138779D02*
X206791Y1136909D01*
G01X204921Y1138779D02*
X203051Y1136909D01*
G01X208661Y1138779D02*
X210531Y1136909D01*
G01X206791D02*
X204921Y1138779D01*
G01X203051Y1136909D02*
X201181Y1138779D01*
G01X214271Y1136909D02*
X212401Y1138779D01*
G01X210531Y1136909D02*
X212401Y1138779D01*
G01X203051Y1129429D02*
X204921Y1131299D01*
G01X210531Y1129429D02*
X212401Y1131299D01*
G01X214271Y1129429D02*
X216141Y1131299D01*
G01X206791Y1129429D02*
X208661Y1131299D01*
G01X199311Y1129429D02*
X201181Y1131299D01*
G01Y1142519D02*
X199311Y1140649D01*
G01X204921Y1142519D02*
X203051Y1140649D01*
G01X208661Y1142519D02*
X206791Y1140649D01*
G01X208661Y1142519D02*
X210531Y1140649D01*
G01X212401Y1142519D02*
X214271Y1140649D01*
G01X216141Y1149999D02*
X214271Y1148129D01*
G01X204921Y1149999D02*
X203051Y1148129D01*
G01X208661Y1149999D02*
X206791Y1148129D01*
G01X208661Y1149999D02*
X210531Y1148129D01*
G01X216141Y1157480D02*
X214271Y1155610D01*
G01X203051Y1148129D02*
X201181Y1149999D01*
G01X199311Y1148129D02*
X201181Y1149999D01*
G01X206791Y1148129D02*
X204921Y1149999D01*
G01X214271Y1148129D02*
X212401Y1149999D01*
G01X210531Y1148129D02*
X212401Y1149999D01*
G01X199311Y1155610D02*
X201181Y1157480D01*
G01X208661D02*
X206791Y1155610D01*
G01X203051Y1140649D02*
X201181Y1142519D01*
G01X206791Y1140649D02*
X204921Y1142519D01*
G01X210531Y1140649D02*
X212401Y1142519D01*
G01X214271Y1140649D02*
X216141Y1142519D01*
G01X204921Y1157480D02*
X203051Y1155610D01*
G01X212401Y1157480D02*
X210531Y1155610D01*
G01X216141Y1146259D02*
X214271Y1144389D01*
G01X201181Y1146259D02*
X199311Y1144389D01*
G01X208661Y1146259D02*
X206791Y1144389D01*
G01X204921Y1146259D02*
X203051Y1144389D01*
G01X208661Y1146259D02*
X210531Y1144389D01*
G01X206791D02*
X204921Y1146259D01*
G01X203051Y1144389D02*
X201181Y1146259D01*
G01X214271Y1144389D02*
X212401Y1146259D01*
G01X210531Y1144389D02*
X212401Y1146259D01*
G01X199311Y1151870D02*
X201181Y1153740D01*
G01X203051Y1151870D02*
X204921Y1153740D01*
G01X206791Y1151870D02*
X208661Y1153740D01*
G01X210531Y1151870D02*
X212401Y1153740D01*
G01X214271Y1151870D02*
X216141Y1153740D01*
G01X208661Y1164960D02*
X206791Y1166830D01*
G01X204921Y1168700D02*
X203051Y1170570D01*
G01X204921Y1161220D02*
X203051Y1159350D01*
G01X212401Y1161220D02*
X210531Y1159350D01*
G01X206791Y1166830D02*
X204921Y1168700D01*
G01X203051Y1159350D02*
X201181Y1157480D01*
G01X199311Y1166830D02*
X201181Y1164960D01*
G01X203051Y1170570D02*
X201181Y1172440D01*
G01X208661D02*
X206791Y1174310D01*
G01X216141Y1164960D02*
X214271Y1166830D01*
G01X212401Y1168700D02*
X210531Y1170570D01*
G01X214271Y1166830D02*
X212401Y1168700D01*
G01X210531Y1159350D02*
X208661Y1157480D01*
G01X210531Y1170570D02*
X208661Y1172440D01*
G01X199311Y1174310D02*
X201181Y1172440D01*
G01X199311Y1159350D02*
X201181Y1161220D01*
G01X208661D02*
X206791Y1159350D01*
G01D02*
X204921Y1157480D01*
G01X216141Y1161220D02*
X214271Y1159350D01*
G01D02*
X212401Y1157480D01*
G01X201181Y1168700D02*
X203051Y1166830D01*
G01D02*
X204921Y1164960D01*
G01X199311Y1170570D02*
X201181Y1168700D01*
G01X208661D02*
X206791Y1170570D01*
G01X212401Y1164960D02*
X210531Y1166830D01*
G01D02*
X208661Y1168700D01*
G01X212401Y1172440D02*
X210531Y1174310D01*
G01X212401Y1172440D02*
X214271Y1170570D01*
G01D02*
X216141Y1168700D01*
G01X204921Y1172440D02*
X203051Y1174310D01*
G01X216141Y1179921D02*
X214271Y1181791D01*
G01X208661Y1179921D02*
X206791Y1181791D01*
G01X204921Y1179921D02*
X203051Y1181791D01*
G01X208661Y1179921D02*
X210531Y1181791D01*
G01X212401Y1187401D02*
X214271Y1189271D01*
G01X208661Y1187401D02*
X206791Y1189271D01*
G01X204921Y1187401D02*
X203051Y1189271D01*
G01X208661Y1187401D02*
X210531Y1189271D01*
G01X216141Y1172440D02*
X214271Y1174310D01*
G01X206791Y1181791D02*
X204921Y1179921D01*
G01X203051Y1181791D02*
X201181Y1179921D01*
G01X199311Y1181791D02*
X201181Y1179921D01*
G01X206791Y1189271D02*
X204921Y1187401D01*
G01X203051Y1189271D02*
X201181Y1187401D01*
G01X199311Y1189271D02*
X201181Y1187401D01*
G01X214271Y1181791D02*
X212401Y1179921D01*
G01X210531Y1181791D02*
X212401Y1179921D01*
G01X210531Y1189271D02*
X212401Y1187401D01*
G01X216141Y1176180D02*
X214271Y1178051D01*
G01X201181Y1176180D02*
X199311Y1178051D01*
G01X208661Y1176180D02*
X206791Y1178051D01*
G01X204921Y1176180D02*
X203051Y1178051D01*
G01X208661Y1176180D02*
X210531Y1178051D01*
G01X206791D02*
X204921Y1176180D01*
G01X203051Y1178051D02*
X201181Y1176180D01*
G01X214271Y1178051D02*
X212401Y1176180D01*
G01X210531Y1178051D02*
X212401Y1176180D01*
G01X216141Y1183661D02*
X214271Y1185531D01*
G01X201181Y1183661D02*
X199311Y1185531D01*
G01X201181Y1183661D02*
X203051Y1185531D01*
G01X208661Y1183661D02*
X206791Y1185531D01*
G01X208661Y1183661D02*
X210531Y1185531D01*
G01X203051D02*
X204921Y1183661D01*
G01X206791Y1185531D02*
X204921Y1183661D01*
G01X214271Y1185531D02*
X212401Y1183661D01*
G01X210531Y1185531D02*
X212401Y1183661D01*
G01Y1194881D02*
X214271Y1196751D01*
G01X204921Y1194881D02*
X206791Y1196751D01*
G01X201181Y1194881D02*
X203051Y1196751D01*
G01X212401Y1194881D02*
X210531Y1196751D01*
G01X204921Y1206102D02*
X206791Y1204232D01*
G01X201181Y1202362D02*
X203051Y1204232D01*
G01D02*
X204921Y1202362D01*
G01Y1206102D02*
X203051Y1204232D01*
G01D02*
X201181Y1206102D01*
G01Y1202362D02*
X199311Y1204232D01*
G01X216141Y1202362D02*
X214271Y1204232D01*
G01D02*
X212401Y1202362D01*
G01X216141Y1206102D02*
X214271Y1204232D01*
G01D02*
X212401Y1206102D01*
G01X208661D02*
X210531Y1204232D01*
G01D02*
X212401Y1202362D01*
G01X210531Y1204232D02*
X212401Y1206102D01*
G01X210531Y1204232D02*
X208661Y1202362D01*
G01X206791Y1204232D02*
X208661Y1206102D01*
G01X204921Y1202362D02*
X206791Y1204232D01*
G01D02*
X208661Y1202362D01*
G01X199311Y1204232D02*
X201181Y1206102D01*
G01X214271Y1189271D02*
X216141Y1187401D01*
G01X206791Y1196751D02*
X208661Y1194881D01*
G01X203051Y1196751D02*
X204921Y1194881D01*
G01X199311Y1196751D02*
X201181Y1194881D01*
G01X214271Y1196751D02*
X216141Y1194881D01*
G01X210531Y1196751D02*
X208661Y1194881D01*
G01X206791Y1193011D02*
X208661Y1191141D01*
G01X203051Y1193011D02*
X204921Y1191141D01*
G01X210531Y1193011D02*
X208661Y1191141D01*
G01X214271Y1193011D02*
X212401Y1191141D01*
G01X204921D02*
X206791Y1193011D01*
G01X212401Y1191141D02*
X210531Y1193011D01*
G01X216141Y1191141D02*
X214271Y1193011D01*
G01X201181Y1191141D02*
X203051Y1193011D01*
G01X201181Y1191141D02*
X199311Y1193011D01*
G01X203051Y1200491D02*
X204921Y1198621D01*
G01X206791Y1200491D02*
X208661Y1198621D01*
G01X199311Y1200491D02*
X201181Y1198621D01*
G01X210531Y1200491D02*
X212401Y1198621D01*
G01X214271Y1200491D02*
X216141Y1198621D01*
G01X208661Y1206102D02*
X206791Y1207972D01*
G01D02*
X204921Y1206102D01*
G01X206791Y1207972D02*
X204921Y1209842D01*
G01D02*
X203051Y1207972D01*
G01D02*
X201181Y1209842D01*
G01X204921Y1206102D02*
X203051Y1207972D01*
G01D02*
X201181Y1206102D01*
G01X216141Y1209842D02*
X214271Y1207972D01*
G01D02*
X212401Y1209842D01*
G01X216141Y1206102D02*
X214271Y1207972D01*
G01D02*
X212401Y1206102D01*
G01Y1209842D02*
X210531Y1207972D01*
G01D02*
X212401Y1206102D01*
G01X208661D02*
X210531Y1207972D01*
G01X206791D02*
X208661Y1209842D01*
G01X210531Y1211712D02*
X208661Y1209842D01*
G01X210531Y1207972D02*
X208661Y1209842D01*
G01X201181D02*
X199311Y1207972D01*
G01D02*
X201181Y1206102D01*
G01X231102Y1120078D02*
X229232Y1121948D01*
G01D02*
X227362Y1120078D01*
G01X231102Y1123818D02*
X229232Y1121948D01*
G01D02*
X227362Y1123818D01*
G01D02*
X225492Y1121948D01*
G01D02*
X227362Y1120078D01*
G01X223622D02*
X225492Y1121948D01*
G01X216141Y1116338D02*
X218011Y1118208D01*
G01D02*
X216141Y1120078D01*
G01X218011Y1118208D02*
X219881Y1120078D01*
G01X216141D02*
X218011Y1121948D01*
G01D02*
X219881Y1120078D01*
G01Y1123818D02*
X218011Y1121948D01*
G01D02*
X216141Y1123818D01*
G01X219881Y1120078D02*
X221751Y1121948D01*
G01D02*
X223622Y1120078D01*
G01Y1123818D02*
X221751Y1121948D01*
G01D02*
X219881Y1123818D01*
G01X225492Y1121948D02*
X223622Y1123818D01*
G01D02*
X225492Y1125688D01*
G01X223622Y1123818D02*
X221751Y1125688D01*
G01X227362Y1120078D02*
X229232Y1118208D01*
G01D02*
X231102Y1120078D01*
G01X229232Y1118208D02*
X231102Y1116338D01*
G01X227362Y1120078D02*
X225492Y1118208D01*
G01X219881Y1120078D02*
X221751Y1118208D01*
G01X231102Y1116338D02*
X229232Y1114468D01*
G01X225492Y1125688D02*
X227362Y1123818D01*
G01X218011Y1125688D02*
X216141Y1123818D01*
G01X221751Y1125688D02*
X219881Y1123818D01*
G01X229232Y1125688D02*
X227362Y1123818D01*
G01X225492Y1118208D02*
X223622Y1120078D01*
G01X221751Y1118208D02*
X223622Y1120078D01*
G01X229232Y1114468D02*
X231102Y1112598D01*
G01X225492Y1125688D02*
X227362Y1127558D01*
G01D02*
X229232Y1125688D01*
G01X219881Y1127558D02*
X218011Y1125688D01*
G01X216141Y1127558D02*
X218011Y1125688D01*
G01X221751D02*
X219881Y1127558D01*
G01X223622D02*
X225492Y1125688D01*
G01X223622Y1127558D02*
X221751Y1125688D01*
G01X231102Y1127558D02*
X229232Y1125688D01*
G01X231102Y1123818D02*
X229232Y1125688D01*
G01X216141Y1135039D02*
X218011Y1133169D01*
G01X223622Y1135039D02*
X221751Y1133169D01*
G01X231102Y1135039D02*
Y1134448D01*
X229330Y1132677D01*
G01X227362Y1135039D02*
X225492Y1133169D01*
G01D02*
X223622Y1135039D01*
G01X221751Y1133169D02*
X219881Y1135039D01*
G01X218011Y1133169D02*
X219881Y1135039D01*
G01X229330Y1132677D02*
X227362Y1134645D01*
Y1135039D01*
G01Y1138779D02*
X225492Y1136909D01*
G01X219881Y1138779D02*
X221751Y1136909D01*
G01X219881Y1138779D02*
X218011Y1136909D01*
G01X227362Y1138779D02*
X229232Y1136909D01*
G01X225492D02*
X223622Y1138779D01*
G01X221751Y1136909D02*
X223622Y1138779D01*
G01X218011Y1136909D02*
X216141Y1138779D01*
G01X229232Y1136909D02*
X231102Y1138779D01*
G01X225492Y1129429D02*
X227362Y1131299D01*
G01X221751Y1129429D02*
X223622Y1131299D01*
G01X218011Y1129429D02*
X219881Y1131299D01*
G01X229232Y1129429D02*
X231102Y1131299D01*
G01X216141Y1142519D02*
X218011Y1140649D01*
G01X227362Y1142519D02*
X225492Y1140649D01*
G01X223622Y1142519D02*
X221751Y1140649D01*
G01X227362Y1142519D02*
X229232Y1140649D01*
G01X225492D02*
X223622Y1142519D01*
G01X218011Y1140649D02*
X219881Y1142519D01*
G01X221751Y1140649D02*
X219881Y1142519D01*
G01X229232Y1140649D02*
X231102Y1142519D01*
G01X227362Y1149999D02*
X225492Y1148129D01*
G01X219881Y1149999D02*
X221751Y1148129D01*
G01X219881Y1149999D02*
X218011Y1148129D01*
G01X227362Y1149999D02*
X229232Y1148129D01*
G01X225492D02*
X223622Y1149999D01*
G01X221751Y1148129D02*
X223622Y1149999D01*
G01X218011Y1148129D02*
X216141Y1149999D01*
G01X229232Y1148129D02*
X231102Y1149999D01*
G01X223622Y1157480D02*
X221751Y1155610D01*
G01X231102Y1157480D02*
X229232Y1155610D01*
G01X227362Y1157480D02*
X225492Y1155610D01*
G01X219881Y1157480D02*
X218011Y1155610D01*
G01X223622Y1146259D02*
X225492Y1144389D01*
G01X219881Y1146259D02*
X221751Y1144389D01*
G01X216141Y1146259D02*
X218011Y1144389D01*
G01X231102Y1146259D02*
X229232Y1144389D01*
G01X225492D02*
X227362Y1146259D01*
G01X221751Y1144389D02*
X223622Y1146259D01*
G01X218011Y1144389D02*
X219881Y1146259D01*
G01X229232Y1144389D02*
X227362Y1146259D01*
G01X225492Y1151870D02*
X227362Y1153740D01*
G01X218011Y1151870D02*
X219881Y1153740D01*
G01X221752Y1151870D02*
X223622Y1153740D01*
G01X229232Y1151870D02*
X231102Y1153740D01*
G01X227362Y1161220D02*
X225492Y1159350D01*
G01X223622Y1172440D02*
X221751Y1174310D01*
G01X223622Y1172440D02*
X225492Y1170570D01*
G01X231102Y1164960D02*
X229232Y1166830D01*
G01X225492Y1170570D02*
X227362Y1168700D01*
G01X225492Y1159350D02*
X223622Y1157480D01*
G01Y1164960D02*
X221752Y1166830D01*
G01X219881Y1168700D02*
X218011Y1170570D01*
G01D02*
X216141Y1172440D01*
G01X221752Y1166830D02*
X219882Y1168700D01*
X219881D01*
G01Y1161220D02*
X218011Y1159350D01*
G01D02*
X216141Y1157480D01*
G01X229232Y1166830D02*
X227362Y1168700D01*
G01X231102Y1161220D02*
X229232Y1159350D01*
G01D02*
X227362Y1157480D01*
G01X223622Y1161220D02*
X221751Y1159350D01*
G01D02*
X219881Y1157480D01*
G01Y1164960D02*
X218011Y1166830D01*
G01D02*
X216141Y1168700D01*
G01X227362Y1172440D02*
X225492Y1174310D01*
G01X231102Y1168700D02*
X229232Y1170570D01*
G01D02*
X227362Y1172440D01*
G01X219881D02*
X218011Y1174310D01*
G01X223622Y1168700D02*
X225492Y1166830D01*
G01X223622Y1168700D02*
X221751Y1170570D01*
G01X225492Y1166830D02*
X227362Y1164960D01*
G01X221751Y1170570D02*
X219881Y1172440D01*
G01X227362Y1179921D02*
X225492Y1181791D01*
G01X223622Y1179921D02*
X221751Y1181791D01*
G01X219881Y1179921D02*
X218011Y1181791D01*
G01X227362Y1179921D02*
X229232Y1181791D01*
G01X223622Y1187401D02*
X225492Y1189271D01*
G01X223622Y1187401D02*
X221751Y1189271D01*
G01X219881Y1187401D02*
X218011Y1189271D01*
G01X227362Y1187401D02*
X229232Y1189271D01*
G01X225492Y1181791D02*
X223622Y1179921D01*
G01X225492Y1189271D02*
X227362Y1187401D01*
G01X221751Y1181791D02*
X219881Y1179921D01*
G01X218011Y1181791D02*
X216141Y1179921D01*
G01X221751Y1189271D02*
X219881Y1187401D01*
G01X218011Y1189271D02*
X216141Y1187401D01*
G01X229232Y1181791D02*
X231102Y1179921D01*
G01X229232Y1189271D02*
X231102Y1187401D01*
G01Y1172440D02*
X229232Y1174310D01*
G01X227362Y1176180D02*
X225492Y1178051D01*
G01X219881Y1176180D02*
X221751Y1178051D01*
G01X219881Y1176180D02*
X218011Y1178051D01*
G01X227362Y1176180D02*
X229232Y1178051D01*
G01X225492D02*
X223622Y1176180D01*
G01X221751Y1178051D02*
X223622Y1176180D01*
G01X218011Y1178051D02*
X216141Y1176180D01*
G01X229232Y1178051D02*
X231102Y1176180D01*
G01X227362Y1183661D02*
X225492Y1185531D01*
G01X219881Y1183661D02*
X218011Y1185531D01*
G01X219881Y1183661D02*
X221751Y1185531D01*
G01X227362Y1183661D02*
X229232Y1185531D01*
G01X225492D02*
X223622Y1183661D01*
G01X218011Y1185531D02*
X216141Y1183661D01*
G01X221751Y1185531D02*
X223622Y1183661D01*
G01X229232Y1185531D02*
X231102Y1183661D01*
G01X227362Y1194881D02*
X229232Y1196751D01*
G01X227362Y1194881D02*
X225492Y1196751D01*
G01X219881Y1194881D02*
X221751Y1196751D01*
G01X219881Y1194881D02*
X218011Y1196751D01*
G01X223622Y1206102D02*
X225492Y1204232D01*
G01D02*
X227362Y1206102D01*
G01X225492Y1204232D02*
X227362Y1202362D01*
G01X225492Y1204232D02*
X223622Y1202362D01*
G01D02*
X221751Y1204232D01*
G01D02*
X219881Y1202362D01*
G01X223622Y1206102D02*
X221751Y1204232D01*
G01D02*
X219881Y1206102D01*
G01Y1202362D02*
X218011Y1204232D01*
G01D02*
X216141Y1202362D01*
G01X219881Y1206102D02*
X218011Y1204232D01*
G01D02*
X216141Y1206102D01*
G01X227362Y1202362D02*
X229232Y1204232D01*
G01D02*
X231102Y1202362D01*
G01Y1206102D02*
X229232Y1204232D01*
G01X227362Y1206102D02*
X229232Y1204232D01*
G01Y1196751D02*
X231102Y1194881D01*
G01X225492Y1196751D02*
X223622Y1194881D01*
G01X221751Y1196751D02*
X223622Y1194881D01*
G01X218011Y1196751D02*
X216141Y1194881D01*
G01X229232Y1193011D02*
X231102Y1191141D01*
G01X225492Y1193011D02*
X223622Y1191141D01*
G01X221751Y1193011D02*
X223622Y1191141D01*
G01X218011Y1193011D02*
X219881Y1191141D01*
G01X227362D02*
X229232Y1193011D01*
G01X219881Y1191141D02*
X221751Y1193011D01*
G01X227362Y1191141D02*
X225492Y1193011D01*
G01X216141Y1191141D02*
X218011Y1193011D01*
G01X229232Y1200491D02*
X231102Y1198621D01*
G01X225492Y1200491D02*
X227362Y1198621D01*
G01X221751Y1200491D02*
X223622Y1198621D01*
G01X218011Y1200491D02*
X219881Y1198621D01*
G01X227362Y1206102D02*
X225492Y1207972D01*
G01D02*
X227362Y1209842D01*
G01X223622Y1206102D02*
X225492Y1207972D01*
G01X219881Y1206102D02*
X221751Y1207972D01*
G01D02*
X223622Y1206102D01*
G01Y1209842D02*
X221751Y1207972D01*
G01X225492D02*
X223622Y1209842D01*
G01X221751Y1207972D02*
X219881Y1209842D01*
G01D02*
X218011Y1207972D01*
G01D02*
X216141Y1209842D01*
G01X219881Y1206102D02*
X218011Y1207972D01*
G01D02*
X216141Y1206102D01*
G01X227362Y1209842D02*
X229232Y1207972D01*
G01D02*
X231102Y1209842D01*
G01X227362Y1206102D02*
X229232Y1207972D01*
G01D02*
X231102Y1206102D01*
G01X236712Y1121948D02*
X238582Y1120078D01*
G01X234842Y1123818D02*
X236712Y1121948D01*
G01X238582Y1123818D02*
X236712Y1125688D01*
G01X246062Y1123818D02*
X247933Y1121948D01*
G01Y1125688D02*
X246062Y1123818D01*
G01X242322D02*
X244192Y1125688D01*
G01X246062Y1123818D02*
X244192Y1121948D01*
G01D02*
X242322Y1123818D01*
G01Y1120078D02*
X244192Y1121948D01*
G01X242322Y1123818D02*
X240452Y1121948D01*
G01D02*
X242322Y1120078D01*
G01X238582D02*
X240452Y1121948D01*
G01D02*
X238582Y1123818D01*
G01X242322D02*
X240452Y1125688D01*
G01X247933Y1121948D02*
X246062Y1120078D01*
G01X244192Y1121948D02*
X246062Y1120078D01*
G01X240452Y1125688D02*
X238582Y1123818D01*
G01X244192Y1125688D02*
X246062Y1123818D01*
G01X236712Y1125688D02*
X234842Y1123818D01*
G01X238582Y1127558D02*
X240452Y1125688D01*
G01X234842Y1127558D02*
X236712Y1125688D01*
G01X246062Y1127558D02*
X244192Y1125688D01*
G01X246062Y1127558D02*
X247933Y1125688D01*
G01X236712D02*
X238582Y1127558D01*
G01X244192Y1125688D02*
X242322Y1127558D01*
G01X240452Y1125688D02*
X242322Y1127558D01*
G01X246062Y1135039D02*
X247933Y1133169D01*
G01X234842Y1135039D02*
X236417Y1133464D01*
X236712D01*
G01X242322Y1135039D02*
X240452Y1133169D01*
G01X242322Y1135039D02*
X244192Y1133169D01*
G01X236712Y1133464D02*
X238287Y1135039D01*
X238582D01*
G01X240452Y1133169D02*
X238582Y1135039D01*
G01X244192Y1133169D02*
X246062Y1135039D01*
G01Y1138779D02*
X247933Y1136909D01*
G01X242322Y1138779D02*
X240452Y1136909D01*
G01X234842Y1138779D02*
X236712Y1136909D01*
G01X242322Y1138779D02*
X244192Y1136909D01*
G01X240452D02*
X238582Y1138779D01*
G01X236712Y1136909D02*
X238582Y1138779D01*
G01X244192Y1136909D02*
X246062Y1138779D01*
G01X236712Y1129429D02*
X234842Y1131299D01*
G01X240452Y1129429D02*
X238582Y1131299D01*
G01X244192Y1129429D02*
X242322Y1131299D01*
G01X247933Y1129429D02*
X246062Y1131299D01*
G01Y1142519D02*
X247933Y1140649D01*
G01X246062Y1149999D02*
X247933Y1148129D01*
G01X234842Y1142519D02*
X236712Y1140649D01*
G01X242322Y1142519D02*
X240452Y1140649D01*
G01X242322Y1142519D02*
X244192Y1140649D01*
G01X234842Y1149999D02*
X236712Y1148129D01*
G01X242322Y1149999D02*
X240452Y1148129D01*
G01X242322Y1149999D02*
X244192Y1148129D01*
G01X236712Y1140649D02*
X238582Y1142519D01*
G01X240452Y1140649D02*
X238582Y1142519D01*
G01X244192Y1140649D02*
X246062Y1142519D01*
G01X236712Y1148129D02*
X238582Y1149999D01*
G01X240452Y1148129D02*
X238582Y1149999D01*
G01X244192Y1148129D02*
X246062Y1149999D01*
G01X238582Y1157480D02*
X240452Y1155610D01*
G01X242322Y1157480D02*
X244192Y1155610D01*
G01X234842Y1157480D02*
X236712Y1155610D01*
G01X246062Y1146259D02*
X247933Y1144389D01*
G01X238582Y1146259D02*
X240452Y1144389D01*
G01X234842Y1146259D02*
X236712Y1144389D01*
G01X242322Y1146259D02*
X244192Y1144389D01*
G01X240452D02*
X242322Y1146259D01*
G01X236712Y1144389D02*
X238582Y1146259D01*
G01X244192Y1144389D02*
X246062Y1146259D01*
G01Y1153740D02*
X247933Y1151869D01*
G01X242322Y1153740D02*
X240452Y1151869D01*
G01X234842Y1153740D02*
X236712Y1151869D01*
G01X242322Y1153740D02*
X244192Y1151869D01*
G01X240452D02*
X238582Y1153740D01*
G01X236712Y1151869D02*
X238582Y1153740D01*
G01X244192Y1151869D02*
X246062Y1153740D01*
G01Y1164960D02*
X247933Y1166830D01*
G01X238582Y1164960D02*
X240452Y1166830D01*
G01X246062Y1172440D02*
X247933Y1174310D01*
G01X246062Y1172440D02*
X244192Y1170570D01*
G01X246062Y1157480D02*
X247933Y1155610D01*
G01X242322Y1161220D02*
X244192Y1159350D01*
G01X234842Y1161220D02*
X236712Y1159350D01*
G01X240452Y1166830D02*
X242322Y1168700D01*
G01X238582Y1172440D02*
X240452Y1174310D01*
G01X234842Y1168700D02*
X236712Y1170570D01*
G01D02*
X238582Y1172440D01*
G01X236712Y1159350D02*
X238582Y1157480D01*
G01X244192Y1170570D02*
X242322Y1168700D01*
G01X244192Y1159350D02*
X246062Y1157480D01*
G01X238582Y1161220D02*
X240452Y1159350D01*
G01D02*
X242322Y1157480D01*
G01X246062Y1161220D02*
X247933Y1159350D01*
G01X242322Y1164960D02*
X244192Y1166830D01*
G01X246062Y1168700D02*
X247933Y1170570D01*
G01X244192Y1166830D02*
X246062Y1168700D01*
G01X238582D02*
X240452Y1170570D01*
G01X242322Y1172440D02*
X244192Y1174310D01*
G01X240452Y1170570D02*
X242322Y1172440D01*
G01X234842Y1164960D02*
X236712Y1166830D01*
G01X234842Y1172440D02*
X236712Y1174310D01*
G01X246062Y1187401D02*
X247933Y1189271D01*
G01X234842Y1187401D02*
X236712Y1189271D01*
G01X242322Y1187401D02*
X240452Y1189271D01*
G01X242322Y1187401D02*
X244192Y1189271D01*
G01X246062Y1179921D02*
X247933Y1181791D01*
G01X242322Y1179921D02*
X240452Y1181791D01*
G01X234842Y1179921D02*
X236712Y1181791D01*
G01X242322Y1179921D02*
X244192Y1181791D01*
G01X240452D02*
X238582Y1179921D01*
G01X236712Y1181791D02*
X238582Y1179921D01*
G01X236712Y1189271D02*
X238582Y1187401D01*
G01X240452Y1189271D02*
X238582Y1187401D01*
G01X244192Y1181791D02*
X246062Y1179921D01*
G01X244192Y1189271D02*
X246062Y1187401D01*
G01Y1176180D02*
X247933Y1178051D01*
G01X242322Y1176180D02*
X240452Y1178051D01*
G01X234842Y1176180D02*
X236712Y1178051D01*
G01X242322Y1176180D02*
X244192Y1178051D01*
G01X240452D02*
X238582Y1176180D01*
G01X236712Y1178051D02*
X238582Y1176180D01*
G01X244192Y1178051D02*
X246062Y1176180D01*
G01Y1183661D02*
X247933Y1185531D01*
G01X242322Y1183661D02*
X240452Y1185531D01*
G01X234842Y1183661D02*
X236712Y1185531D01*
G01X242322Y1183661D02*
X244192Y1185531D01*
G01X240452D02*
X238582Y1183661D01*
G01X236712Y1185531D02*
X238582Y1183661D01*
G01X244192Y1185531D02*
X246062Y1183661D01*
G01X234842Y1194881D02*
X236712Y1196751D01*
G01X238582Y1194881D02*
X240452Y1196751D01*
G01X246062Y1194881D02*
X247933Y1196751D01*
G01X246062Y1202362D02*
X247933Y1204232D01*
G01X246062Y1206102D02*
X244192Y1204232D01*
G01D02*
X246062Y1202362D01*
G01X244192Y1204232D02*
X242322Y1202362D01*
G01Y1206102D02*
X244192Y1204232D01*
G01X238582Y1202362D02*
X236712Y1204232D01*
G01D02*
X234842Y1202362D01*
G01X238582Y1206102D02*
X236712Y1204232D01*
G01D02*
X234842Y1206102D01*
G01X238582Y1202362D02*
X240452Y1204232D01*
G01D02*
X238582Y1206102D01*
G01X242322D02*
X240452Y1204232D01*
G01D02*
X242322Y1202362D01*
G01X246062Y1194881D02*
X244192Y1196751D01*
G01X236712D02*
X238582Y1194881D01*
G01X240452Y1196751D02*
X242322Y1194881D01*
G01X244192Y1196751D02*
X242322Y1194881D01*
G01X246062Y1191141D02*
X247933Y1193011D01*
G01X242322Y1191141D02*
X244192Y1193011D01*
G01X236712D02*
X234842Y1191141D01*
G01X238582D02*
X236712Y1193011D01*
G01X238582Y1191141D02*
X240452Y1193011D01*
G01Y1200491D02*
X238582Y1198621D01*
G01X244192Y1200491D02*
X242322Y1198621D01*
G01X236712Y1200491D02*
X234842Y1198621D01*
G01X247933Y1200491D02*
X246062Y1198621D01*
G01X234842Y1206102D02*
X236712Y1207972D01*
G01D02*
X238582Y1206102D01*
G01X234842Y1209842D02*
X236712Y1207972D01*
G01X246062Y1206102D02*
X247933Y1207972D01*
G01X242322Y1209842D02*
X244192Y1207972D01*
G01D02*
X246062Y1209842D01*
G01Y1206102D02*
X244192Y1207972D01*
G01D02*
X242322Y1206102D01*
G01X246062Y1209842D02*
X247933Y1207972D01*
G01X236712D02*
X238582Y1209842D01*
G01X242322Y1206102D02*
X240452Y1207972D01*
G01D02*
X242322Y1209842D01*
G01X238582D02*
X240452Y1207972D01*
G01D02*
X238582Y1206102D01*
G01X246062D02*
X247933Y1204232D01*
G01X242322Y1209842D02*
X240452Y1211712D01*
G01X242322Y1209842D02*
X244192Y1211712D01*
G01X240452D02*
X238582Y1209842D01*
G01X244192Y1211712D02*
X246062Y1209842D01*
G01X253543Y1123818D02*
X251673Y1125688D01*
G01X253543Y1120078D02*
X255413Y1121948D01*
G01D02*
X257283Y1120078D01*
G01X253543Y1123818D02*
X255413Y1121948D01*
G01D02*
X257283Y1123818D01*
G01X249803Y1120078D02*
X251673Y1121948D01*
G01D02*
X253543Y1120078D01*
G01X249803Y1123818D02*
X251673Y1121948D01*
G01D02*
X253543Y1123818D01*
G01X264763Y1120078D02*
X262893Y1121948D01*
G01D02*
X261023Y1120078D01*
G01X264763Y1123818D02*
X262893Y1121948D01*
G01D02*
X261023Y1123818D01*
G01X257283D02*
X259153Y1125688D01*
G01X257283Y1123818D02*
X255413Y1125688D01*
G01X261023Y1120078D02*
X259153Y1121948D01*
G01D02*
X261023Y1123818D01*
G01X257283Y1120078D02*
X259153Y1121948D01*
G01D02*
X257283Y1123818D01*
G01X249803Y1120078D02*
X247933Y1121948D01*
G01X262893Y1125688D02*
X261023Y1123818D01*
G01X255413Y1125688D02*
X253543Y1123818D01*
G01X251673Y1125688D02*
X249803Y1123818D01*
G01X259153Y1125688D02*
X261023Y1123818D01*
G01X247933Y1125688D02*
X249803Y1123818D01*
G01X247933Y1121948D02*
X249803Y1123818D01*
G01X264763Y1127558D02*
X262893Y1125688D01*
G01D02*
X264763Y1123818D01*
G01X262893Y1125688D02*
X261023Y1127558D01*
G01X257283D02*
X255413Y1125688D01*
G01X253543Y1127558D02*
X251673Y1125688D01*
G01X255413D02*
X253543Y1127558D01*
G01X251673Y1125688D02*
X249803Y1127558D01*
G01X259153Y1125688D02*
X257283Y1127558D01*
G01X261023D02*
X259153Y1125688D01*
G01X249803Y1127558D02*
X247933Y1125688D01*
G01X249803Y1135039D02*
X251673Y1133169D01*
G01X253543Y1135039D02*
X255413Y1133169D01*
G01X261023Y1135039D02*
X259153Y1133169D01*
G01X261023Y1135039D02*
X262893Y1133169D01*
G01X247933D02*
X249803Y1135039D01*
G01X251673Y1133169D02*
X253543Y1135039D01*
G01X255413Y1133169D02*
X257283Y1135039D01*
G01X259153Y1133169D02*
X257283Y1135039D01*
G01X262893Y1133169D02*
X264763Y1135039D01*
G01X253543Y1138779D02*
X255413Y1136909D01*
G01X253543Y1138779D02*
X251673Y1136909D01*
G01X261023Y1138779D02*
X259153Y1136909D01*
G01X261023Y1138779D02*
X262893Y1136909D01*
G01X255413D02*
X257283Y1138779D01*
G01X251673Y1136909D02*
X249803Y1138779D01*
G01X247933Y1136909D02*
X249803Y1138779D01*
G01X259153Y1136909D02*
X257283Y1138779D01*
G01X262893Y1136909D02*
X264763Y1138779D01*
G01X251673Y1129429D02*
X249803Y1131299D01*
G01X255413Y1129429D02*
X253543Y1131299D01*
G01X262893Y1129429D02*
X261023Y1131299D01*
G01X259153Y1129429D02*
X257283Y1131299D01*
G01X253543Y1149999D02*
X251673Y1148129D01*
G01X257283Y1149999D02*
X255413Y1148129D01*
G01X261023Y1149999D02*
X259153Y1148129D01*
G01X264763Y1142519D02*
X262893Y1140649D01*
G01X257283Y1142519D02*
X259153Y1140649D01*
G01X253543Y1142519D02*
X251673Y1140649D01*
G01X257283Y1142519D02*
X255413Y1140649D01*
G01X264763Y1149999D02*
X262893Y1148129D01*
G01X253543Y1157480D02*
X255413Y1155610D01*
G01X261023Y1157480D02*
X262893Y1155610D01*
G01X247933Y1140649D02*
X249803Y1142519D01*
G01X251673Y1140649D02*
X249803Y1142519D01*
G01X255413Y1140649D02*
X253543Y1142519D01*
G01X262893Y1140649D02*
X261023Y1142519D01*
G01X259153Y1140649D02*
X261023Y1142519D01*
G01X259153Y1148129D02*
X257283Y1149999D01*
G01X262893Y1148129D02*
X261023Y1149999D01*
G01X247933Y1148129D02*
X249803Y1149999D01*
G01X251673Y1148129D02*
X249803Y1149999D01*
G01X255413Y1148129D02*
X253543Y1149999D01*
G01X259153Y1155610D02*
X257283Y1157480D01*
G01X249803D02*
X251673Y1155610D01*
G01X261023Y1146259D02*
X262893Y1144389D01*
G01X261023Y1146259D02*
X259153Y1144389D01*
G01X249803Y1146259D02*
X251673Y1144389D01*
G01X253543Y1146259D02*
X255413Y1144389D01*
G01X251673D02*
X253543Y1146259D01*
G01X247933Y1144389D02*
X249803Y1146259D01*
G01X255413Y1144389D02*
X257283Y1146259D01*
G01X262893Y1144389D02*
X264763Y1146259D01*
G01X259153Y1144389D02*
X257283Y1146259D01*
G01X261023Y1153740D02*
X259153Y1151869D01*
G01X261023Y1153740D02*
X262893Y1151869D01*
G01X253543Y1153740D02*
X255413Y1151869D01*
G01X253543Y1153740D02*
X251673Y1151869D01*
G01X259153D02*
X257283Y1153740D01*
G01X262893Y1151869D02*
X264763Y1153740D01*
G01X247933Y1151869D02*
X249803Y1153740D01*
G01X255413Y1151869D02*
X257283Y1153740D01*
G01X251673Y1151869D02*
X249803Y1153740D01*
G01X261023Y1164960D02*
X262893Y1166830D01*
G01X253543Y1172440D02*
X255413Y1174310D01*
G01X253543Y1172440D02*
X251673Y1170570D01*
G01D02*
X249803Y1168700D01*
G01X253543Y1164960D02*
X255413Y1166830D01*
G01X261023Y1172440D02*
X262893Y1174310D01*
G01X261023Y1172440D02*
X259153Y1170570D01*
G01X255413Y1166830D02*
X257283Y1168700D01*
G01X247933Y1166830D02*
X249803Y1168700D01*
G01Y1161220D02*
X251673Y1159350D01*
G01D02*
X253543Y1157480D01*
G01X261023D02*
X259153Y1159350D01*
G01D02*
X257283Y1161220D01*
G01X259153Y1170570D02*
X257283Y1168700D01*
G01X253543Y1161220D02*
X255413Y1159350D01*
G01D02*
X257283Y1157480D01*
G01X247933Y1159350D02*
X249803Y1157480D01*
G01Y1172440D02*
X251673Y1174310D01*
G01X247933Y1170570D02*
X249803Y1172440D01*
G01X257283Y1164960D02*
X259153Y1166830D01*
G01Y1174310D02*
X257283Y1172440D01*
G01X249803Y1164960D02*
X251673Y1166830D01*
G01X253543Y1168700D02*
X255413Y1170570D01*
G01X251673Y1166830D02*
X253543Y1168700D01*
G01X255413Y1170570D02*
X257283Y1172440D01*
G01X261023Y1161220D02*
X262893Y1159350D01*
G01D02*
X264763Y1161220D01*
G01Y1168700D02*
X262893Y1170570D01*
G01D02*
X261023Y1168700D01*
G01X249803Y1187401D02*
X251673Y1189271D01*
G01X257283Y1187401D02*
X255413Y1189271D01*
G01X257283Y1187401D02*
X259153Y1189271D01*
G01X249803Y1179921D02*
X251673Y1181791D01*
G01X257283Y1179921D02*
X255413Y1181791D01*
G01X261023Y1179921D02*
X259153Y1181791D01*
G01X261023Y1179921D02*
X262893Y1181791D01*
G01X247933D02*
X249803Y1179921D01*
G01X251673Y1181791D02*
X253543Y1179921D01*
G01X255413Y1181791D02*
X253543Y1179921D01*
G01X247933Y1189271D02*
X249803Y1187401D01*
G01X251673Y1189271D02*
X253543Y1187401D01*
G01X255413Y1189271D02*
X253543Y1187401D01*
G01X262893Y1189271D02*
X261023Y1187401D01*
G01X259153Y1181791D02*
X257283Y1179921D01*
G01X262893Y1181791D02*
X264763Y1179921D01*
G01X259153Y1189271D02*
X261023Y1187401D01*
G01Y1176180D02*
X262893Y1178051D01*
G01X249803Y1176180D02*
X251673Y1178051D01*
G01X257283Y1176180D02*
X255413Y1178051D01*
G01X257283Y1176180D02*
X259153Y1178051D01*
G01X251673D02*
X253543Y1176180D01*
G01X247933Y1178051D02*
X249803Y1176180D01*
G01X255413Y1178051D02*
X253543Y1176180D01*
G01X259153Y1178051D02*
X261023Y1176180D01*
G01Y1183661D02*
X262893Y1185531D01*
G01X257283Y1183661D02*
X255413Y1185531D01*
G01X253543Y1183661D02*
X251673Y1185531D01*
G01X257283Y1183661D02*
X259153Y1185531D01*
G01X247933D02*
X249803Y1183661D01*
G01X255413Y1185531D02*
X253543Y1183661D01*
G01X251673Y1185531D02*
X249803Y1183661D01*
G01X259153Y1185531D02*
X261023Y1183661D01*
G01X257283Y1206102D02*
X255413Y1204232D01*
G01D02*
X253543Y1206102D01*
G01X255413Y1204232D02*
X253543Y1202362D01*
G01D02*
X251673Y1204232D01*
G01D02*
X249803Y1202362D01*
G01X253543Y1206102D02*
X251673Y1204232D01*
G01D02*
X249803Y1206102D01*
G01X257283Y1202362D02*
X259153Y1204232D01*
G01D02*
X257283Y1206102D01*
G01X261023Y1202362D02*
X259153Y1204232D01*
G01D02*
X261023Y1206102D01*
G01X264763Y1202362D02*
X262893Y1204232D01*
G01D02*
X261023Y1202362D01*
G01X264763Y1206102D02*
X262893Y1204232D01*
G01D02*
X261023Y1206102D01*
G01X249803Y1202362D02*
X247933Y1204232D01*
G01X264763Y1187401D02*
X262893Y1189271D01*
G01X249803Y1194881D02*
X251673Y1196751D01*
G01X257283Y1194881D02*
X255413Y1196751D01*
G01X257283Y1194881D02*
X259153Y1196751D01*
G01X261023Y1194881D02*
X262893Y1196751D01*
G01X247933Y1204232D02*
X249803Y1206102D01*
G01X247933Y1196751D02*
X249803Y1194881D01*
G01X251673Y1196751D02*
X253543Y1194881D01*
G01X255413Y1196751D02*
X253543Y1194881D01*
G01X259153Y1196751D02*
X261023Y1194881D01*
G01X262893Y1196751D02*
X264763Y1194881D01*
G01X249803Y1191141D02*
X251673Y1193011D01*
G01X253543Y1191141D02*
X255413Y1193011D01*
G01X261023Y1191141D02*
X262893Y1193011D01*
G01X257283Y1191141D02*
X259153Y1193011D01*
G01X255413Y1200491D02*
X253543Y1198621D01*
G01X251673Y1200491D02*
X249803Y1198621D01*
G01X262893Y1200491D02*
X261023Y1198621D01*
G01X259153Y1200491D02*
X257283Y1198621D01*
G01X261023Y1206102D02*
X262893Y1207972D01*
G01D02*
X264763Y1206102D01*
G01Y1209842D02*
X262893Y1207972D01*
G01D02*
X261023Y1209842D01*
G01X253543D02*
X255413Y1207972D01*
G01D02*
X257283Y1209842D01*
G01X255413Y1207972D02*
X257283Y1206102D01*
G01D02*
X259153Y1207972D01*
G01D02*
X261023Y1206102D01*
G01X259153Y1207972D02*
X261023Y1209842D01*
G01X257283D02*
X259153Y1207972D01*
G01X255413D02*
X253543Y1206102D01*
G01Y1209842D02*
X251673Y1207972D01*
G01D02*
X249803Y1209842D01*
G01Y1206102D02*
X251673Y1207972D01*
G01X253543Y1206102D02*
X251673Y1207972D01*
G01X249803Y1206102D02*
X247933Y1207972D01*
G01X257283Y1209842D02*
X255413Y1211712D01*
G01X264763Y1209842D02*
X262893Y1211712D01*
G01X261023Y1209842D02*
X259153Y1211712D01*
G01X247933Y1207972D02*
X249803Y1209842D01*
G01X255413Y1211712D02*
X253543Y1209842D01*
G01X262893Y1211712D02*
X261023Y1209842D01*
G01X259153Y1211712D02*
X257283Y1209842D01*
G01X270373Y1118208D02*
X268503Y1120078D01*
G01X272244D02*
X270373Y1121948D01*
G01D02*
X268503Y1123818D01*
G01Y1120078D02*
X270373Y1121948D01*
G01X264763Y1123818D02*
X266633Y1125688D01*
G01X264763Y1123818D02*
X266633Y1121948D01*
G01D02*
X268503Y1120078D01*
G01X266633Y1121948D02*
X264763Y1120078D01*
G01X270373Y1121948D02*
X272244Y1123818D01*
G01X275984Y1120078D02*
X274114Y1118208D01*
G01X275984Y1120078D02*
X274114Y1121948D01*
G01X275984Y1120078D02*
X277854Y1118208D01*
G01X279724Y1123818D02*
X277854Y1121948D01*
G01X266633Y1125688D02*
X268503Y1123818D01*
G01X274114Y1118208D02*
X272244Y1120078D01*
G01X274114Y1121948D02*
X272244Y1120078D01*
G01X277854Y1118208D02*
X279724Y1120078D01*
G01X277854Y1121948D02*
X279724Y1120078D01*
G01X274114Y1125688D02*
X272244Y1123818D01*
G01X270373Y1125688D02*
X272244Y1123818D01*
G01X268503Y1127558D02*
X266633Y1125688D01*
G01D02*
X264763Y1127558D01*
G01X272244D02*
X274114Y1125688D01*
G01X268503Y1127558D02*
X270373Y1125688D01*
G01X268503Y1127558D02*
X270373Y1129429D01*
G01X275984Y1138779D02*
X277854Y1140649D01*
G01X279724Y1135039D02*
X277854Y1136909D01*
G01D02*
X275984Y1138779D01*
G01X277854Y1136909D02*
X279724Y1138779D01*
G01X277854Y1140649D02*
X279724Y1138779D01*
G01Y1131299D02*
X277854Y1129429D01*
G01X279724Y1131299D02*
X277854Y1133169D01*
G01X279724Y1127558D02*
X277854Y1125688D01*
G01Y1129429D02*
X279724Y1127558D01*
G01X268503Y1138779D02*
X270373Y1136909D01*
G01X264763Y1135039D02*
X266633Y1133169D01*
G01X268503Y1135039D02*
X270373Y1133169D01*
G01Y1136909D02*
X272244Y1135039D01*
G01X266633Y1133169D02*
X268503Y1135039D01*
G01X270373Y1133169D02*
X272244Y1135039D01*
G01X270373Y1129429D02*
X268503Y1131299D01*
G01X277854Y1133169D02*
X279724Y1135039D01*
G01X277854Y1125688D02*
X279724Y1123818D01*
G01X264763Y1138779D02*
X266633Y1136909D01*
G01Y1129429D02*
X264763Y1131299D01*
G01X272244D02*
X274114Y1129429D01*
G01X272244Y1138779D02*
X274114Y1140649D01*
G01X272244Y1138779D02*
X274114Y1136909D01*
G01X275984Y1142519D02*
X277854Y1140649D01*
G01X275984Y1142519D02*
X277854Y1144389D01*
G01D02*
X279724Y1142519D01*
G01Y1146259D02*
X277854Y1144389D01*
G01D02*
X275984Y1146259D01*
G01D02*
X277854Y1148129D01*
G01D02*
X279724Y1146259D01*
G01X277854Y1148129D02*
X279724Y1149999D01*
G01X272244Y1157480D02*
X270373Y1155610D01*
G01D02*
X272244Y1153740D01*
G01X270373Y1155610D02*
X268503Y1157480D01*
G01Y1153740D02*
X270373Y1151869D01*
G01D02*
X272244Y1153740D01*
G01X268503Y1149999D02*
X270373Y1151869D01*
G01D02*
X272244Y1149999D01*
G01X268503D02*
X270373Y1148129D01*
G01D02*
X272244Y1149999D01*
G01X270373Y1148129D02*
X268503Y1146259D01*
G01X272244Y1149999D02*
X274114Y1151869D01*
G01D02*
X272244Y1153740D01*
G01X275984Y1149999D02*
X274114Y1151869D01*
G01X275984Y1149999D02*
X274114Y1148129D01*
G01D02*
X272244Y1149999D01*
G01X274114Y1148129D02*
X275984Y1146259D01*
G01Y1153740D02*
X274114Y1155610D01*
G01D02*
X272244Y1157480D01*
G01X274114Y1155610D02*
X272244Y1153740D01*
G01X274114Y1151869D02*
X275984Y1153740D01*
G01X264763Y1149999D02*
X266633Y1148129D01*
G01X268503Y1142519D02*
X270373Y1140649D01*
G01X264763Y1142519D02*
X266633Y1140649D01*
G01X268503Y1142519D02*
X270373Y1144389D01*
G01Y1155610D02*
X268503Y1153740D01*
G01X277854Y1140649D02*
X279724Y1142519D01*
G01Y1149999D02*
Y1150000D01*
X277854Y1151870D01*
G01X275984Y1149999D02*
X277854Y1148129D01*
G01X266633Y1140649D02*
X268503Y1142519D01*
G01X266633Y1148129D02*
X268503Y1149999D01*
G01X270373Y1144389D02*
X268503Y1146259D01*
G01X277854Y1151870D02*
X275984Y1153740D01*
G01X264763Y1157480D02*
X266633Y1155610D01*
G01X277854D02*
X275984Y1157480D01*
G01X264763Y1146259D02*
X266633Y1144389D01*
G01X264763Y1153740D02*
X266633Y1151869D01*
G01X274114Y1144389D02*
X272244Y1146259D01*
G01X274114Y1140649D02*
X272244Y1142519D01*
G01D02*
X274114Y1144389D01*
G01X272244Y1172440D02*
X270373Y1174310D01*
G01X268503Y1172440D02*
X270373Y1174310D01*
G01X272244Y1172440D02*
X274114Y1174310D01*
G01X272244Y1168700D02*
X274114Y1166830D01*
G01X272244Y1168700D02*
X274114Y1170570D01*
G01X272244Y1157480D02*
X274114Y1159350D01*
G01Y1166830D02*
X272244Y1164960D01*
G01X274114Y1159350D02*
X272244Y1161220D01*
G01X274114Y1170570D02*
X272244Y1172440D01*
G01X264763D02*
X266633Y1174310D01*
G01X277854Y1159350D02*
X275984Y1161220D01*
G01X277854Y1170570D02*
X275984Y1168700D01*
G01X277854Y1166830D02*
X275984Y1168700D01*
G01Y1172440D02*
X277854Y1170570D01*
G01X275984Y1164960D02*
X277854Y1166830D01*
G01X275984Y1172440D02*
X277854Y1174310D01*
G01X268503Y1161220D02*
X270373Y1159350D01*
G01X264763Y1161220D02*
X266633Y1159350D01*
G01D02*
X268503Y1161220D01*
G01Y1168700D02*
X270373Y1170570D01*
G01X264763Y1168700D02*
X266633Y1170570D01*
G01D02*
X268503Y1168700D01*
G01Y1164960D02*
X270373Y1166830D01*
G01X268503Y1164960D02*
X266633Y1166830D01*
G01D02*
X264763Y1164960D01*
G01X270373Y1174310D02*
X268503Y1176180D01*
G01X279724Y1183661D02*
X277854Y1181791D01*
G01D02*
X275984Y1183661D01*
G01X277854Y1181791D02*
X275984Y1179921D01*
G01Y1183661D02*
X277854Y1185531D01*
G01D02*
X279724Y1183661D01*
G01X277854Y1185531D02*
X275984Y1187401D01*
G01Y1191141D02*
X277854Y1189271D01*
G01D02*
X279724Y1191141D01*
G01X277854Y1189271D02*
X275984Y1187401D01*
G01Y1176180D02*
X277854Y1178051D01*
G01X268503Y1176180D02*
X270373Y1178051D01*
G01X275984Y1183661D02*
X274114Y1181791D01*
G01X277854Y1178051D02*
X275984Y1179921D01*
G01X279724Y1176180D02*
X277854Y1178051D01*
G01X279724Y1187401D02*
X277854Y1189271D01*
G01X279724Y1187401D02*
X277854Y1185531D01*
G01X268503Y1187401D02*
X270373Y1189271D01*
G01X264763Y1187401D02*
X266633Y1189271D01*
G01D02*
X268503Y1187401D01*
G01X266633Y1189271D02*
X268503Y1191141D01*
G01X270373Y1185531D02*
X268503Y1183661D01*
G01D02*
X266633Y1181791D01*
G01D02*
X264763Y1179921D01*
G01X274114Y1174310D02*
X275984Y1176180D01*
G01X264763D02*
X266633Y1178051D01*
G01X264763Y1183661D02*
X266633Y1185531D01*
G01X268503Y1179921D02*
X270373Y1181791D01*
G01X272244Y1187401D02*
X274114Y1189271D01*
G01X272244Y1183661D02*
X274114Y1185531D01*
G01X272244Y1176180D02*
X274114Y1178051D01*
G01X279724Y1191141D02*
X277854Y1193011D01*
G01D02*
X279724Y1194881D01*
G01X277854Y1193011D02*
X275984Y1191141D01*
G01X268503Y1206102D02*
X270373Y1204232D01*
G01D02*
X272244Y1206102D01*
G01Y1202362D02*
X270373Y1204232D01*
G01D02*
X268503Y1202362D01*
G01X264763Y1206102D02*
X266633Y1204232D01*
G01D02*
X268503Y1206102D01*
G01Y1202362D02*
X266633Y1204232D01*
G01D02*
X264763Y1202362D01*
G01X268503D02*
X270373Y1200491D01*
G01D02*
X272244Y1202362D01*
G01Y1194881D02*
X270373Y1193011D01*
G01D02*
X268503Y1194881D01*
G01X270373Y1193011D02*
X268503Y1191141D01*
G01X274114Y1196751D02*
X272244Y1194881D01*
G01X268503D02*
X270354Y1196732D01*
X270393D01*
G01D02*
X272244Y1194881D01*
G01X270393Y1196732D02*
X268503Y1198621D01*
G01X270373Y1200491D02*
X268503Y1198621D01*
G01Y1194881D02*
X266633Y1196751D01*
G01D02*
X268503Y1198621D01*
G01X266633Y1196751D02*
X264763Y1194881D01*
G01X272244Y1206102D02*
X274114Y1204232D01*
G01D02*
X272244Y1202362D01*
G01X264763Y1191141D02*
X266633Y1193011D01*
G01Y1200491D02*
X264763Y1198621D01*
G01X272244D02*
X274114Y1200491D01*
G01X272244Y1191141D02*
X274114Y1193011D01*
G01X275984Y1202362D02*
X277854Y1204232D01*
G01X275984Y1194881D02*
X277854Y1196751D01*
G01X275984Y1198621D02*
X277854Y1200491D01*
G01X268503Y1206102D02*
X270373Y1207972D01*
G01D02*
X272244Y1206102D01*
G01Y1209842D02*
X270373Y1207972D01*
G01D02*
X268503Y1209842D01*
G01X275984D02*
X274114Y1207972D01*
G01D02*
X272244Y1206102D01*
G01Y1209842D02*
X274114Y1207972D01*
G01X264763Y1206102D02*
X266633Y1207972D01*
G01D02*
X268503Y1206102D01*
G01Y1209842D02*
X266633Y1207972D01*
G01D02*
X264763Y1209842D01*
G01X272244D02*
X270373Y1211712D01*
G01X268503Y1209842D02*
X266633Y1211712D01*
G01X279724Y1209842D02*
X277854Y1211712D01*
G01X270373D02*
X268503Y1209842D01*
G01X266633Y1211712D02*
X264763Y1209842D01*
G01X277854Y1211712D02*
X275984Y1209842D01*
G01X294684Y1120078D02*
X294685D01*
G01X279724Y1138779D02*
X281594Y1136909D01*
G01Y1140649D02*
X279724Y1138779D01*
G01X281594Y1136909D02*
X279724Y1135039D01*
G01X290944Y1142519D02*
X292814Y1144389D01*
G01D02*
X290944Y1146259D01*
G01X294685Y1149999D02*
X296555Y1151869D01*
G01X294685Y1142519D02*
X296555Y1144389D01*
G01X294685Y1149999D02*
X292814Y1151869D01*
G01X287204Y1153740D02*
X289074Y1155610D01*
G01D02*
X287204Y1157480D01*
G01X290944D02*
X289074Y1155610D01*
G01X292814Y1151869D02*
X290944Y1153740D01*
G01X292814Y1151869D02*
X290944Y1149999D01*
G01X289074Y1155610D02*
X290944Y1153740D01*
G01D02*
X289074Y1151869D01*
G01D02*
X287204Y1153740D01*
G01X289074Y1151869D02*
X290944Y1149999D01*
G01X292814Y1144389D02*
X294685Y1142519D01*
G01X283464Y1153740D02*
X281594Y1151869D01*
G01D02*
X279724Y1149999D01*
G01X281594Y1151869D02*
X279724Y1153740D01*
G01Y1149999D02*
X281594Y1148129D01*
G01X283464Y1153740D02*
X285334Y1151869D01*
G01X290944Y1146259D02*
X289074Y1144389D01*
G01X279724Y1142519D02*
X281594Y1140649D01*
G01Y1148129D02*
X279724Y1146259D01*
G01X281594Y1155610D02*
X279724Y1157480D01*
G01X285334Y1151869D02*
X287204Y1153740D01*
G01X289074Y1144389D02*
X290944Y1142519D01*
G01X285334Y1155610D02*
X283464Y1157480D01*
G01X281594Y1174310D02*
X279724Y1172440D01*
G01D02*
X281594Y1170570D01*
G01X279724Y1168700D02*
X281594Y1166830D01*
G01Y1170570D02*
X279724Y1168700D01*
G01X294685Y1157480D02*
X296555Y1159350D01*
G01X287204Y1161220D02*
X289074Y1159350D01*
G01D02*
X290944Y1157480D01*
G01X289074Y1159350D02*
X290944Y1161220D01*
G01D02*
X292814Y1159350D01*
G01D02*
X294685Y1157480D01*
G01X290944D02*
X292814Y1159350D01*
G01X289074D02*
X287204Y1157480D01*
G01X289074Y1174310D02*
X287204Y1172440D01*
G01X290944D02*
X289074Y1174310D01*
G01X294685Y1164960D02*
X296555Y1166830D01*
G01X294685Y1172440D02*
X292814Y1174310D01*
G01X294685Y1172440D02*
X296555Y1174310D01*
G01X290944Y1172440D02*
X292814Y1174310D01*
G01X287204Y1168700D02*
X289074Y1170570D01*
G01D02*
X287204Y1172440D01*
G01X290944Y1168700D02*
X289074Y1170570D01*
G01X287204Y1164960D02*
X289074Y1166830D01*
G01D02*
X287204Y1168700D01*
G01X290944D02*
X289074Y1166830D01*
G01Y1170570D02*
X290944Y1172440D01*
G01X289074Y1166830D02*
X290944Y1164960D01*
G01D02*
X292814Y1166830D01*
G01D02*
X294685Y1164960D01*
G01X292814Y1166830D02*
X290944Y1168700D01*
G01X281594Y1159350D02*
X279724Y1161220D01*
G01X281594Y1166830D02*
X279724Y1164960D01*
G01X285334Y1159350D02*
X283464Y1161220D01*
G01X285334Y1166830D02*
X283464Y1164960D01*
G01X285334Y1170570D02*
X283464Y1168700D01*
G01X285334Y1174310D02*
X283464Y1172440D01*
G01X279724Y1176180D02*
X281594Y1178051D01*
G01D02*
X283464Y1179921D01*
G01X281594Y1178051D02*
X283464Y1176180D01*
G01D02*
X281594Y1174310D01*
G01X283464Y1183661D02*
X281594Y1185531D01*
G01D02*
X279724Y1187401D01*
G01X281594Y1185531D02*
X279724Y1183661D01*
G01Y1187401D02*
X281594Y1189271D01*
G01D02*
X279724Y1191141D01*
G01X281594Y1189271D02*
X283464Y1191141D01*
G01Y1183661D02*
X285334Y1181791D01*
G01X281594Y1174310D02*
X279724Y1176180D01*
G01X287204D02*
X289074Y1178051D01*
G01D02*
X290944Y1176180D01*
G01X289074Y1178051D02*
X290944Y1179921D01*
G01X292814Y1189271D02*
X294685Y1187401D01*
G01X292814Y1189271D02*
X290944Y1187401D01*
G01X294685Y1179921D02*
X292814Y1181791D01*
G01D02*
X290944Y1179921D01*
G01X292814Y1181791D02*
X290944Y1183661D01*
G01X287204Y1176180D02*
X289074Y1174310D01*
G01X290944Y1187401D02*
X289074Y1185531D01*
G01Y1174310D02*
X290944Y1176180D01*
G01X292814Y1174310D02*
X290944Y1176180D01*
G01X283464Y1187401D02*
X285334Y1185531D01*
G01X289074D02*
X290944Y1183661D01*
G01X285334Y1181791D02*
X283464Y1179921D01*
G01X294685D02*
X298425D01*
G01X294685Y1187401D02*
X298425D01*
G01X279724Y1179921D02*
X281594Y1181791D01*
G01X283464Y1191141D02*
X285334Y1193011D01*
G01X283464Y1191141D02*
X281594Y1193011D01*
G01D02*
X279724Y1191141D01*
G01X281594Y1193011D02*
X279724Y1194881D01*
G01D02*
X281594Y1196751D01*
G01X279724Y1202362D02*
X281594Y1204232D01*
G01Y1196751D02*
X279724Y1198621D01*
G01X281594Y1204232D02*
X279724Y1206102D01*
G01X283464Y1194881D02*
X285334Y1196751D01*
G01X287204Y1198621D02*
X285334Y1200491D01*
G01X302165Y1138779D02*
X300295Y1140649D01*
G01X309645Y1138779D02*
X307775Y1140649D01*
G01D02*
X305905Y1138779D01*
G01X309645D02*
X311515Y1136909D01*
G01D02*
X313385Y1138779D01*
G01X305905D02*
X304035Y1140649D01*
G01D02*
X302165Y1138779D01*
G01Y1153740D02*
X300295Y1155610D01*
G01X302165Y1153740D02*
X304035Y1155610D01*
G01X298425Y1149999D02*
X300295Y1148129D01*
G01X307775Y1140649D02*
X309645Y1142519D01*
G01X302165Y1146259D02*
X300295Y1144389D01*
G01X309645Y1146259D02*
X307775Y1148129D01*
G01D02*
X309645Y1149999D01*
G01X307775Y1148129D02*
X305905Y1146259D01*
G01X302165D02*
X304035Y1148129D01*
G01X302165Y1153740D02*
X300295Y1151869D01*
G01X305905Y1153740D02*
X307775Y1155610D01*
G01D02*
X309645Y1157480D01*
G01X307775Y1155610D02*
X309645Y1153740D01*
G01X313385D02*
X311515Y1151869D01*
G01D02*
X309645Y1149999D01*
G01X311515Y1151869D02*
X309645Y1153740D01*
G01X313385Y1146259D02*
X311515Y1144389D01*
G01D02*
X309645Y1142519D01*
G01X311515Y1144389D02*
X309645Y1146259D01*
G01X296555Y1151869D02*
X298425Y1149999D01*
G01X304035Y1155610D02*
X305905Y1153740D01*
G01X304035Y1148129D02*
X305905Y1146259D01*
G01X300295Y1155610D02*
X298425Y1157480D01*
G01X300295Y1151869D02*
X298425Y1149999D01*
G01X300295Y1148129D02*
X302165Y1146259D01*
G01X300295Y1144389D02*
X298425Y1142519D01*
G01X296555Y1144389D02*
X298425Y1142519D01*
G01X300295Y1140649D02*
X298425Y1142519D01*
G01Y1157480D02*
X300295Y1159350D01*
G01X309645Y1157480D02*
X311515Y1159350D01*
G01D02*
X313385Y1161220D01*
G01X311515Y1159350D02*
X309645Y1161220D01*
G01X305905Y1168700D02*
X307775Y1170570D01*
G01D02*
X309645Y1172440D01*
G01X307775Y1170570D02*
X309645Y1168700D01*
G01X313385D02*
X311515Y1166830D01*
G01D02*
X309645Y1168700D01*
G01X311515Y1166830D02*
X309645Y1164960D01*
G01X305905Y1168700D02*
X304035Y1170570D01*
G01X302165Y1168700D02*
X300295Y1170570D01*
G01X298425Y1164960D02*
X300295Y1166830D01*
G01X311515Y1174310D02*
X309645Y1172440D01*
G01X305905Y1161220D02*
X307775Y1159350D01*
G01X296555D02*
X298425Y1157480D01*
G01X300295Y1159350D02*
X302165Y1161220D01*
G01X296555Y1166830D02*
X298425Y1164960D01*
G01X304035Y1170570D02*
X302165Y1168700D01*
G01X300295Y1170570D02*
X298425Y1172440D01*
G01X300295Y1166830D02*
X302165Y1168700D01*
G01X300295Y1174310D02*
X298425Y1172440D01*
G01X296555Y1174310D02*
X298425Y1172440D01*
G01X309645Y1183661D02*
X307775Y1185531D01*
G01D02*
X305905Y1183661D01*
G01X307775Y1185531D02*
X309645Y1187401D01*
G01X302165Y1176180D02*
X300295Y1174310D01*
G01X313385Y1176180D02*
X311515Y1174310D01*
G01X309645Y1176180D02*
X311515Y1174310D01*
G01X305905Y1176180D02*
X307775Y1178051D01*
G01D02*
X309645Y1176180D01*
G01X307775Y1178051D02*
X309645Y1179921D01*
G01D02*
X311515Y1181791D01*
G01D02*
X313385Y1183661D01*
G01X311515Y1181791D02*
X309645Y1183661D01*
G01X298425Y1187401D02*
X300295Y1185531D01*
G01X298425Y1179921D02*
X300295Y1181791D01*
G01X298425Y1179921D02*
X300295Y1178051D01*
G01X305905Y1183661D02*
X304035Y1185531D01*
G01X305905Y1176180D02*
X304035Y1178051D01*
G01X302165Y1191141D02*
X300295Y1189271D01*
G01X311515D02*
X309645Y1187401D01*
G01X300295Y1185531D02*
X302165Y1183661D01*
G01X300295Y1181791D02*
X302165Y1183661D01*
G01X300295Y1178051D02*
X302165Y1176180D01*
G01X304035Y1185531D02*
X302165Y1183661D01*
G01X304035Y1178051D02*
X302165Y1176180D01*
G01X300295Y1189271D02*
X298425Y1187401D01*
G01X302165Y1191141D02*
X304035Y1193011D01*
G01X311515Y1196751D02*
X309645Y1194881D01*
G01X305905Y1191141D02*
X307775Y1193011D01*
G01D02*
X309645Y1194881D01*
G01X307775Y1193011D02*
X309645Y1191141D01*
G01D02*
X311515Y1189271D01*
G01D02*
X313385Y1191141D01*
G01X304035Y1193011D02*
X305905Y1191141D01*
G01X317125Y1138779D02*
X315255Y1136909D01*
G01X318996Y1140649D02*
X317125Y1138779D01*
G01X315255Y1136909D02*
X313385Y1138779D01*
G01X318996Y1136909D02*
X317125Y1138779D01*
G01X324606Y1142519D02*
X326476Y1140649D01*
G01X324606Y1142519D02*
X322736Y1140649D01*
G01X320866Y1142519D02*
X318996Y1140649D01*
G01X317125Y1146259D02*
X318996Y1144389D01*
G01X317125Y1146259D02*
X315255Y1144389D01*
G01X324606Y1149999D02*
X326476Y1148129D01*
G01X324606Y1149999D02*
X322736Y1148129D01*
G01X324606Y1157480D02*
X326476Y1155610D01*
G01X324606Y1157480D02*
X322736Y1155610D01*
G01X320866Y1157480D02*
X318996Y1155610D01*
G01X313385Y1153740D02*
X315255Y1151869D01*
G01X317125Y1153740D02*
X318996Y1151869D01*
G01X320866Y1149999D02*
X318996Y1148129D01*
G01X322736Y1155610D02*
X320866Y1157480D01*
G01X318996Y1144389D02*
X320866Y1142519D01*
G01X315255Y1144389D02*
X313385Y1146259D01*
G01X318996Y1155610D02*
X317125Y1153740D01*
G01X315255Y1151869D02*
X317125Y1153740D01*
G01X318996Y1151869D02*
X320866Y1149999D01*
G01X318996Y1148129D02*
X317125Y1146259D01*
G01X322736Y1140649D02*
X320866Y1142519D01*
G01X322736Y1148129D02*
X320866Y1149999D01*
G01X317125Y1161220D02*
X315255Y1159350D01*
G01X317125Y1161220D02*
X318996Y1159350D01*
G01X313385Y1168700D02*
X315255Y1166830D01*
G01X324606Y1172440D02*
X326476Y1170570D01*
G01X320866Y1172440D02*
X322736Y1170570D01*
G01X320866Y1172440D02*
X318996Y1170570D01*
G01X324606Y1164960D02*
X326476Y1166830D01*
G01X320866Y1164960D02*
X322736Y1166830D01*
G01X320866Y1164960D02*
X318996Y1166830D01*
G01X322736Y1170570D02*
X324606Y1172440D01*
G01X322736Y1166830D02*
X324606Y1164960D01*
G01X315255Y1159350D02*
X313385Y1161220D01*
G01X318996Y1159350D02*
X320866Y1157480D01*
G01X315255Y1166830D02*
X317125Y1168700D01*
G01X318996Y1170570D02*
X317125Y1168700D01*
G01X318996Y1166830D02*
X317125Y1168700D01*
G01X318996Y1174310D02*
X320866Y1172440D01*
G01Y1179921D02*
X318996Y1178051D01*
G01X313385Y1176180D02*
X315255Y1174310D01*
G01X317125Y1176180D02*
X318996Y1174310D01*
G01X324606Y1179921D02*
X322736Y1178051D01*
G01X324606Y1179921D02*
X326476Y1178051D01*
G01X324606Y1187401D02*
X322736Y1185531D01*
G01X324606Y1187401D02*
X326476Y1185531D01*
G01X317125Y1183661D02*
X318996Y1185531D01*
G01X320866Y1179921D02*
X318996Y1181791D01*
G01X313385Y1183661D02*
X315255Y1181791D01*
G01X317125Y1191141D02*
X315255Y1189271D01*
G01X317125Y1191141D02*
X318996Y1189271D01*
G01X315255Y1181791D02*
X317125Y1183661D01*
G01X315255Y1189271D02*
X313385Y1191141D01*
G01X318996Y1189271D02*
X320866Y1187401D01*
G01X318996Y1185531D02*
X320866Y1187401D01*
G01X318996Y1181791D02*
X317125Y1183661D01*
G01X318996Y1178051D02*
X317125Y1176180D01*
G01X315255Y1174310D02*
X317125Y1176180D01*
G01X322736Y1178051D02*
X320866Y1179921D01*
G01X322736Y1185531D02*
X320866Y1187401D01*
G01X324606Y1194881D02*
X326416Y1193071D01*
Y1193011D01*
G01X324606Y1194881D02*
X322736Y1193011D01*
G01X317125Y1191141D02*
X318996Y1193011D01*
G01X322736D02*
X320866Y1194881D01*
G01X318996Y1193011D02*
X320866Y1194881D01*
G01X602165Y1086417D02*
X600295Y1084547D01*
G01X605905Y1078936D02*
X604035Y1077066D01*
G01X602165Y1078936D02*
X604035Y1080806D01*
G01X605905Y1086417D02*
X604035Y1084547D01*
G01X605905Y1093897D02*
X604035Y1092027D01*
G01X602165Y1093897D02*
X600295Y1092027D01*
G01X605905Y1105117D02*
X604035Y1103247D01*
G01X600295D02*
X602165Y1105117D01*
G01Y1097637D02*
X600295Y1095767D01*
G01X605905Y1097637D02*
X604035Y1095767D01*
G01X602165Y1112598D02*
X600295Y1110728D01*
G01X602165Y1120078D02*
X600295Y1118208D01*
G01X605905Y1112598D02*
X604035Y1110728D01*
G01X605905Y1120078D02*
X604035Y1118208D01*
G01X602165Y1127558D02*
X600295Y1125688D01*
G01X602165Y1135039D02*
X600295Y1133169D01*
G01X605905Y1127558D02*
X604035Y1125688D01*
G01X605905Y1135039D02*
X604035Y1133169D01*
G01X605905Y1142519D02*
X604035Y1140649D01*
G01X602165Y1142519D02*
X600295Y1140649D01*
G01X602165Y1146259D02*
X600295Y1144389D01*
G01X602165Y1153740D02*
X600295Y1151870D01*
G01X605905Y1146259D02*
X604035Y1144389D01*
G01X605905Y1153740D02*
X604035Y1151870D01*
G01X602165Y1161220D02*
X600295Y1159350D01*
G01X604036Y1166830D02*
X602165Y1168700D01*
G01X605905Y1161220D02*
X604035Y1159350D01*
G01X605905Y1176180D02*
X604034Y1174310D01*
G01D02*
X602165Y1176179D01*
Y1176180D01*
G01X613386Y1075196D02*
X611516Y1073326D01*
G01X620866Y1075196D02*
X618996Y1073326D01*
G01X605905Y1075196D02*
X607775Y1077066D01*
G01X620866Y1090157D02*
X618996Y1088287D01*
G01X613386Y1078936D02*
X611516Y1077066D01*
G01X617126Y1082677D02*
X615256Y1080807D01*
G01X609646Y1082677D02*
X607776Y1080807D01*
G01X617126Y1086417D02*
X615256Y1084547D01*
G01X609646Y1086417D02*
X607776Y1084547D01*
G01X617126Y1090157D02*
X615256Y1088287D01*
G01X613386Y1090157D02*
X611516Y1088287D01*
G01X609646Y1090157D02*
X607776Y1088287D01*
G01X620866Y1078936D02*
X618996Y1077066D01*
G01X613386Y1093897D02*
X611516Y1092027D01*
G01X620866Y1093897D02*
X618996Y1092027D01*
G01X613386Y1108858D02*
X611516Y1106988D01*
G01X609646Y1108858D02*
X607776Y1106988D01*
G01X613386Y1097637D02*
X611516Y1095767D01*
G01X617126Y1101377D02*
X615256Y1099507D01*
G01X609646Y1101377D02*
X607776Y1099507D01*
G01X617126Y1105117D02*
X615256Y1103247D01*
G01X609646Y1105117D02*
X607776Y1103247D01*
G01X617126Y1108858D02*
X615256Y1106988D01*
G01X620866Y1097637D02*
X618996Y1095767D01*
G01X620866Y1108858D02*
X618996Y1106988D01*
G01X617126Y1112598D02*
X615256Y1110728D01*
G01X617126Y1116338D02*
X615256Y1114468D01*
G01X613386Y1116338D02*
X611516Y1114468D01*
G01X609646Y1116338D02*
X607776Y1114468D01*
G01X617126Y1120078D02*
X615256Y1118208D01*
G01X617126Y1123818D02*
X615256Y1121948D01*
G01X613386Y1123818D02*
X611516Y1121948D01*
G01X609646Y1123818D02*
X607776Y1121948D01*
G01X620866Y1116338D02*
X618996Y1114468D01*
G01X617126Y1127558D02*
X615256Y1125688D01*
G01X617126Y1131299D02*
X615256Y1129429D01*
G01X613386Y1131299D02*
X611516Y1129429D01*
G01X609646Y1131299D02*
X607776Y1129429D01*
G01X609646Y1138779D02*
X607776Y1136909D01*
G01X620866Y1123818D02*
X618996Y1125688D01*
G01X620866Y1131299D02*
X618996Y1129429D01*
G01X617126Y1135039D02*
X618996Y1133169D01*
G01X620866Y1142519D02*
X618996Y1140649D01*
G01X609646Y1142519D02*
X607776Y1140649D01*
G01X613386Y1142519D02*
X611516Y1140649D01*
G01X617126Y1142519D02*
X615256Y1140649D01*
G01X620866Y1146259D02*
X618996Y1144389D01*
G01X620866Y1149999D02*
X618996Y1148129D01*
G01X620866Y1153740D02*
X618996Y1151870D01*
G01X620866Y1157480D02*
X618996Y1155610D01*
G01X609646Y1146259D02*
X607776Y1144389D01*
G01X617126Y1149999D02*
X615256Y1151869D01*
G01X613386Y1149999D02*
X611516Y1151869D01*
G01X609646Y1149999D02*
X607776Y1148129D01*
G01X609646Y1153740D02*
X607776Y1151870D01*
G01X617126Y1157480D02*
X615256Y1155610D01*
G01X613386Y1157480D02*
X611516Y1155610D01*
G01X609646Y1157480D02*
X607776Y1155610D01*
G01X609646Y1172440D02*
X611516Y1174310D01*
G01X607775D02*
X609646Y1172440D01*
G01X611516Y1174310D02*
X613386Y1172440D01*
G01X617126D02*
X618996Y1174310D01*
G01X613386Y1172440D02*
X615256Y1174310D01*
G01X609646Y1161220D02*
X607776Y1159350D01*
G01X611516Y1166830D02*
X613386Y1164960D01*
G01D02*
X615256Y1166830D01*
G01D02*
X617126Y1164960D01*
G01X607775Y1166830D02*
X609646Y1164960D01*
G01Y1168700D02*
X611516Y1170570D01*
G01X605905Y1168700D02*
X607775Y1170570D01*
G01X620866Y1161220D02*
X618996Y1159350D01*
G01X615256Y1174310D02*
X617126Y1172440D01*
G01X620866Y1179921D02*
X618996Y1178051D01*
G01D02*
X620866Y1176180D01*
G01X618996Y1178051D02*
X617126Y1179921D01*
G01X605905Y1176180D02*
X607775Y1174310D01*
G01X605905Y1176180D02*
X607775Y1178051D01*
G01D02*
X609646Y1176180D01*
G01X607775Y1178051D02*
X609646Y1179921D01*
G01X607775Y1174310D02*
X609646Y1176180D01*
G01X611516Y1174310D02*
X609646Y1176180D01*
G01X618996Y1174310D02*
X620866Y1176180D01*
G01Y1172440D02*
X618996Y1174310D01*
G01X628346Y1075196D02*
X626476Y1073326D01*
G01X628346Y1075196D02*
X626476Y1077066D01*
G01X624606Y1086417D02*
X622736Y1084547D01*
G01X628346Y1090157D02*
X626476Y1088287D01*
G01Y1077066D02*
X628346Y1078936D01*
G01X626476Y1088287D02*
X624606Y1086417D01*
G01X626476Y1092027D02*
X628346Y1090157D01*
G01X624606Y1082677D02*
X622736Y1080807D01*
G01X624606Y1090157D02*
X622736Y1088287D01*
G01X628346Y1097637D02*
X626476Y1099507D01*
G01X628346Y1093897D02*
X626476Y1092027D01*
G01X628346Y1093897D02*
X626476Y1095767D01*
G01X632086Y1105117D02*
X630216Y1103247D01*
G01Y1099507D02*
X628346Y1097637D01*
G01X624606Y1101377D02*
X622736Y1099507D01*
G01X624606Y1105117D02*
X622736Y1103247D01*
G01X628346Y1108858D02*
X626476Y1106988D01*
G01X624606Y1108858D02*
X622736Y1106988D01*
G01X626476Y1095767D02*
X628346Y1097637D01*
G01X633957Y1110728D02*
X635827Y1112598D01*
G01X632086D02*
X630216Y1110728D01*
G01X628346Y1112598D02*
X626476Y1110728D01*
G01X624606Y1116338D02*
X622736Y1114468D01*
G01X632086Y1120078D02*
X630216Y1118208D01*
G01X628346Y1120078D02*
X626476Y1118208D01*
G01X624606Y1123818D02*
X626476Y1121948D01*
G01X635827Y1116338D02*
X633957Y1114468D01*
G01X635827Y1120078D02*
X633957Y1118208D01*
G01X635827Y1123818D02*
X633957Y1121948D01*
G01X635827Y1135039D02*
X637697Y1133169D01*
G01X635827Y1135039D02*
X633957Y1133169D01*
G01X635827Y1127558D02*
X633957Y1125688D01*
G01X635827Y1131299D02*
X633957Y1129429D01*
G01X635827Y1138779D02*
X633957Y1136909D01*
G01X632086Y1127558D02*
X630216Y1129428D01*
G01X628346Y1127558D02*
X626476Y1129428D01*
G01X624606Y1131299D02*
X622736Y1129429D01*
G01X632086Y1135039D02*
X630216Y1136909D01*
G01X628346Y1135039D02*
X626476Y1136909D01*
G01X624606Y1142519D02*
X622736Y1140649D01*
G01X628346Y1142519D02*
X626476Y1140649D01*
G01X632086Y1142519D02*
X630216Y1140649D01*
G01X635827Y1142519D02*
X633957Y1140649D01*
G01X632086Y1146259D02*
X630216Y1144389D01*
G01X628346Y1146259D02*
X626476Y1144389D01*
G01X632086Y1149999D02*
X630216Y1148129D01*
G01X632086Y1157480D02*
X630216Y1155610D01*
G01X632086Y1153740D02*
X630216Y1151870D01*
G01X635827Y1146259D02*
X633957Y1144389D01*
G01X635827Y1149999D02*
X633957Y1148129D01*
G01X635827Y1153740D02*
X633957Y1151870D01*
G01X637697Y1166830D02*
X635827Y1168700D01*
G01D02*
X637697Y1170570D01*
G01X632086Y1168700D02*
X630216Y1166830D01*
G01X632086Y1172440D02*
X630216Y1170570D01*
G01X632086Y1168700D02*
X633957Y1170570D01*
G01X635827Y1157480D02*
X637697Y1159350D01*
G01X622736Y1174310D02*
X620866Y1172440D01*
G01X630216Y1174310D02*
X632086Y1172440D01*
G01X622736Y1166830D02*
X620866Y1164960D01*
G01X622736Y1170570D02*
X620866Y1168700D01*
G01X632086Y1161220D02*
X630216Y1159350D01*
G01Y1166830D02*
X632086Y1164960D01*
G01X630216Y1170570D02*
X632086Y1168700D01*
G01X633957Y1170570D02*
X635827Y1168700D01*
G01X633957Y1174310D02*
X635827Y1172440D01*
G01Y1161220D02*
X633957Y1159350D01*
G01X635827Y1164960D02*
X633957Y1166830D01*
G01X620866Y1176180D02*
X622736Y1174310D01*
G01Y1178050D02*
X620866Y1176180D01*
G01X635827Y1183661D02*
X637697Y1181791D01*
G01Y1185531D02*
X635827Y1183661D01*
G01X632086Y1176180D02*
X630216Y1178051D01*
G01D02*
X632086Y1179921D01*
G01X630216Y1178051D02*
X628346Y1179921D01*
G01X632086D02*
X630216Y1181791D01*
G01D02*
X628346Y1179921D01*
G01X630216Y1181791D02*
X632086Y1183661D01*
G01D02*
X633957Y1185531D01*
G01D02*
X635827Y1183661D01*
G01X632086Y1176180D02*
X630216Y1174310D01*
G01X635827Y1176180D02*
X633957Y1174310D01*
G01X635827Y1179921D02*
X633957Y1181791D01*
G01X635827Y1179921D02*
X633957Y1178051D01*
G01D02*
X635827Y1176180D01*
G01X637697Y1110728D02*
X639567Y1112598D01*
G01Y1116338D02*
X637697Y1114468D01*
G01X650787Y1120078D02*
X648917Y1118208D01*
G01X647047Y1120078D02*
X645177Y1118208D01*
G01X643307Y1120078D02*
X641437Y1118208D01*
G01X639567Y1120078D02*
X637697Y1118208D01*
G01X650787Y1123818D02*
X648917Y1121948D01*
G01X647047Y1123818D02*
X645177Y1121948D01*
G01X643307Y1123818D02*
X641437Y1121948D01*
G01X639567Y1123818D02*
X637697Y1121948D01*
G01X654527Y1120078D02*
X652657Y1118208D01*
G01X654527Y1123818D02*
X652657Y1121948D01*
G01X654527Y1127558D02*
X652657Y1125688D01*
G01X654527Y1135039D02*
X652657Y1133169D01*
G01X654527Y1131299D02*
X652657Y1129429D01*
G01X654527Y1135039D02*
X652657Y1136909D01*
G01X643307Y1135039D02*
X641437Y1133169D01*
G01X637697D02*
X639567Y1135039D01*
G01X647047Y1138779D02*
X645177Y1136909D01*
G01X639567Y1138779D02*
X637697Y1136909D01*
G01X652657Y1133169D02*
X654527Y1131299D01*
G01X652657Y1129429D02*
X654527Y1127558D01*
G01X652657Y1136909D02*
X654527Y1138779D01*
G01X650787Y1127558D02*
X648917Y1125688D01*
G01X647047Y1127558D02*
X645177Y1125688D01*
G01X643307Y1127558D02*
X641437Y1125688D01*
G01X639567Y1127558D02*
X637697Y1125688D01*
G01X647047Y1131299D02*
X645177Y1129429D01*
G01X643307Y1131299D02*
X641437Y1129429D01*
G01X639567Y1131299D02*
X637697Y1129429D01*
G01X647047Y1135039D02*
X645177Y1133169D01*
G01X650787Y1138779D02*
X648917Y1136909D01*
G01X639567Y1142519D02*
X637697Y1140649D01*
G01X643307Y1142519D02*
X641437Y1140649D01*
G01X647047Y1142519D02*
X645177Y1140649D01*
G01X654527Y1146259D02*
X652657Y1144389D01*
G01X650787Y1149999D02*
X648917Y1148129D01*
G01X654527Y1153740D02*
X652657Y1151869D01*
G01X639567Y1157480D02*
X637697Y1155610D01*
G01X639567Y1153740D02*
X637697Y1151870D01*
G01X647047Y1146259D02*
X645177Y1144389D01*
G01X639567Y1146259D02*
X637697Y1144389D01*
G01X639567Y1149999D02*
X637697Y1148129D01*
G01X645177Y1151870D02*
X647047Y1153740D01*
G01D02*
X648917Y1155610D01*
G01D02*
X650787Y1157480D01*
G01X652657Y1151869D02*
X650787Y1149999D01*
G01Y1153740D02*
X648917Y1151869D01*
G01X654527Y1157480D02*
X652657Y1155610D01*
G01D02*
X650787Y1153740D01*
G01Y1146259D02*
X648917Y1144389D01*
G01X654527Y1149999D02*
X652657Y1148129D01*
G01D02*
X650787Y1146259D01*
G01X643307D02*
X641437Y1144389D01*
G01X643307Y1153740D02*
X641437Y1151870D01*
G01X647047Y1149999D02*
X645177Y1148129D01*
G01X639567Y1168700D02*
X637697Y1166830D01*
G01X639567Y1172440D02*
X637697Y1170570D01*
G01X647047Y1168700D02*
X645177Y1170570D01*
G01X639567Y1172440D02*
X637697Y1174310D01*
G01X647047Y1168700D02*
X648917Y1166830D01*
G01X654527Y1168700D02*
X652657Y1170570D01*
G01X650787Y1172440D02*
X648917Y1174310D01*
G01X637697Y1166830D02*
X639567Y1164960D01*
G01X637697Y1170570D02*
X639567Y1168700D01*
G01X654527Y1161220D02*
X652657Y1159350D01*
G01X645177Y1170570D02*
X643307Y1172440D01*
G01X647047Y1161220D02*
X645177Y1159350D01*
G01X637697D02*
X639567Y1161220D01*
G01X648917Y1166830D02*
X650787Y1164960D01*
G01X652657Y1159350D02*
X650787Y1157480D01*
G01X652657Y1170570D02*
X650787Y1172440D01*
G01X643307Y1164960D02*
X639567Y1168700D01*
G01X650787D02*
X648917Y1170570D01*
G01X654527Y1164960D02*
X652657Y1166830D01*
G01D02*
X650787Y1168700D01*
G01Y1161220D02*
X648917Y1159350D01*
G01X641437Y1170570D02*
X643307Y1168700D01*
G01X647047Y1172440D02*
X645177Y1174310D01*
G01Y1166830D02*
X647047Y1164960D01*
G01X643307Y1161220D02*
X641437Y1159350D01*
G01X652657Y1189271D02*
X650787Y1187401D01*
G01D02*
X652657Y1185531D01*
G01X647047Y1187401D02*
X645177Y1185531D01*
G01D02*
X647047Y1183661D01*
G01X643307Y1191141D02*
X641437Y1189271D01*
G01D02*
X639567Y1191141D01*
G01X641437Y1189271D02*
X639567Y1187401D01*
G01X641437Y1189271D02*
X643307Y1187401D01*
G01X645177Y1185531D02*
X643307Y1187401D01*
G01X639567Y1179921D02*
X637697Y1181791D01*
G01X639567Y1183661D02*
X637697Y1185531D01*
G01X639567Y1187401D02*
X637697Y1189271D01*
G01X639567Y1179921D02*
X637697Y1178051D01*
G01X647047Y1176180D02*
X645177Y1178051D01*
G01X647047Y1183661D02*
X648917Y1181791D01*
G01X650787Y1179921D02*
X652657Y1178051D01*
G01X637697Y1189271D02*
X639567Y1191141D01*
G01X637697Y1181791D02*
X639567Y1183661D01*
G01X637697Y1185531D02*
X639567Y1187401D01*
G01X637697Y1178051D02*
X639567Y1176180D01*
G01X637697Y1174310D02*
X639567Y1176180D01*
G01X645177Y1178051D02*
X643307Y1179921D01*
G01X648917Y1181791D02*
X650787Y1179921D01*
G01X648917Y1174310D02*
X647047Y1176180D01*
G01X652657Y1185531D02*
X654527Y1183661D01*
G01X652657Y1178051D02*
X654527Y1176180D01*
G01Y1172440D02*
X652657Y1174310D01*
G01X650787Y1176180D02*
X648917Y1178051D01*
G01X652657Y1174310D02*
X650787Y1176180D01*
G01X654527Y1179921D02*
X652657Y1181791D01*
G01X648917Y1185531D02*
X650787Y1183661D01*
G01X652657Y1181791D02*
X650787Y1183661D01*
G01X643307Y1176180D02*
X641437Y1178051D01*
G01X647047Y1179921D02*
X645177Y1181791D01*
G01X654527Y1198621D02*
X652657Y1200491D01*
G01X654527Y1191141D02*
X652657Y1189271D01*
G01X654527Y1191141D02*
X652657Y1193011D01*
G01X654527Y1194881D02*
X652657Y1196751D01*
G01Y1189271D02*
X654527Y1187401D01*
G01X650787Y1206102D02*
X648917Y1204232D01*
G01D02*
X650787Y1202362D01*
G01X647047Y1206102D02*
X648917Y1204232D01*
G01D02*
X647047Y1202362D01*
G01X643307D02*
X645177Y1204232D01*
G01D02*
X647047Y1202362D01*
G01Y1206102D02*
X645177Y1204232D01*
G01D02*
X643307Y1206102D01*
G01X639567Y1202362D02*
X641437Y1204232D01*
G01D02*
X643307Y1202362D01*
G01Y1206102D02*
X641437Y1204232D01*
G01D02*
X639567Y1206102D01*
G01X643307Y1191141D02*
X645177Y1193011D01*
G01D02*
X647047Y1191141D01*
G01Y1194881D02*
X645177Y1193011D01*
G01D02*
X643307Y1194881D01*
G01X639567Y1191141D02*
X641437Y1193011D01*
G01D02*
X643307Y1191141D01*
G01Y1194881D02*
X641437Y1193011D01*
G01D02*
X639567Y1194881D01*
G01X647047D02*
X645177Y1196751D01*
G01D02*
X643307Y1198621D01*
G01X647047D02*
X645177Y1196751D01*
G01X643307Y1194881D02*
X645177Y1196751D01*
G01X647047Y1198621D02*
X648917Y1196751D01*
G01Y1200491D02*
X647047Y1198621D01*
G01X643307Y1194881D02*
X641437Y1196751D01*
G01D02*
X639567Y1194881D01*
G01Y1198621D02*
X641437Y1196751D01*
G01D02*
X643307Y1198621D01*
G01D02*
X645177Y1200491D01*
G01D02*
X647047Y1198621D01*
G01Y1202362D02*
X645177Y1200491D01*
G01D02*
X643307Y1202362D01*
G01X639567Y1198621D02*
X641437Y1200491D01*
G01D02*
X643307Y1198621D01*
G01Y1202362D02*
X641437Y1200491D01*
G01D02*
X639567Y1202362D01*
G01X650787D02*
X652657Y1204232D01*
G01D02*
X654527Y1202362D01*
G01Y1206102D02*
X652657Y1204232D01*
G01X650787Y1206102D02*
X652657Y1204232D01*
G01X639567Y1191141D02*
X637697Y1193011D01*
G01D02*
X639567Y1194881D01*
G01X652657Y1193011D02*
X654527Y1194881D01*
G01X652657Y1196751D02*
X654527Y1198621D01*
G01X650787Y1191141D02*
X648917Y1193011D01*
G01X641437Y1219192D02*
X639567Y1217322D01*
G01X650787Y1213582D02*
X648917Y1211712D01*
G01D02*
X647047Y1209842D01*
G01X650787D02*
X648917Y1211712D01*
G01X647047Y1209842D02*
X645177Y1211712D01*
G01D02*
X643307Y1213582D01*
G01X645177Y1211712D02*
X643307Y1209842D01*
G01Y1213582D02*
X641437Y1211712D01*
G01D02*
X639567Y1213582D01*
G01X643307Y1209842D02*
X641437Y1211712D01*
G01D02*
X639567Y1209842D01*
G01X650787D02*
X648917Y1207972D01*
G01D02*
X650787Y1206102D01*
G01X647047Y1209842D02*
X648917Y1207972D01*
G01D02*
X647047Y1206102D01*
G01D02*
X645177Y1207972D01*
G01D02*
X647047Y1209842D01*
G01X643307Y1206102D02*
X645177Y1207972D01*
G01D02*
X643307Y1209842D01*
G01X639567Y1206102D02*
X641437Y1207972D01*
G01D02*
X639567Y1209842D01*
G01X643307Y1206102D02*
X641437Y1207972D01*
G01D02*
X643307Y1209842D01*
G01X654527Y1206102D02*
X652657Y1207972D01*
G01D02*
X650787Y1206102D01*
G01Y1209842D02*
X652657Y1207972D01*
G01D02*
X654527Y1209842D01*
G01X650787Y1213582D02*
X652657Y1211712D01*
G01D02*
X654527Y1209842D01*
G01X650787D02*
X652657Y1211712D01*
G01X648917Y1219192D02*
X650787Y1217322D01*
G01X663878Y1125688D02*
X662008Y1123818D01*
G01X667618Y1125688D02*
X665748Y1123818D01*
G01X663878Y1118208D02*
X665748Y1120078D01*
G01X662008D02*
X660138Y1118208D01*
G01X662008Y1120078D02*
X663878Y1121948D01*
G01D02*
X665748Y1120078D01*
G01Y1123818D02*
X663878Y1121948D01*
G01D02*
X662008Y1123818D01*
G01D02*
X660138Y1121948D01*
G01X665748Y1123818D02*
X663878Y1125688D01*
G01X665748Y1123818D02*
X667618Y1121948D01*
G01D02*
X665748Y1120078D01*
G01X669488Y1123818D02*
X667618Y1121948D01*
G01X669488Y1120078D02*
X671358Y1118208D01*
G01Y1121948D02*
X669488Y1120078D01*
G01X667618Y1121948D02*
X669488Y1120078D01*
G01X665748D02*
X667618Y1118208D01*
G01X658268Y1120078D02*
X656398Y1118208D01*
G01X658268Y1123818D02*
X656398Y1121948D01*
G01X667618Y1118208D02*
X669488Y1120078D01*
G01X665748Y1127558D02*
X667618Y1125688D01*
G01X665748Y1127558D02*
X663878Y1125688D01*
G01D02*
X662008Y1127558D01*
G01D02*
X660138Y1125688D01*
G01X669488Y1123818D02*
X667618Y1125688D01*
G01X671358Y1121948D02*
X669488Y1123818D01*
G01X667618Y1125688D02*
X669488Y1127558D01*
G01D02*
X671358Y1125688D01*
G01X669488Y1135039D02*
X671358Y1133169D01*
G01X665748Y1135039D02*
X663878Y1133169D01*
G01X662008Y1135039D02*
X660138Y1133169D01*
G01X658268Y1135039D02*
X656398Y1133169D01*
G01X665748Y1135039D02*
X667618Y1133169D01*
G01X658268Y1127558D02*
X656398Y1125688D01*
G01X663878Y1133169D02*
X662008Y1135039D01*
G01X660138Y1133169D02*
X658268Y1135039D01*
G01X656398Y1133169D02*
X654527Y1135039D01*
G01X667618Y1133169D02*
X669488Y1135039D01*
G01X663878Y1129429D02*
X665748Y1131299D01*
G01X656398Y1129429D02*
X658268Y1131299D01*
G01X660138Y1129429D02*
X662008Y1131299D01*
G01X667618Y1129429D02*
X669488Y1131299D01*
G01X667618Y1136909D02*
X669488Y1138779D01*
G01X660138Y1136909D02*
X658268Y1138779D01*
G01X663878Y1136909D02*
X662008Y1138779D01*
G01X665748D02*
X667618Y1136909D01*
G01X662008Y1138779D02*
X660138Y1136909D01*
G01X665748Y1138779D02*
X663878Y1136909D01*
G01X658268Y1138779D02*
X656398Y1136909D01*
G01X669488Y1138779D02*
X671358Y1136909D01*
G01X658268Y1142519D02*
X656398Y1140649D01*
G01X662008Y1142519D02*
X660138Y1140649D01*
G01X665748Y1142519D02*
X663878Y1140649D01*
G01X669488Y1142519D02*
X671358Y1140649D01*
G01X669488Y1142519D02*
X667618Y1140649D01*
G01X662008Y1149999D02*
X660138Y1148129D01*
G01X654527Y1146259D02*
X656398Y1148129D01*
G01X669488Y1149999D02*
X671358Y1148129D01*
G01X669488Y1149999D02*
X667618Y1148129D01*
G01X665748Y1149999D02*
X663878Y1148129D01*
G01X660138Y1140649D02*
X658268Y1142519D01*
G01X663878Y1140649D02*
X662008Y1142519D01*
G01X667618Y1140649D02*
X665748Y1142519D01*
G01X667618Y1148129D02*
X665748Y1149999D01*
G01X660138Y1148129D02*
X658268Y1149999D01*
G01X656398Y1148129D02*
X658268Y1149999D01*
G01X663878Y1148129D02*
X662008Y1149999D01*
G01X654527Y1153740D02*
X656398Y1155610D01*
G01D02*
X658268Y1157480D01*
G01X665748D02*
X663878Y1155610D01*
G01X669488Y1157480D02*
X667618Y1155610D01*
G01X662008Y1157480D02*
X660138Y1155610D01*
G01X658268Y1146259D02*
X656398Y1144389D01*
G01X669488Y1146259D02*
X671358Y1144389D01*
G01X665748Y1146259D02*
X667618Y1144389D01*
G01X665748Y1146259D02*
X663878Y1144389D01*
G01X662008Y1146259D02*
X660138Y1144389D01*
G01X667618D02*
X669488Y1146259D01*
G01X663878Y1144389D02*
X662008Y1146259D01*
G01X660138Y1144389D02*
X658268Y1146259D01*
G01X656398Y1151870D02*
X658268Y1153740D01*
G01X660138Y1151870D02*
X662008Y1153740D01*
G01X663878Y1151870D02*
X665748Y1153740D01*
G01X667618Y1151870D02*
X669488Y1153740D01*
G01X658268Y1172440D02*
X656398Y1174310D01*
G01X665748Y1164960D02*
X663878Y1166830D01*
G01X662008Y1168700D02*
X660138Y1170570D01*
G01X658268Y1164960D02*
X656398Y1166830D01*
G01X665748Y1172440D02*
X663878Y1174310D01*
G01X669488Y1168700D02*
X671358Y1166830D01*
G01X669488Y1168700D02*
X667618Y1170570D01*
G01X662008Y1161220D02*
X660138Y1159350D01*
G01X669488Y1161220D02*
X667618Y1159350D01*
G01X663878Y1166830D02*
X662008Y1168700D01*
G01X660138Y1159350D02*
X658268Y1157480D01*
G01X656398Y1166830D02*
X654527Y1168700D01*
G01X660138Y1170570D02*
X658268Y1172440D01*
G01X667618Y1159350D02*
X665748Y1157480D01*
G01X667618Y1170570D02*
X665748Y1172440D01*
G01X658268Y1161220D02*
X656398Y1159350D01*
G01D02*
X654527Y1157480D01*
G01X669488D02*
X671358Y1159350D01*
G01X665748Y1161220D02*
X663878Y1159350D01*
G01D02*
X662008Y1157480D01*
G01X665748Y1168700D02*
X663878Y1170570D01*
G01X669488Y1164960D02*
X667618Y1166830D01*
G01D02*
X665748Y1168700D01*
G01X654527Y1172440D02*
X656398Y1170570D01*
G01X658268Y1168700D02*
X660138Y1166830D01*
G01D02*
X662008Y1164960D01*
G01X656398Y1170570D02*
X658268Y1168700D01*
G01X662008Y1172440D02*
X660138Y1174310D01*
G01X669488Y1179921D02*
X671358Y1181791D01*
G01X665748Y1179921D02*
X663878Y1181791D01*
G01X662008Y1179921D02*
X660138Y1181791D01*
G01X658268Y1179921D02*
X656398Y1181791D01*
G01X665748Y1179921D02*
X667618Y1181791D01*
G01X669488Y1187401D02*
X671358Y1189271D01*
G01X665748Y1187401D02*
X663878Y1189271D01*
G01X662008Y1187401D02*
X660138Y1189271D01*
G01X658268Y1187401D02*
X656398Y1189271D01*
G01X665748Y1187401D02*
X667618Y1189271D01*
G01X663878Y1181791D02*
X662008Y1179921D01*
G01X660138Y1181791D02*
X658268Y1179921D01*
G01X656398Y1181791D02*
X654527Y1183661D01*
G01X663878Y1189271D02*
X662008Y1187401D01*
G01X660138Y1189271D02*
X658268Y1187401D01*
G01X656398Y1189271D02*
X654527Y1187401D01*
G01X667618Y1181791D02*
X669488Y1179921D01*
G01X667618Y1189271D02*
X669488Y1187401D01*
G01X656398Y1174310D02*
X654527Y1176180D01*
G01X669488Y1172440D02*
X667618Y1174310D01*
G01X669488Y1172440D02*
X671358Y1170570D01*
G01X658268Y1176180D02*
X656398Y1178051D01*
G01X669488Y1176180D02*
X671358Y1178051D01*
G01X665748Y1176180D02*
X667618Y1178051D01*
G01X665748Y1176180D02*
X663878Y1178051D01*
G01X662008Y1176180D02*
X660138Y1178051D01*
G01X667618D02*
X669488Y1176180D01*
G01X663878Y1178051D02*
X662008Y1176180D01*
G01X660138Y1178051D02*
X658268Y1176180D01*
G01Y1183661D02*
X656398Y1185531D01*
G01X658268Y1183661D02*
X660138Y1185531D01*
G01X669488Y1183661D02*
X671358Y1185531D01*
G01X665748Y1183661D02*
X667618Y1185531D01*
G01X665748Y1183661D02*
X663878Y1185531D01*
G01X667618D02*
X669488Y1183661D01*
G01X660138Y1185531D02*
X662008Y1183661D01*
G01X663878Y1185531D02*
X662008Y1183661D01*
G01X665748Y1194881D02*
X663878Y1196751D01*
G01X662008Y1194881D02*
X660138Y1196751D01*
G01X654527Y1194881D02*
X656398Y1196751D01*
G01X669488Y1194881D02*
X671358Y1196751D01*
G01X669488Y1194881D02*
X667618Y1196751D01*
G01X662008Y1206102D02*
X663878Y1204232D01*
G01D02*
X665748Y1206102D01*
G01X662008Y1202362D02*
X663878Y1204232D01*
G01X662008Y1202362D02*
X660138Y1204232D01*
G01D02*
X662008Y1206102D01*
G01X660138Y1204232D02*
X658268Y1206102D01*
G01X671358Y1204232D02*
X669488Y1202362D01*
G01Y1206102D02*
X667618Y1204232D01*
G01D02*
X669488Y1202362D01*
G01X665748Y1206102D02*
X667618Y1204232D01*
G01D02*
X665748Y1202362D01*
G01X663878Y1204232D02*
X665748Y1202362D01*
G01X658268Y1206102D02*
X656398Y1204232D01*
G01D02*
X654527Y1206102D01*
G01X656398Y1204232D02*
X654527Y1202362D01*
G01X658268D02*
X656398Y1204232D01*
G01X660138D02*
X658268Y1202362D01*
G01X663878Y1196751D02*
X662008Y1194881D01*
G01X660138Y1196751D02*
X658268Y1194881D01*
G01X656398Y1196751D02*
X658268Y1194881D01*
G01X667618Y1196751D02*
X665748Y1194881D01*
G01X660138Y1200491D02*
X662008Y1198621D01*
G01X663878Y1200491D02*
X665748Y1198621D01*
G01X656398Y1200491D02*
X658268Y1198621D01*
G01X667618Y1200491D02*
X669488Y1198621D01*
G01X658268Y1191141D02*
X656398Y1193011D01*
G01X665748Y1191141D02*
X663878Y1193011D01*
G01X662008Y1191141D02*
X660138Y1193011D01*
G01X669488Y1191141D02*
X671358Y1193011D01*
G01X669488Y1191141D02*
X667618Y1193011D01*
G01X663878D02*
X662008Y1191141D01*
G01X660138Y1193011D02*
X658268Y1191141D01*
G01X667618Y1193011D02*
X665748Y1191141D01*
G01X667618Y1211712D02*
X665748Y1209842D01*
G01X671358Y1204232D02*
X669488Y1206102D01*
G01X671358Y1207972D02*
X669488Y1206102D01*
G01X671358Y1207972D02*
X669488Y1209842D01*
G01X665748Y1206102D02*
X667618Y1207972D01*
G01D02*
X669488Y1209842D01*
G01Y1206102D02*
X667618Y1207972D01*
G01X654527Y1209842D02*
X656398Y1207972D01*
G01X665748Y1209842D02*
X667618Y1207972D01*
G01X665748Y1209842D02*
X663878Y1207972D01*
G01D02*
X665748Y1206102D01*
G01X662008D02*
X663878Y1207972D01*
G01X662008Y1209842D02*
X663878Y1207972D01*
G01X662008Y1209842D02*
X660138Y1207972D01*
G01D02*
X658268Y1209842D01*
G01X662008Y1206102D02*
X660138Y1207972D01*
G01D02*
X658268Y1206102D01*
G01X656398Y1207972D02*
X658268Y1206102D01*
G01X654527D02*
X656398Y1207972D01*
G01D02*
X658268Y1209842D01*
G01X680709Y1123818D02*
X682579Y1125688D01*
G01X686319D02*
X684449Y1123818D01*
G01X686319Y1118208D02*
X684449Y1120078D01*
G01D02*
X686319Y1121948D01*
G01X684449Y1123818D02*
X686319Y1121948D01*
G01X680709Y1123818D02*
X682579Y1121948D01*
G01D02*
X684449Y1123818D01*
G01Y1120078D02*
X682579Y1121948D01*
G01X673228Y1116338D02*
X675098Y1118208D01*
G01D02*
X673228Y1120078D01*
G01X675098Y1118208D02*
X676968Y1120078D01*
G01X671358Y1114468D02*
X673228Y1116338D01*
G01Y1120078D02*
X675098Y1121948D01*
G01D02*
X676968Y1120078D01*
G01Y1123818D02*
X675098Y1121948D01*
G01D02*
X673228Y1123818D01*
G01X676968D02*
X678838Y1125688D01*
G01X680709Y1120078D02*
X682579Y1121948D01*
G01X676968Y1120078D02*
X678838Y1121948D01*
G01D02*
X680709Y1120078D01*
G01Y1123818D02*
X678838Y1121948D01*
G01D02*
X676968Y1123818D01*
G01X673228Y1116338D02*
X671358Y1118208D01*
G01X673228Y1120078D02*
X671358Y1121948D01*
G01X684449Y1120078D02*
X682579Y1118208D01*
G01X676968Y1120078D02*
X678838Y1118208D01*
G01X682579Y1125688D02*
X684449Y1123818D01*
G01X678838Y1125688D02*
X680709Y1123818D01*
G01X675098Y1125688D02*
X673228Y1123818D01*
G01X671358Y1121948D02*
X673228Y1123818D01*
G01X671358Y1125688D02*
X673228Y1123818D01*
G01X671358Y1118208D02*
X673228Y1120078D01*
G01X682579Y1118208D02*
X680709Y1120078D01*
G01X678838Y1118208D02*
X680709Y1120078D01*
G01X682579Y1125688D02*
X680709Y1127558D01*
G01X673228D02*
X675098Y1125688D01*
G01X680709Y1127558D02*
X678838Y1125688D01*
G01X682579D02*
X684449Y1127558D01*
G01D02*
X686319Y1125688D01*
G01X675098D02*
X676968Y1127558D01*
G01X678838Y1125688D02*
X676968Y1127558D01*
G01X673228D02*
X671358Y1125688D01*
G01X684449Y1135039D02*
Y1134645D01*
X686417Y1132677D01*
G01X680709Y1135039D02*
X682579Y1133169D01*
G01X676968Y1135039D02*
X678838Y1133169D01*
G01X676968Y1135039D02*
X675098Y1133169D01*
G01X682579D02*
X684449Y1135039D01*
G01X678838Y1133169D02*
X680709Y1135039D01*
G01X675098Y1133169D02*
X673228Y1135039D01*
G01X671358Y1133169D02*
X673228Y1135039D01*
G01X682579Y1129429D02*
X684449Y1131299D01*
G01X678838Y1129429D02*
X680709Y1131299D01*
G01X671358Y1129429D02*
X673228Y1131299D01*
G01X675098Y1129429D02*
X676968Y1131299D01*
G01X671358Y1136909D02*
X673228Y1138779D01*
G01X675098Y1136909D02*
X673228Y1138779D01*
G01X678838Y1136909D02*
X676968Y1138779D01*
G01X682579Y1136909D02*
X684449Y1138779D01*
G01X676968D02*
X675098Y1136909D01*
G01X680709Y1138779D02*
X678838Y1136909D01*
G01X680709Y1138779D02*
X682579Y1136909D01*
G01X684449Y1138779D02*
X686319Y1136909D01*
G01X680709Y1157480D02*
X678838Y1155610D01*
G01X673228Y1157480D02*
X671358Y1155610D01*
G01X673228Y1142519D02*
X675098Y1140649D01*
G01X684449Y1142519D02*
X686319Y1140649D01*
G01X684449Y1142519D02*
X682579Y1140649D01*
G01X680709Y1142519D02*
X678838Y1140649D01*
G01X682579D02*
X680709Y1142519D01*
G01X671358Y1140649D02*
X673228Y1142519D01*
G01X675098Y1140649D02*
X676968Y1142519D01*
G01X678838Y1140649D02*
X676968Y1142519D01*
G01X684449Y1149999D02*
X682579Y1148129D01*
G01X676968Y1149999D02*
X678838Y1148129D01*
G01X684449Y1149999D02*
X686319Y1148129D01*
G01X673228Y1149999D02*
X675098Y1148129D01*
G01X682579D02*
X680709Y1149999D01*
G01X678838Y1148129D02*
X680709Y1149999D01*
G01X675098Y1148129D02*
X676968Y1149999D01*
G01X671358Y1148129D02*
X673228Y1149999D01*
G01X676968Y1157480D02*
X675098Y1155610D01*
G01X684449Y1157480D02*
X682579Y1155610D01*
G01X684449Y1146259D02*
X686319Y1144389D01*
G01X684449Y1146259D02*
X682579Y1144389D01*
G01X676968Y1146259D02*
X678838Y1144389D01*
G01X673228Y1146259D02*
X675098Y1144389D01*
G01X682579D02*
X680709Y1146259D01*
G01X671358Y1144389D02*
X673228Y1146259D01*
G01X678838Y1144389D02*
X680709Y1146259D01*
G01X675098Y1144389D02*
X676968Y1146259D01*
G01X682579Y1151870D02*
X684449Y1153740D01*
G01X671358Y1151870D02*
X673228Y1153740D01*
G01X675098Y1151870D02*
X676968Y1153740D01*
G01X678839Y1151870D02*
X680709Y1153740D01*
G01X684449Y1168700D02*
X686319Y1166830D01*
G01X680709Y1172440D02*
X678838Y1174310D01*
G01X680709Y1172440D02*
X682579Y1170570D01*
G01D02*
X684449Y1168700D01*
G01Y1161220D02*
X682579Y1159350D01*
G01D02*
X680709Y1157480D01*
G01X673228Y1172440D02*
X671358Y1174310D01*
G01X676968Y1168700D02*
X675098Y1170570D01*
G01X680709Y1164960D02*
X678839Y1166830D01*
G01X675098Y1170570D02*
X673228Y1172440D01*
G01X678839Y1166830D02*
X676969Y1168700D01*
X676968D01*
G01X671358Y1166830D02*
X673228Y1164960D01*
G01X676968Y1161220D02*
X675098Y1159350D01*
G01D02*
X673228Y1157480D01*
G01X671358Y1159350D02*
X673228Y1161220D01*
G01X680709D02*
X678838Y1159350D01*
G01D02*
X676968Y1157480D01*
G01X684449D02*
X686319Y1159350D01*
G01X684449Y1172440D02*
X682579Y1174310D01*
G01X684449Y1172440D02*
X686319Y1170570D01*
G01X676968Y1164960D02*
X675098Y1166830D01*
G01X671358Y1170570D02*
X673228Y1168700D01*
G01X675098Y1166830D02*
X673228Y1168700D01*
G01X676968Y1172440D02*
X675098Y1174310D01*
G01X680709Y1168700D02*
X682579Y1166830D01*
G01X680709Y1168700D02*
X678838Y1170570D01*
G01X682579Y1166830D02*
X684449Y1164960D01*
G01X678838Y1170570D02*
X676968Y1172440D01*
G01Y1179921D02*
X675098Y1181791D01*
G01X684449Y1179921D02*
X686319Y1181791D01*
G01X684449Y1179921D02*
X682579Y1181791D01*
G01X680709Y1179921D02*
X678838Y1181791D01*
G01X684449Y1187401D02*
X686319Y1189271D01*
G01X680709Y1187401D02*
X678838Y1189271D01*
G01X676968Y1187401D02*
X675098Y1189271D01*
G01X680709Y1187401D02*
X682579Y1189271D01*
G01X675098Y1181791D02*
X673228Y1179921D01*
G01X671358Y1181791D02*
X673228Y1179921D01*
G01X678838Y1189271D02*
X676968Y1187401D01*
G01X675098Y1189271D02*
X673228Y1187401D01*
G01X671358Y1189271D02*
X673228Y1187401D01*
G01X682579Y1181791D02*
X680709Y1179921D01*
G01X682579Y1189271D02*
X684449Y1187401D01*
G01X678838Y1181791D02*
X676968Y1179921D01*
G01X684449Y1176180D02*
X686319Y1178051D01*
G01X684449Y1176180D02*
X682579Y1178051D01*
G01X676968Y1176180D02*
X678838Y1178051D01*
G01X676968Y1176180D02*
X675098Y1178051D01*
G01X682579D02*
X680709Y1176180D01*
G01X678838Y1178051D02*
X680709Y1176180D01*
G01X675098Y1178051D02*
X673228Y1176180D01*
G01X671358Y1178051D02*
X673228Y1176180D01*
G01X684449Y1183661D02*
X686319Y1185531D01*
G01X684449Y1183661D02*
X682579Y1185531D01*
G01X676968Y1183661D02*
X675098Y1185531D01*
G01X676968Y1183661D02*
X678838Y1185531D01*
G01X682579D02*
X680709Y1183661D01*
G01X675098Y1185531D02*
X673228Y1183661D01*
G01X671358Y1185531D02*
X673228Y1183661D01*
G01X678838Y1185531D02*
X680709Y1183661D01*
G01X684449Y1194881D02*
X686319Y1196751D01*
G01X680709Y1194881D02*
X682579Y1196751D01*
G01X676968Y1194881D02*
X678838Y1196751D01*
G01X676968Y1194881D02*
X675098Y1196751D01*
G01X684449Y1202362D02*
X686319Y1204232D01*
G01X684449Y1206102D02*
X682579Y1204232D01*
G01D02*
X684449Y1202362D01*
G01X680709Y1206102D02*
X682579Y1204232D01*
G01D02*
X680709Y1202362D01*
G01D02*
X678838Y1204232D01*
G01D02*
X676968Y1202362D01*
G01X680709Y1206102D02*
X678838Y1204232D01*
G01D02*
X676968Y1206102D01*
G01Y1202362D02*
X675098Y1204232D01*
G01D02*
X673228Y1202362D01*
G01X676968Y1206102D02*
X675098Y1204232D01*
G01D02*
X673228Y1206102D01*
G01X684449D02*
X686319Y1204232D01*
G01X673228Y1202362D02*
X671358Y1204232D01*
G01D02*
X673228Y1206102D01*
G01X682579Y1196751D02*
X684449Y1194881D01*
G01X678838Y1196751D02*
X680709Y1194881D01*
G01X675098Y1196751D02*
X673228Y1194881D01*
G01X671358Y1196751D02*
X673228Y1194881D01*
G01X682579Y1200491D02*
X684449Y1198621D01*
G01X678838Y1200491D02*
X680709Y1198621D01*
G01X671358Y1200491D02*
X673228Y1198621D01*
G01X675098Y1200491D02*
X676968Y1198621D01*
G01X684449Y1191141D02*
X686319Y1193011D01*
G01X680709Y1191141D02*
X682579Y1193011D01*
G01X680709Y1191141D02*
X678838Y1193011D01*
G01X676968Y1191141D02*
X675098Y1193011D01*
G01X682579D02*
X684449Y1191141D01*
G01X678838Y1193011D02*
X676968Y1191141D01*
G01X675098Y1193011D02*
X673228Y1191141D01*
G01X671358Y1193011D02*
X673228Y1191141D01*
G01X684449Y1209842D02*
X686319Y1207972D01*
G01X684449Y1206102D02*
X682579Y1207972D01*
G01D02*
X684449Y1209842D01*
G01X680709Y1206102D02*
X682579Y1207972D01*
G01X676968Y1206102D02*
X678838Y1207972D01*
G01D02*
X680709Y1206102D01*
G01Y1209842D02*
X678838Y1207972D01*
G01X682579D02*
X680709Y1209842D01*
G01X678838Y1207972D02*
X676968Y1209842D01*
G01D02*
X675098Y1207972D01*
G01D02*
X673228Y1209842D01*
G01X676968Y1206102D02*
X675098Y1207972D01*
G01D02*
X673228Y1206102D01*
G01X686319Y1207972D02*
X684449Y1206102D01*
G01X673228Y1209842D02*
X671358Y1207972D01*
G01D02*
X673228Y1206102D01*
G01X678838Y1219192D02*
X676968Y1217322D01*
G01X699409Y1123818D02*
X701279Y1121948D01*
G01D02*
X703149Y1123818D01*
G01Y1120078D02*
X701279Y1121948D01*
G01D02*
X699409Y1120078D01*
G01X695669Y1123818D02*
X697539Y1125688D01*
G01X693799Y1121948D02*
X695669Y1120078D01*
G01X691929Y1123818D02*
X693799Y1121948D01*
G01X695669Y1123818D02*
X693799Y1125688D01*
G01X699409Y1123818D02*
X697539Y1121948D01*
G01D02*
X699409Y1120078D01*
G01X695669D02*
X697539Y1121948D01*
G01D02*
X695669Y1123818D01*
G01X688189Y1116338D02*
X686319Y1118208D01*
G01X688189Y1120078D02*
X686319Y1121948D01*
G01X688189Y1116338D02*
X686319Y1114468D01*
G01X701279Y1125688D02*
X699409Y1123818D01*
G01X697539Y1125688D02*
X699409Y1123818D01*
G01X693799Y1125688D02*
X691929Y1123818D01*
G01X686319Y1125688D02*
X688189Y1123818D01*
G01X686319Y1118208D02*
X688189Y1120078D01*
G01X686319Y1121948D02*
X688189Y1123818D01*
G01X686319Y1114468D02*
X688189Y1112598D01*
G01X703149Y1127558D02*
X701279Y1125688D01*
G01D02*
X703149Y1123818D01*
G01X695669Y1127558D02*
X697539Y1125688D01*
G01X691929Y1127558D02*
X693799Y1125688D01*
G01X701279D02*
X699409Y1127558D01*
G01X697539Y1125688D02*
X699409Y1127558D01*
G01X693799Y1125688D02*
X695669Y1127558D01*
G01X688189D02*
X686319Y1125688D01*
G01X691929Y1135039D02*
X693504Y1133464D01*
X693799D01*
G01X695669Y1135039D02*
X697539Y1133169D01*
G01X703149Y1135039D02*
X701279Y1133169D01*
G01X693799Y1133464D02*
X695374Y1135039D01*
X695669D01*
G01X697539Y1133169D02*
X699409Y1135039D01*
G01X686417Y1132677D02*
X688189Y1134448D01*
Y1135039D01*
G01X701279Y1133169D02*
X699409Y1135039D01*
G01X686319Y1129429D02*
X688189Y1131299D01*
G01X693799Y1129429D02*
X691929Y1131299D01*
G01X697539Y1129429D02*
X695669Y1131299D01*
G01X701279Y1129429D02*
X699409Y1131299D01*
G01X701279Y1136909D02*
X699409Y1138779D01*
G01X693799Y1136909D02*
X691929Y1138779D01*
G01X697539Y1136909D02*
X699409Y1138779D01*
G01X695669D02*
X693799Y1136909D01*
G01X703149Y1138779D02*
X701279Y1136909D01*
G01X695669Y1138779D02*
X697539Y1136909D01*
G01X686319D02*
X688189Y1138779D01*
G01Y1157480D02*
X686319Y1155610D01*
G01X691929Y1142519D02*
X693799Y1140649D01*
G01X699409Y1142519D02*
X697539Y1140649D01*
G01X699409Y1149999D02*
X697539Y1148129D01*
G01X703149Y1149999D02*
X701279Y1148129D01*
G01X703149Y1142519D02*
X701279Y1140649D01*
G01X691929Y1149999D02*
X693799Y1148129D01*
G01Y1140649D02*
X695669Y1142519D01*
G01X697539Y1140649D02*
X695669Y1142519D01*
G01X701279Y1140649D02*
X699409Y1142519D01*
G01X697539Y1148129D02*
X695669Y1149999D01*
G01X701279Y1148129D02*
X699409Y1149999D01*
G01X693799Y1148129D02*
X695669Y1149999D01*
G01Y1157480D02*
X697539Y1155610D01*
G01X686319Y1140649D02*
X688189Y1142519D01*
G01X686319Y1148129D02*
X688189Y1149999D01*
G01X691929Y1157480D02*
X693799Y1155610D01*
G01X699409Y1157480D02*
X701279Y1155610D01*
G01X686319Y1144389D02*
X688189Y1146259D01*
G01X686319Y1151870D02*
X688189Y1153740D01*
G01X703149Y1146259D02*
X701279Y1144389D01*
G01X699409Y1146259D02*
X697539Y1144389D01*
G01X691929Y1146259D02*
X693799Y1144389D01*
G01X701279D02*
X699409Y1146259D01*
G01X697539Y1144389D02*
X695669Y1146259D01*
G01X693799Y1144389D02*
X695669Y1146259D01*
G01X703149Y1153740D02*
X701279Y1151869D01*
G01X699409Y1153740D02*
X698814Y1153145D01*
X697539Y1151869D01*
G01X691929Y1153740D02*
X693799Y1151869D01*
G01X701279D02*
X699409Y1153740D01*
G01X697539Y1151869D02*
X695669Y1153740D01*
G01X693799Y1151869D02*
X695669Y1153740D01*
G01X688189Y1172440D02*
X686319Y1174310D01*
G01X699409Y1161220D02*
X701279Y1159350D01*
G01X699409Y1168700D02*
X697539Y1166830D01*
G01X703149Y1172440D02*
X701279Y1170570D01*
G01X691929Y1161220D02*
X693799Y1159350D01*
G01X697539Y1166830D02*
X695669Y1164960D01*
G01Y1172440D02*
X697539Y1174310D01*
G01X691929Y1168700D02*
X693799Y1170570D01*
G01D02*
X695669Y1172440D01*
G01X693799Y1159350D02*
X695669Y1157480D01*
G01X701279Y1159350D02*
X703149Y1157480D01*
G01X701279Y1170570D02*
X699409Y1168700D01*
G01X686319Y1166830D02*
X688189Y1164960D01*
G01X686319Y1159350D02*
X688189Y1161220D01*
G01X699409Y1157480D02*
X697539Y1159350D01*
G01D02*
X695669Y1161220D01*
G01X686319Y1170570D02*
X688189Y1168700D01*
G01X699409Y1164960D02*
X701279Y1166830D01*
G01D02*
X703149Y1168700D01*
G01X699409Y1172440D02*
X701279Y1174310D01*
G01X699409Y1172440D02*
X697539Y1170570D01*
G01D02*
X695669Y1168700D01*
G01X691929Y1164960D02*
X693799Y1166830D01*
G01X691929Y1172440D02*
X693799Y1174310D01*
G01X695669Y1187401D02*
X693799Y1189271D01*
G01X699409Y1187401D02*
X701279Y1189271D01*
G01X695669Y1187401D02*
X697539Y1189271D01*
G01X691929Y1179921D02*
X693799Y1181791D01*
G01X703149Y1179921D02*
X701279Y1181791D01*
G01X699409Y1179921D02*
X697539Y1181791D01*
G01X693799D02*
X695669Y1179921D01*
G01X693799Y1189271D02*
X691929Y1187401D01*
G01X697539Y1189271D02*
X699409Y1187401D01*
G01X701279Y1189271D02*
X703149Y1187401D01*
G01X701279Y1181791D02*
X699409Y1179921D01*
G01X697539Y1181791D02*
X695669Y1179921D01*
G01X686319Y1181791D02*
X688189Y1179921D01*
G01X686319Y1189271D02*
X688189Y1187401D01*
G01X686319Y1178051D02*
X688189Y1176180D01*
G01X686319Y1185531D02*
X688189Y1183661D01*
G01X703149Y1176180D02*
X701279Y1178051D01*
G01X695669Y1176180D02*
X697539Y1178051D01*
G01X691929Y1176180D02*
X693799Y1178051D01*
G01X701279D02*
X699409Y1176180D01*
G01X697539Y1178051D02*
X698814Y1176775D01*
X699409Y1176180D01*
G01X693799Y1178051D02*
X695669Y1176180D01*
G01X703149Y1183661D02*
X701279Y1185531D01*
G01X699409Y1183661D02*
X697539Y1185531D01*
G01X691929Y1183661D02*
X693799Y1185531D01*
G01X701279D02*
X699409Y1183661D01*
G01X697539Y1185531D02*
X695669Y1183661D01*
G01X693799Y1185531D02*
X695669Y1183661D01*
G01X691929Y1194881D02*
X693799Y1196751D01*
G01X695669Y1194881D02*
X697539Y1196751D01*
G01X699409Y1206102D02*
X701279Y1204232D01*
G01D02*
X703149Y1206102D01*
G01Y1202362D02*
X701279Y1204232D01*
G01D02*
X699409Y1202362D01*
G01X695669D02*
X693799Y1204232D01*
G01D02*
X691929Y1202362D01*
G01X695669Y1206102D02*
X693799Y1204232D01*
G01D02*
X691929Y1206102D01*
G01X695669Y1202362D02*
X697539Y1204232D01*
G01D02*
X695669Y1206102D01*
G01X699409D02*
X697539Y1204232D01*
G01D02*
X699409Y1202362D01*
G01X703149Y1194881D02*
X701279Y1196751D01*
G01X688189Y1202362D02*
X686319Y1204232D01*
G01D02*
X688189Y1206102D01*
G01X693799Y1196751D02*
X695669Y1194881D01*
G01X697539Y1196751D02*
X699409Y1194881D01*
G01X701279Y1196751D02*
X699409Y1194881D01*
G01X686319Y1196751D02*
X688189Y1194881D01*
G01X686319Y1200491D02*
X688189Y1198621D01*
G01X693799Y1200491D02*
X691929Y1198621D01*
G01X697539Y1200491D02*
X695669Y1198621D01*
G01X701279Y1200491D02*
X699409Y1198621D01*
G01X686319Y1193011D02*
X688189Y1191141D01*
G01X695669D02*
X697539Y1193011D01*
G01X691929Y1191141D02*
X693799Y1193011D01*
G01D02*
X695669Y1191141D01*
G01X699409D02*
X701279Y1193011D01*
G01X691929Y1206102D02*
X693799Y1207972D01*
G01D02*
X695669Y1206102D01*
G01X691929Y1209842D02*
X693799Y1207972D01*
G01D02*
X695669Y1209842D01*
G01D02*
X697539Y1207972D01*
G01D02*
X699409Y1206102D01*
G01X697539Y1207972D02*
X699409Y1209842D01*
G01X695669Y1206102D02*
X697539Y1207972D01*
G01X699409Y1206102D02*
X701279Y1207972D01*
G01D02*
X703149Y1206102D01*
G01Y1209842D02*
X701279Y1207972D01*
G01D02*
X699409Y1209842D01*
G01D02*
X697539Y1211712D01*
G01X703149Y1209842D02*
X701279Y1211712D01*
G01X688189Y1206102D02*
X686319Y1207972D01*
G01D02*
X688189Y1209842D01*
G01X697539Y1211712D02*
X695669Y1209842D01*
G01X701279Y1211712D02*
X699409Y1209842D01*
G01X710630Y1123818D02*
X712500Y1125688D01*
G01X714370Y1123818D02*
X712500Y1125688D01*
G01X716240D02*
X714370Y1123818D01*
G01D02*
X716240Y1121948D01*
G01D02*
X714370Y1120078D01*
G01X718110Y1123818D02*
X716240Y1121948D01*
G01D02*
X718110Y1120078D01*
G01X719980Y1121948D02*
X718110Y1120078D01*
G01X714370D02*
X712500Y1121948D01*
G01D02*
X710630Y1120078D01*
G01X714370Y1123818D02*
X712500Y1121948D01*
G01D02*
X710630Y1123818D01*
G01D02*
X708760Y1121948D01*
G01D02*
X706890Y1123818D01*
G01X710630Y1120078D02*
X708760Y1121948D01*
G01X710630Y1123818D02*
X708760Y1125688D01*
G01D02*
X706890Y1123818D01*
G01D02*
X705020Y1125688D01*
G01D02*
X703149Y1123818D01*
G01Y1120078D02*
X705020Y1121948D01*
G01D02*
X703149Y1123818D01*
G01X706890D02*
X705020Y1121948D01*
G01X708760D02*
X706890Y1120078D01*
G01X705020Y1121948D02*
X706890Y1120078D01*
G01Y1127558D02*
X705020Y1125688D01*
G01X719980D02*
X718110Y1127558D01*
G01Y1123818D02*
X719980Y1121948D01*
G01X718110Y1123818D02*
X719980Y1125688D01*
G01X718110Y1123818D02*
X716240Y1125688D01*
G01D02*
X718110Y1127558D01*
G01X716240Y1125688D02*
X714370Y1127558D01*
G01X710630D02*
X712500Y1125688D01*
G01X710630Y1127558D02*
X708760Y1125688D01*
G01X712500D02*
X714370Y1127558D01*
G01X708760Y1125688D02*
X706890Y1127558D01*
G01X705020Y1125688D02*
X703149Y1127558D01*
G01X718110Y1135039D02*
X719980Y1133169D01*
G01X714370Y1135039D02*
X716240Y1133169D01*
G01X710630Y1135039D02*
X712500Y1133169D01*
G01X710630Y1135039D02*
X708760Y1133169D01*
G01X706890Y1135039D02*
X705020Y1133169D01*
G01X716240D02*
X718110Y1135039D01*
G01X712500Y1133169D02*
X714370Y1135039D01*
G01X708760Y1133169D02*
X706890Y1135039D01*
G01X705020Y1133169D02*
X703149Y1135039D01*
G01X716240Y1129429D02*
X714370Y1131299D01*
G01X712500Y1129429D02*
X710630Y1131299D01*
G01X708760Y1129429D02*
X706890Y1131299D01*
G01X705020Y1129429D02*
X703149Y1131299D01*
G01X719980Y1129429D02*
X718110Y1131299D01*
G01X712500Y1136909D02*
X714370Y1138779D01*
G01X708760Y1136909D02*
X710630Y1138779D01*
G01X705020Y1136909D02*
X703149Y1138779D01*
G01X716240Y1136909D02*
X718110Y1138779D01*
G01X710630D02*
X712500Y1136909D01*
G01X706890Y1138779D02*
X708760Y1136909D01*
G01X706890Y1138779D02*
X705020Y1136909D01*
G01X714370Y1138779D02*
X716240Y1136909D01*
G01X718110Y1138779D02*
X719980Y1136909D01*
G01X718110Y1149999D02*
X719980Y1148129D01*
G01X718110Y1142519D02*
X719980Y1140649D01*
G01X718110Y1149999D02*
X716240Y1148129D01*
G01X710630Y1149999D02*
X712500Y1148129D01*
G01X710630Y1149999D02*
X708760Y1148129D01*
G01X703149Y1149999D02*
X705020Y1148129D01*
G01X718110Y1142519D02*
X716240Y1140649D01*
G01X710630Y1142519D02*
X712500Y1140649D01*
G01X710630Y1142519D02*
X708760Y1140649D01*
G01X706890Y1142519D02*
X705020Y1140649D01*
G01X716240D02*
X714370Y1142519D01*
G01X712500Y1140649D02*
X714370Y1142519D01*
G01X708760Y1140649D02*
X706890Y1142519D01*
G01X705020Y1140649D02*
X703149Y1142519D01*
G01X716240Y1148129D02*
X714370Y1149999D01*
G01X712500Y1148129D02*
X714370Y1149999D01*
G01X708760Y1148129D02*
X706890Y1149999D01*
G01X705020Y1148129D02*
X706890Y1149999D01*
G01X710630Y1157480D02*
X712500Y1155610D01*
G01X703149Y1157480D02*
X705020Y1155610D01*
G01X716240D02*
X714370Y1157480D01*
G01X706890D02*
X708760Y1155610D01*
G01X718110Y1146259D02*
X719980Y1144389D01*
G01X714370Y1146259D02*
X712500Y1144389D01*
G01X706890Y1146259D02*
X705020Y1144389D01*
G01X706890Y1146259D02*
X708760Y1144389D01*
G01X714370Y1146259D02*
X716240Y1144389D01*
G01X712500D02*
X710630Y1146259D01*
G01X705020Y1144389D02*
X703149Y1146259D01*
G01X708760Y1144389D02*
X710630Y1146259D01*
G01X716240Y1144389D02*
X718110Y1146259D01*
G01X706890Y1153740D02*
X708760Y1151869D01*
G01X718110Y1153740D02*
X719980Y1151869D01*
G01X714370Y1153740D02*
X716240Y1151869D01*
G01X714370Y1153740D02*
X712500Y1151869D01*
G01X706890Y1153740D02*
X705020Y1151869D01*
G01X716240D02*
X718110Y1153740D01*
G01X708760Y1151869D02*
X710630Y1153740D01*
G01X712500Y1151869D02*
X710630Y1153740D01*
G01X705020Y1151869D02*
X703149Y1153740D01*
G01X718110Y1157480D02*
X719980Y1155610D01*
G01X714370Y1161220D02*
X716240Y1159350D01*
G01X718110Y1164960D02*
X719980Y1166830D01*
G01X718110Y1172440D02*
X719980Y1174310D01*
G01X714370Y1168700D02*
X712500Y1166830D01*
G01X714370Y1168700D02*
X716240Y1170570D01*
G01X710630Y1157480D02*
X708760Y1159350D01*
G01X716240Y1170570D02*
X718110Y1172440D01*
G01X716240Y1159350D02*
X718110Y1157480D01*
G01X708760Y1159350D02*
X706890Y1161220D01*
G01Y1168700D02*
X705020Y1166830D01*
G01X710630Y1172440D02*
X712500Y1174310D01*
G01X710630Y1172440D02*
X708760Y1170570D01*
G01X705020Y1166830D02*
X703149Y1164960D01*
G01X712500Y1166830D02*
X710630Y1164960D01*
G01X708760Y1170570D02*
X706890Y1168700D01*
G01X703149Y1172440D02*
X705020Y1174310D01*
G01X710630Y1161220D02*
X712500Y1159350D01*
G01D02*
X714370Y1157480D01*
G01X706890D02*
X705020Y1159350D01*
G01D02*
X703149Y1161220D01*
G01X706890Y1172440D02*
X708760Y1174310D01*
G01X706890Y1172440D02*
X705020Y1170570D01*
G01D02*
X703149Y1168700D01*
G01X716240Y1174310D02*
X714370Y1172440D01*
G01D02*
X712500Y1170570D01*
G01X710630Y1168700D02*
X708760Y1166830D01*
G01X712500Y1170570D02*
X710630Y1168700D01*
G01X708760Y1166830D02*
X706890Y1164960D01*
G01X714370D02*
X716240Y1166830D01*
G01X718110Y1168700D02*
X719980Y1170570D01*
G01X718110Y1161220D02*
X719980Y1159350D01*
G01X718110Y1187401D02*
X719980Y1189271D01*
G01X718110Y1187401D02*
X716240Y1189271D01*
G01X710630Y1187401D02*
X712500Y1189271D01*
G01X710630Y1187401D02*
X708760Y1189271D01*
G01X706890Y1187401D02*
X705020Y1189271D01*
G01X718110Y1179921D02*
X719980Y1181791D01*
G01X718110Y1179921D02*
X716240Y1181791D01*
G01X710630Y1179921D02*
X712500Y1181791D01*
G01X710630Y1179921D02*
X708760Y1181791D01*
G01X706890Y1179921D02*
X705020Y1181791D01*
G01X716240Y1189271D02*
X714370Y1187401D01*
G01X716240Y1181791D02*
X714370Y1179921D01*
G01X712500Y1189271D02*
X714370Y1187401D01*
G01X708760Y1189271D02*
X706890Y1187401D01*
G01X705020Y1189271D02*
X703149Y1187401D01*
G01X712500Y1181791D02*
X714370Y1179921D01*
G01X708760Y1181791D02*
X706890Y1179921D01*
G01X705020Y1181791D02*
X703149Y1179921D01*
G01Y1176180D02*
X705020Y1178051D01*
G01X718110Y1176180D02*
X719980Y1178051D01*
G01X718110Y1176180D02*
X716240Y1178051D01*
G01X710630Y1176180D02*
X712500Y1178051D01*
G01X710630Y1176180D02*
X708760Y1178051D01*
G01X716240D02*
X714370Y1176180D01*
G01X712500Y1178051D02*
X714370Y1176180D01*
G01X705020Y1178051D02*
X706890Y1176180D01*
G01X708760Y1178051D02*
X706890Y1176180D01*
G01X718110Y1183661D02*
X719980Y1185531D01*
G01X718110Y1183661D02*
X716240Y1185531D01*
G01X706890Y1183661D02*
X708760Y1185531D01*
G01X710630Y1183661D02*
X712500Y1185531D01*
G01X706890Y1183661D02*
X705020Y1185531D01*
G01X716240D02*
X714370Y1183661D01*
G01X708760Y1185531D02*
X710630Y1183661D01*
G01X712500Y1185531D02*
X714370Y1183661D01*
G01X705020Y1185531D02*
X703149Y1183661D01*
G01X718110Y1194881D02*
X716240Y1196751D01*
G01X710630Y1194881D02*
X712500Y1196751D01*
G01X710630Y1194881D02*
X708760Y1196751D01*
G01X706890Y1194881D02*
X705020Y1196751D01*
G01X710630Y1202362D02*
X712500Y1204232D01*
G01X714370Y1206102D02*
X716240Y1204232D01*
G01D02*
X714370Y1202362D01*
G01X718110Y1206102D02*
X716240Y1204232D01*
G01X718110Y1202362D02*
X719980Y1204232D01*
G01X716240D02*
X718110Y1202362D01*
G01Y1194881D02*
X719980Y1196751D01*
G01X703149Y1206102D02*
X705020Y1204232D01*
G01D02*
X706890Y1206102D01*
G01X705020Y1204232D02*
X703149Y1202362D01*
G01X706890D02*
X705020Y1204232D01*
G01X706890Y1206102D02*
X708760Y1204232D01*
G01D02*
X710630Y1206102D01*
G01X706890Y1202362D02*
X708760Y1204232D01*
G01D02*
X710630Y1202362D01*
G01X712500Y1204232D02*
X714370Y1206102D01*
G01X710630D02*
X712500Y1204232D01*
G01X716240Y1196751D02*
X714370Y1194881D01*
G01X712500Y1196751D02*
X714370Y1194881D01*
G01X708760Y1196751D02*
X706890Y1194881D01*
G01X705020Y1196751D02*
X703149Y1194881D01*
G01X716240Y1200491D02*
X714370Y1198621D01*
G01X708760Y1200491D02*
X706890Y1198621D01*
G01X705020Y1200491D02*
X703149Y1198621D01*
G01X712500Y1200491D02*
X710630Y1198621D01*
G01X719980Y1200491D02*
X718110Y1198621D01*
G01X714370Y1191141D02*
X716240Y1193011D01*
G01X703149Y1191141D02*
X705020Y1193011D01*
G01X710630Y1191141D02*
X712500Y1193011D01*
G01X706890Y1191141D02*
X708760Y1193011D01*
G01X718110Y1191141D02*
X719980Y1193011D01*
G01X714370Y1206102D02*
X716240Y1207972D01*
G01D02*
X718110Y1206102D01*
G01X716240Y1207972D02*
X718110Y1209842D01*
G01X719980Y1207972D02*
X718110Y1209842D01*
G01X719980Y1207972D02*
X718110Y1206102D01*
G01Y1209842D02*
X719980Y1211712D01*
G01X718110Y1206102D02*
X719980Y1204232D01*
G01X714370Y1206102D02*
X712500Y1207972D01*
G01D02*
X714370Y1209842D01*
G01X710630D02*
X712500Y1207972D01*
G01X710630Y1209842D02*
X708760Y1207972D01*
G01D02*
X710630Y1206102D01*
G01X708760Y1207972D02*
X706890Y1206102D01*
G01X712500Y1207972D02*
X710630Y1206102D01*
G01X708760Y1207972D02*
X706890Y1209842D01*
G01X703149D02*
X705020Y1207972D01*
G01D02*
X706890Y1209842D01*
G01Y1206102D02*
X705020Y1207972D01*
G01D02*
X703149Y1206102D01*
G01X716240Y1207972D02*
X714370Y1209842D01*
G01D02*
X716240Y1211712D01*
G01X710630Y1209842D02*
X712500Y1211712D01*
G01X716240D02*
X718110Y1209842D01*
G01X712500Y1211712D02*
X714370Y1209842D01*
G01X733071Y1120078D02*
X734941Y1118208D01*
G01X721850Y1123818D02*
X723720Y1121948D01*
G01D02*
X721850Y1120078D01*
G01X727460Y1118208D02*
X725590Y1120078D01*
G01X723720Y1121948D02*
X725590Y1120078D01*
G01D02*
X727460Y1121948D01*
G01D02*
X725590Y1123818D01*
G01X729331Y1120078D02*
X727460Y1121948D01*
G01D02*
X729331Y1123818D01*
G01X721850D02*
X723720Y1125688D01*
G01X721850Y1123818D02*
X719980Y1121948D01*
G01X729331Y1120078D02*
X731201Y1121948D01*
G01X729331Y1120078D02*
X731201Y1118208D01*
G01X723720Y1125688D02*
X725590Y1123818D01*
G01X719980Y1125688D02*
X721850Y1123818D01*
G01X719980Y1121948D02*
X721850Y1120078D01*
G01X731201Y1121948D02*
X733071Y1120078D01*
G01X731201Y1118208D02*
X733071Y1120078D01*
G01X727460Y1125688D02*
X729331Y1123818D01*
G01X731201Y1125688D02*
X729331Y1123818D01*
G01X733071Y1138779D02*
X734941Y1140649D01*
G01Y1136909D02*
X733071Y1138779D01*
G01X725590Y1127558D02*
X727460Y1125688D01*
G01X723720D02*
X725590Y1127558D01*
G01X721850D02*
X719980Y1125688D01*
G01X721850Y1127558D02*
X723720Y1125688D01*
G01X729331Y1127558D02*
X731201Y1125688D01*
G01X725590Y1131299D02*
X727460Y1129429D01*
G01D02*
X725590Y1127558D01*
G01X729331Y1135039D02*
X727460Y1133169D01*
G01X725590Y1135039D02*
X723720Y1133169D01*
G01X729331Y1135039D02*
X727460Y1136909D01*
G01Y1133169D02*
X725590Y1135039D01*
G01X723720Y1133169D02*
X721850Y1135039D01*
G01X719980Y1133169D02*
X721850Y1135039D01*
G01X727460Y1136909D02*
X725590Y1138779D01*
G01X723720Y1129429D02*
X721850Y1131299D01*
G01X729331D02*
X731201Y1129429D01*
G01X719980Y1136909D02*
X721850Y1138779D01*
G01D02*
X723720Y1136909D01*
G01X729331Y1138779D02*
X731201Y1136909D01*
G01X729331Y1138779D02*
X731201Y1140649D01*
G01X721850Y1149999D02*
X723720Y1148129D01*
G01X729331Y1149999D02*
X731201Y1148129D01*
G01D02*
X733071Y1146259D01*
G01X731201Y1148129D02*
X733071Y1149999D01*
G01Y1153740D02*
X734941Y1151870D01*
G01X733071Y1146259D02*
X734941Y1148129D01*
G01Y1144389D02*
X733071Y1146259D01*
G01Y1142519D02*
X734941Y1144389D01*
G01Y1140649D02*
X733071Y1142519D01*
G01Y1149999D02*
X734941Y1148129D01*
G01X733071Y1153740D02*
X731201Y1151869D01*
G01D02*
X733071Y1149999D01*
G01X731201Y1151869D02*
X729331Y1153740D01*
G01D02*
X731201Y1155610D01*
G01D02*
X733071Y1153740D01*
G01X731201Y1155610D02*
X729331Y1157480D01*
G01Y1149999D02*
X727460Y1151869D01*
G01D02*
X725590Y1149999D01*
G01X729331Y1153740D02*
X727460Y1151869D01*
G01X729331Y1157480D02*
X727460Y1155610D01*
G01D02*
X725590Y1157480D01*
G01X729331Y1153740D02*
X727460Y1155610D01*
G01Y1151869D02*
X725590Y1153740D01*
G01X727460Y1155610D02*
X725590Y1153740D01*
G01X729331Y1149999D02*
X731201Y1151869D01*
G01X725590Y1146259D02*
X727460Y1148129D01*
G01D02*
X725590Y1149999D01*
G01X729331D02*
X727460Y1148129D01*
G01X725590Y1142519D02*
X727460Y1140649D01*
G01X725590Y1142519D02*
X723720Y1140649D01*
G01X725590Y1146259D02*
X727460Y1144389D01*
G01X723720Y1140649D02*
X721850Y1142519D01*
G01X719980Y1140649D02*
X721850Y1142519D01*
G01X727460Y1144389D02*
X725590Y1142519D01*
G01X723720Y1148129D02*
X725590Y1149999D01*
G01X719980Y1148129D02*
X721850Y1149999D01*
G01Y1157480D02*
X723720Y1155610D01*
G01X721850Y1146259D02*
X723720Y1144389D01*
G01X719980D02*
X721850Y1146259D01*
G01Y1153740D02*
X723720Y1151869D01*
G01X719980D02*
X721850Y1153740D01*
G01X734941Y1155610D02*
X733071Y1157480D01*
G01X729331Y1146259D02*
X731201Y1144389D01*
G01Y1140649D02*
X729331Y1142519D01*
G01X731201Y1144389D02*
X729331Y1142519D01*
G01Y1157480D02*
X731201Y1159350D01*
G01X725590Y1172440D02*
X727460Y1174310D01*
G01X729331Y1172440D02*
X727460Y1174310D01*
G01X729331Y1172440D02*
X731201Y1170570D01*
G01X729331Y1168700D02*
X731201Y1166830D01*
G01X729331Y1172440D02*
X731201Y1174310D01*
G01Y1170570D02*
X729331Y1168700D01*
G01X731201Y1159350D02*
X729331Y1161220D01*
G01X731201Y1166830D02*
X729331Y1164960D01*
G01X721850Y1172440D02*
X723720Y1174310D01*
G01X725590Y1168700D02*
X727460Y1170570D01*
G01X725590Y1168700D02*
X723720Y1170570D01*
G01X719980D02*
X721850Y1168700D01*
G01X723720Y1170570D02*
X721850Y1168700D01*
G01X725590Y1164960D02*
X727460Y1166830D01*
G01X721850Y1164960D02*
X723720Y1166830D01*
G01D02*
X725590Y1164960D01*
G01Y1161220D02*
X727460Y1159350D01*
G01X725590Y1161220D02*
X723720Y1159350D01*
G01X719980D02*
X721850Y1161220D01*
G01X723720Y1159350D02*
X721850Y1161220D01*
G01X733071Y1164960D02*
X734941Y1166830D01*
G01X733071Y1172440D02*
X734941Y1174310D01*
G01X733071Y1172440D02*
X734941Y1170570D01*
G01Y1166830D02*
X733071Y1168700D01*
G01X734941Y1170570D02*
X733071Y1168700D01*
G01X734941Y1159350D02*
X733071Y1161220D01*
G01X725590Y1187401D02*
X727460Y1189271D01*
G01X721850Y1187401D02*
X723720Y1189271D01*
G01D02*
X725590Y1187401D01*
G01X723720Y1189271D02*
X725590Y1191141D01*
G01X733071Y1183661D02*
X731201Y1181791D01*
G01X733071Y1176180D02*
X734941Y1178051D01*
G01X733071Y1183661D02*
X734941Y1185531D01*
G01X733071Y1179921D02*
X734941Y1181791D01*
G01X733071Y1183661D02*
X734941Y1181791D01*
G01X733071Y1187401D02*
X734941Y1185531D01*
G01Y1189271D02*
X733071Y1187401D01*
G01Y1179921D02*
X734941Y1178051D01*
G01X725590Y1176180D02*
X727460Y1178051D01*
G01Y1174310D02*
X725590Y1176180D01*
G01X727460Y1185531D02*
X725590Y1183661D01*
G01D02*
X723720Y1181791D01*
G01D02*
X721850Y1179921D01*
G01X719980Y1181791D02*
X721850Y1179921D01*
G01X719980Y1189271D02*
X721850Y1187401D01*
G01X731201Y1174310D02*
X733071Y1176180D01*
G01X725590Y1179921D02*
X727460Y1181791D01*
G01X721850Y1183661D02*
X723720Y1185531D01*
G01X721850Y1176180D02*
X723720Y1178051D01*
G01X729331Y1183661D02*
X731201Y1185531D01*
G01X729331Y1187401D02*
X731201Y1189271D01*
G01X729331Y1176180D02*
X731201Y1178051D01*
G01X725590Y1198621D02*
X723720Y1196751D01*
G01D02*
X721850Y1194881D01*
G01X725590D02*
X723720Y1196751D01*
G01X725590Y1198621D02*
X727460Y1200491D01*
G01D02*
X729331Y1202362D01*
G01X725590D02*
X727460Y1200491D01*
G01X721850Y1202362D02*
X723720Y1204232D01*
G01D02*
X725590Y1202362D01*
G01Y1206102D02*
X723720Y1204232D01*
G01D02*
X721850Y1206102D01*
G01X725590Y1202362D02*
X727460Y1204232D01*
G01D02*
X729331Y1202362D01*
G01Y1206102D02*
X727460Y1204232D01*
G01D02*
X725590Y1206102D01*
G01Y1194881D02*
X727441Y1196732D01*
X727480D01*
G01D02*
X725590Y1198621D01*
G01X727480Y1196732D02*
X729331Y1194881D01*
G01X731201Y1196751D02*
X729331Y1194881D01*
G01D02*
X727460Y1193011D01*
G01D02*
X725590Y1194881D01*
G01X727460Y1193011D02*
X725590Y1191141D01*
G01X721850Y1206102D02*
X719980Y1204232D01*
G01X729331Y1206102D02*
X731201Y1204232D01*
G01X719980D02*
X721850Y1202362D01*
G01X733071Y1191141D02*
X734941Y1189271D01*
G01Y1193011D02*
X733071Y1191141D01*
G01X731201Y1204232D02*
X729331Y1202362D01*
G01X719980Y1196751D02*
X721850Y1194881D01*
G01X723720Y1200491D02*
X721850Y1198621D01*
G01X729331D02*
X731201Y1200491D01*
G01X721850Y1191141D02*
X723720Y1193011D01*
G01X729331Y1191141D02*
X731201Y1193011D01*
G01X733071Y1194881D02*
X734941Y1196751D01*
G01X733071Y1202362D02*
X734941Y1204232D01*
G01X733071Y1198621D02*
X734941Y1200491D01*
G01X721850Y1209842D02*
X723720Y1207972D01*
G01D02*
X725590Y1209842D01*
G01Y1206102D02*
X723720Y1207972D01*
G01D02*
X721850Y1206102D01*
G01X725590Y1209842D02*
X727460Y1207972D01*
G01D02*
X729331Y1209842D01*
G01Y1206102D02*
X727460Y1207972D01*
G01D02*
X725590Y1206102D01*
G01X729331D02*
X731201Y1207972D01*
G01D02*
X729331Y1209842D01*
G01X731201Y1207972D02*
X733071Y1209842D01*
G01D02*
X734941Y1211712D01*
G01X721850Y1209842D02*
X719980Y1207972D01*
G01X721850Y1209842D02*
X723720Y1211712D01*
G01X725590Y1209842D02*
X727460Y1211712D01*
G01X719980Y1207972D02*
X721850Y1206102D01*
G01X723720Y1211712D02*
X725590Y1209842D01*
G01X719980Y1211712D02*
X721850Y1209842D01*
G01X727460Y1211712D02*
X729331Y1209842D01*
G01X736811Y1120078D02*
X734941Y1121948D01*
G01D02*
X736811Y1123818D01*
G01X734941Y1118208D02*
X736811Y1120078D01*
G01X734941Y1125688D02*
X736811Y1123818D01*
G01Y1127558D02*
X734941Y1125688D01*
G01X736811Y1127558D02*
X734941Y1129429D01*
G01X736811Y1138779D02*
X738681Y1140649D01*
G01X736811Y1135039D02*
X734941Y1136909D01*
G01X736811Y1135039D02*
X738681Y1136909D01*
G01X736811Y1135039D02*
X734941Y1133169D01*
G01Y1140649D02*
X736811Y1138779D01*
G01X734941Y1136909D02*
X736811Y1138779D01*
G01X738681Y1136909D02*
X736811Y1138779D01*
G01X734941Y1129429D02*
X736811Y1131299D01*
G01X734941Y1133169D02*
X736811Y1131299D01*
G01Y1142519D02*
X734941Y1140649D01*
G01X736811Y1153740D02*
X738681Y1151869D01*
G01D02*
X736811Y1149999D01*
G01X738681Y1151869D02*
X740551Y1153740D01*
G01X736811Y1149999D02*
X738681Y1148129D01*
G01X736811Y1146259D02*
X734941Y1148129D01*
G01X736811Y1146259D02*
X734941Y1144389D01*
G01X748031Y1157480D02*
X746161Y1155610D01*
G01D02*
X744291Y1157480D01*
G01X746161Y1155610D02*
X744291Y1153740D01*
G01X748031Y1149999D02*
X746161Y1151869D01*
G01X748031Y1146259D02*
X749901Y1144389D01*
G01D02*
X751772Y1142519D01*
G01X749901Y1144389D02*
X748031Y1142519D01*
G01X746161Y1151869D02*
X744291Y1153740D01*
G01X746161Y1151869D02*
X748031Y1153740D01*
G01D02*
X746161Y1155610D01*
G01X748031Y1149999D02*
X749901Y1151869D01*
G01D02*
X748031Y1153740D01*
G01X749901Y1151869D02*
X751772Y1149999D01*
G01X748031Y1146259D02*
X746161Y1144389D01*
G01X744291Y1153740D02*
X742421Y1151869D01*
G01X734941Y1148129D02*
X736811Y1149999D01*
G01X734941Y1144389D02*
X736811Y1142519D01*
G01X738681Y1155610D02*
X736811Y1157480D01*
G01X738681Y1148129D02*
X736811Y1146259D01*
G01X738681Y1140649D02*
X736811Y1142519D01*
G01X746161Y1144389D02*
X748031Y1142519D01*
G01X742421Y1151869D02*
X740551Y1153740D01*
G01X734941Y1151870D02*
X736811Y1150000D01*
Y1149999D01*
G01X742421Y1155610D02*
X740551Y1157480D01*
G01X744291D02*
X746161Y1159350D01*
G01D02*
X748031Y1161220D01*
G01X746161Y1159350D02*
X748031Y1157480D01*
G01Y1161220D02*
X749901Y1159350D01*
G01D02*
X748031Y1157480D01*
G01X751772D02*
X749901Y1159350D01*
G01X746161D02*
X744291Y1161220D01*
G01Y1172440D02*
X746161Y1174310D01*
G01X748031Y1172440D02*
X746161Y1170570D01*
G01D02*
X744291Y1172440D01*
G01Y1168700D02*
X746161Y1170570D01*
G01X748031Y1164960D02*
X749901Y1166830D01*
G01D02*
X748031Y1168700D01*
G01X751772Y1164960D02*
X749901Y1166830D01*
G01X748031Y1164960D02*
X746161Y1166830D01*
G01D02*
X744291Y1168700D01*
G01Y1164960D02*
X746161Y1166830D01*
G01Y1174310D02*
X748031Y1172440D01*
G01Y1168700D02*
X746161Y1166830D01*
G01X748031Y1168700D02*
X746161Y1170570D01*
G01X748031Y1172440D02*
X749901Y1174310D01*
G01X738681D02*
X736811Y1172440D01*
G01Y1168700D02*
X738681Y1170570D01*
G01X736811Y1164960D02*
X738681Y1166830D01*
G01D02*
X736811Y1168700D01*
G01X738681Y1159350D02*
X736811Y1161220D01*
G01X738681Y1170570D02*
X736811Y1172440D01*
G01X742421Y1170570D02*
X740551Y1168700D01*
G01X742421Y1166830D02*
X740551Y1164960D01*
G01X742421Y1159350D02*
X740551Y1161220D01*
G01X742421Y1174310D02*
X740551Y1172440D01*
G01X748031Y1179921D02*
X746161Y1178051D01*
G01D02*
X748031Y1176180D01*
G01X746161Y1178051D02*
X744291Y1176180D01*
G01D02*
X746161Y1174310D01*
G01X748031Y1183661D02*
X746161Y1185531D01*
G01X748031Y1179921D02*
X749901Y1181791D01*
G01D02*
X751772Y1179921D01*
G01X748031Y1183661D02*
X749901Y1181791D01*
G01X748031Y1176180D02*
X749901Y1174310D01*
G01X746161D02*
X748031Y1176180D01*
G01X749901Y1174310D02*
X751772Y1172440D01*
G01X740551Y1191141D02*
X738681Y1189271D01*
G01D02*
X736811Y1191141D01*
G01X740551Y1183661D02*
X738681Y1185531D01*
G01D02*
X736811Y1187401D01*
G01X738681Y1185531D02*
X736811Y1183661D01*
G01X738681Y1189271D02*
X736811Y1187401D01*
G01Y1176180D02*
X738681Y1178051D01*
G01D02*
X740551Y1179921D01*
G01X738681Y1178051D02*
X740551Y1176180D01*
G01Y1183661D02*
X742421Y1181791D01*
G01X736811Y1176180D02*
X738681Y1174310D01*
G01X736811Y1191141D02*
X734941Y1189271D01*
G01X736811Y1183661D02*
X734941Y1185531D01*
G01X738681Y1174310D02*
X740551Y1176180D01*
G01X734941Y1189271D02*
X736811Y1187401D01*
G01X734941Y1185531D02*
X736811Y1187401D01*
G01X734941Y1181791D02*
X736811Y1183661D01*
G01X734941Y1178051D02*
X736811Y1176180D01*
G01X742421Y1181791D02*
X740551Y1179921D01*
G01X746161Y1185531D02*
X748031Y1187401D01*
G01X740551D02*
X742421Y1185531D01*
G01X748031Y1191141D02*
Y1187401D01*
G01X736811Y1179921D02*
X738681Y1181791D01*
G01X736811Y1206102D02*
X738681Y1204232D01*
G01D02*
X736811Y1202362D01*
G01X740551Y1191141D02*
X738681Y1193011D01*
G01D02*
X736811Y1194881D01*
G01Y1191141D02*
X738681Y1193011D01*
G01X740551Y1191141D02*
X742421Y1193011D01*
G01X736811Y1191141D02*
X734941Y1193011D01*
G01X736811Y1198621D02*
X738681Y1196751D01*
G01X734941Y1193011D02*
X736811Y1194881D01*
G01X738681Y1196751D02*
X736811Y1194881D01*
G01X751772D02*
X748031D01*
G01X740551D02*
X742421Y1196751D01*
G01X744291Y1198621D02*
X742421Y1200491D01*
G01X734941Y1211712D02*
X736811Y1209842D01*
G01X762992Y1138779D02*
X764862Y1140649D01*
G01X759252Y1138779D02*
X761122Y1140649D01*
G01X764862D02*
X766732Y1138779D01*
G01X757382Y1140649D02*
X759252Y1138779D01*
G01X761122Y1140649D02*
X762992Y1138779D01*
G01Y1146259D02*
X764862Y1148129D01*
G01D02*
X766732Y1149999D01*
G01X764862Y1148129D02*
X766732Y1146259D01*
G01X762992Y1153740D02*
X764862Y1155610D01*
G01D02*
X766732Y1157480D01*
G01X764862Y1155610D02*
X766732Y1153740D01*
G01Y1142519D02*
X768602Y1144389D01*
G01X766732Y1146259D02*
X768602Y1144389D01*
G01X766732Y1149999D02*
X768602Y1151869D01*
G01X766732Y1153740D02*
X768602Y1151869D01*
G01X759252Y1153740D02*
X757382Y1155610D01*
G01X755512Y1149999D02*
X757382Y1151869D01*
G01X751772Y1149999D02*
X753642Y1151869D01*
G01X762992Y1153740D02*
X761122Y1155610D01*
G01X762992Y1146259D02*
X761122Y1148129D01*
G01X764862Y1140649D02*
X766732Y1142519D01*
G01X755512D02*
X757382Y1140649D01*
G01X759252Y1146259D02*
X757382Y1144389D01*
G01X755512Y1149999D02*
X757382Y1148129D01*
G01X755512Y1142519D02*
X753642Y1144389D01*
G01D02*
X751772Y1142519D01*
G01X757382Y1144389D02*
X755512Y1142519D01*
G01X757382Y1148129D02*
X759252Y1146259D01*
G01X757382Y1151869D02*
X759252Y1153740D01*
G01X757382Y1155610D02*
X755512Y1157480D01*
G01X761122Y1148129D02*
X759252Y1146259D01*
G01X761122Y1155610D02*
X759252Y1153740D01*
G01X753642Y1151869D02*
X755512Y1149999D01*
G01X766732Y1157480D02*
X768602Y1159350D01*
G01X766732Y1161220D02*
X768602Y1159350D01*
G01X759252Y1161220D02*
X757382Y1159350D01*
G01X751772Y1157480D02*
X753642Y1159350D01*
G01X766732Y1172440D02*
X768602Y1174310D01*
G01X766732Y1164960D02*
X768602Y1166830D01*
G01D02*
X766732Y1168700D01*
G01Y1172440D02*
X764862Y1170570D01*
G01D02*
X766732Y1168700D01*
G01X764862Y1170570D02*
X762992Y1168700D01*
G01X755512Y1164960D02*
X757382Y1166830D01*
G01X755512Y1172440D02*
X753642Y1174310D01*
G01X755512Y1172440D02*
X757382Y1170570D01*
G01X759252Y1168700D02*
X761122Y1170570D01*
G01X751772Y1164960D02*
X753642Y1166830D01*
G01Y1174310D02*
X751772Y1172440D01*
G01X757382Y1174310D02*
X755512Y1172440D01*
G01X762992Y1161220D02*
X764862Y1159350D01*
G01X757382Y1166830D02*
X759252Y1168700D01*
G01X757382Y1170570D02*
X759252Y1168700D01*
G01X761122Y1170570D02*
X762992Y1168700D01*
G01X753642Y1166830D02*
X755512Y1164960D01*
G01X757382Y1159350D02*
X755512Y1157480D01*
G01X753642Y1159350D02*
X755512Y1157480D01*
G01X759252Y1176180D02*
X757382Y1174310D01*
G01X762992Y1183661D02*
X764862Y1185531D01*
G01D02*
X766732Y1187401D01*
G01Y1183661D02*
X764862Y1185531D01*
G01X766732Y1179921D02*
X768602Y1181791D01*
G01X766732Y1183661D02*
X768602Y1181791D01*
G01X766732Y1176180D02*
X768602Y1174310D01*
G01X766732Y1176180D02*
X764862Y1178051D01*
G01D02*
X766732Y1179921D01*
G01X764862Y1178051D02*
X762992Y1176180D01*
G01X751772Y1179921D02*
X753642Y1181791D01*
G01X755512Y1179921D02*
X757382Y1178051D01*
G01X759252Y1183661D02*
X757382Y1181791D01*
G01X759252Y1183661D02*
X757382Y1185531D01*
G01X759252Y1176180D02*
X761122Y1178051D01*
G01X759252Y1183661D02*
X761122Y1185531D01*
G01X751772Y1187401D02*
X753642Y1189271D01*
G01Y1181791D02*
X755512Y1179921D01*
G01X757382Y1178051D02*
X759252Y1176180D01*
G01X757382Y1181791D02*
X755512Y1179921D01*
G01X757382Y1185531D02*
X755512Y1187401D01*
G01X761122Y1178051D02*
X762992Y1176180D01*
G01X761122Y1185531D02*
X762992Y1183661D01*
G01X753642Y1189271D02*
X755512Y1187401D01*
G01X759252Y1191141D02*
X755512Y1187401D01*
G01X764862Y1189271D02*
X766732Y1191141D01*
G01X762992D02*
X764862Y1189271D01*
G01X751772Y1194881D02*
X755512D01*
G01D02*
X759252Y1191141D01*
G01D02*
X762992D01*
G01D02*
X766732D01*
G01D02*
Y1194881D01*
G01Y1191141D02*
X770472D01*
G01X776083Y1140649D02*
X774212Y1138779D01*
G01X781693Y1157480D02*
X783563Y1155610D01*
G01X781693Y1157480D02*
X779823Y1155610D01*
G01X777953Y1157480D02*
X776083Y1155610D01*
G01X781693Y1149999D02*
X783563Y1148129D01*
G01X777953Y1149999D02*
X779823Y1148129D01*
G01X774212Y1146259D02*
X772342Y1144389D01*
G01X777953Y1142519D02*
X776083Y1140649D01*
G01X774212Y1146259D02*
X776083Y1144389D01*
G01X781693Y1142519D02*
X783563Y1140649D01*
G01X781693Y1142519D02*
X779823Y1140649D01*
G01X774212Y1146259D02*
X776083Y1148129D01*
G01X777953Y1149999D02*
X776083Y1151869D01*
G01X774212Y1153740D02*
X772342Y1151869D01*
G01X768602Y1144389D02*
X770472Y1146259D01*
G01X768602Y1151869D02*
X770472Y1153740D01*
G01X776083Y1148129D02*
X777953Y1149999D01*
G01X776083Y1151869D02*
X774212Y1153740D01*
G01X772342Y1151869D02*
X770472Y1153740D01*
G01X776083Y1155610D02*
X774212Y1153740D01*
G01X772342Y1144389D02*
X770472Y1146259D01*
G01X776083Y1144389D02*
X777953Y1142519D01*
G01X779823Y1155610D02*
X777953Y1157480D01*
G01X779823Y1148129D02*
X781693Y1149999D01*
G01X779823Y1140649D02*
X777953Y1142519D01*
G01Y1157480D02*
X776083Y1159350D01*
G01X774212Y1161220D02*
X772342Y1159350D01*
G01X768602D02*
X770472Y1161220D01*
G01X781693Y1172440D02*
X783563Y1170570D01*
G01X781693Y1164960D02*
X783563Y1166830D01*
G01X774212Y1168700D02*
X776083Y1166830D01*
G01X774212Y1168700D02*
X776083Y1170570D01*
G01X774212Y1168700D02*
X772342Y1166830D01*
G01X777953Y1164960D02*
X779823Y1166830D01*
G01X777953Y1172440D02*
X779823Y1170570D01*
G01X768602Y1166830D02*
X770472Y1168700D01*
G01X776083Y1166830D02*
X777953Y1164960D01*
G01X776083Y1170570D02*
X777953Y1172440D01*
G01X772342Y1166830D02*
X770472Y1168700D01*
G01X776083Y1159350D02*
X774212Y1161220D01*
G01X772342Y1159350D02*
X770472Y1161220D01*
G01X779823Y1166830D02*
X781693Y1164960D01*
G01X779823Y1170570D02*
X781693Y1172440D01*
G01X776083Y1174310D02*
X777953Y1172440D01*
G01X781693Y1179921D02*
X783563Y1178051D01*
G01X781693Y1187401D02*
X783563Y1185531D01*
G01X774212Y1176180D02*
X776083Y1174310D01*
G01X770472Y1176180D02*
X772342Y1174310D01*
G01X774212Y1176180D02*
X776083Y1178051D01*
G01X774212Y1183661D02*
X776083Y1181791D01*
G01X777953Y1187401D02*
X776083Y1185531D01*
G01X770472Y1183661D02*
X772342Y1181791D01*
G01X777953Y1187401D02*
X779823Y1185531D01*
G01X777953Y1179921D02*
X779823Y1178051D01*
G01X768602Y1181791D02*
X770472Y1183661D01*
G01X768602Y1174310D02*
X770472Y1176180D01*
G01X772342Y1174310D02*
X774212Y1176180D01*
G01X776083Y1178051D02*
X777953Y1179921D01*
G01X776083Y1181791D02*
X777953Y1179921D01*
G01X776083Y1185531D02*
X774212Y1183661D01*
G01X772342Y1181791D02*
X774212Y1183661D01*
G01X779823Y1185531D02*
X781693Y1187401D01*
G01X779823Y1178051D02*
X781693Y1179921D01*
G01X772342Y1189271D02*
X774212Y1191141D01*
G01X770472D02*
X772342Y1189271D01*
G01X781693Y1194881D02*
X783503Y1193071D01*
Y1193011D01*
G01X777953Y1194881D02*
X776083Y1196751D01*
G01X777953Y1194881D02*
X776083Y1193011D01*
G01X777953Y1194881D02*
X779823Y1193011D01*
G01X776083D02*
X774212Y1191141D01*
G01X779823Y1193011D02*
X781693Y1194881D01*
G01X770472Y1191141D02*
X774212D01*
G01X855017Y411969D02*
X857298Y409688D01*
Y408038D01*
G01X849591Y411388D02*
Y409496D01*
X853608Y405479D01*
X854739D01*
G01X853549Y414760D02*
Y413437D01*
X855017Y411969D01*
G01X853549Y418760D02*
Y414760D01*
G01X850399D02*
Y412196D01*
X849591Y411388D01*
G01X1059251Y1078936D02*
X1061121Y1080806D01*
G01X1059251Y1086417D02*
X1057381Y1084547D01*
G01X1059251Y1093897D02*
X1057381Y1092027D01*
G01X1059251Y1097637D02*
X1057381Y1095767D01*
G01Y1103247D02*
X1059251Y1105117D01*
G01Y1120078D02*
X1057381Y1118208D01*
G01X1059251Y1112598D02*
X1057381Y1110728D01*
G01X1059251Y1135039D02*
X1057381Y1133169D01*
G01X1059251Y1127558D02*
X1057381Y1125688D01*
G01X1059251Y1142519D02*
X1057381Y1140649D01*
G01X1059251Y1153740D02*
X1057381Y1151870D01*
G01X1059251Y1146259D02*
X1057381Y1144389D01*
G01X1061122Y1166830D02*
X1059251Y1168700D01*
G01Y1161220D02*
X1057381Y1159350D01*
G01X1061120Y1174310D02*
X1059251Y1176179D01*
Y1176180D01*
G01X1062991Y1075196D02*
X1064861Y1077066D01*
G01X1070472Y1075196D02*
X1068602Y1073326D01*
G01X1072342Y1088287D02*
X1074212Y1090157D01*
G01X1072342Y1084547D02*
X1074212Y1086417D01*
G01X1072342Y1080807D02*
X1074212Y1082677D01*
G01X1066732Y1090157D02*
X1064862Y1088287D01*
G01X1070472Y1090157D02*
X1068602Y1088287D01*
G01X1062991Y1086417D02*
X1061121Y1084547D01*
G01X1066732Y1086417D02*
X1064862Y1084547D01*
G01X1066732Y1082677D02*
X1064862Y1080807D01*
G01X1062991Y1078936D02*
X1061121Y1077066D01*
G01X1070472Y1078936D02*
X1068602Y1077066D01*
G01X1072342Y1099507D02*
X1074212Y1101377D01*
G01X1072342Y1106988D02*
X1074212Y1108858D01*
G01X1072342Y1103247D02*
X1074212Y1105117D01*
G01X1070472Y1093897D02*
X1068602Y1092027D01*
G01X1062991Y1093897D02*
X1061121Y1092027D01*
G01X1062991Y1097637D02*
X1061121Y1095767D01*
G01X1070472Y1097637D02*
X1068602Y1095767D01*
G01X1066732Y1108858D02*
X1064862Y1106988D01*
G01X1070472Y1108858D02*
X1068602Y1106988D01*
G01X1062991Y1105117D02*
X1061121Y1103247D01*
G01X1066732Y1105117D02*
X1064862Y1103247D01*
G01X1066732Y1101377D02*
X1064862Y1099507D01*
G01X1072342Y1121948D02*
X1074212Y1123818D01*
G01X1072342Y1118208D02*
X1074212Y1120078D01*
G01X1072342Y1114468D02*
X1074212Y1116338D01*
G01X1072342Y1110728D02*
X1074212Y1112598D01*
G01X1070472Y1116338D02*
X1068602Y1114468D01*
G01X1062991Y1112598D02*
X1061121Y1110728D01*
G01X1066732Y1123818D02*
X1064862Y1121948D01*
G01X1070472Y1123818D02*
X1068602Y1121948D01*
G01X1062991Y1120078D02*
X1061121Y1118208D01*
G01X1066732Y1116338D02*
X1064862Y1114468D01*
G01X1072342Y1129429D02*
X1074212Y1131299D01*
G01X1072342Y1125688D02*
X1074212Y1127558D01*
G01X1066732Y1138779D02*
X1064862Y1136909D01*
G01X1062991Y1135039D02*
X1061121Y1133169D01*
G01X1066732Y1131299D02*
X1064862Y1129429D01*
G01X1070472Y1131299D02*
X1068602Y1129429D01*
G01X1062991Y1127558D02*
X1061121Y1125688D01*
G01X1074212Y1135039D02*
X1076082Y1133169D01*
G01X1072342Y1140649D02*
X1074212Y1142519D01*
G01X1072342Y1155610D02*
X1074212Y1157480D01*
G01X1072342Y1151869D02*
X1074212Y1149999D01*
G01X1070472Y1142519D02*
X1068602Y1140649D01*
G01X1066732Y1142519D02*
X1064862Y1140649D01*
G01X1062991Y1142519D02*
X1061121Y1140649D01*
G01X1066732Y1157480D02*
X1064862Y1155610D01*
G01X1070472Y1157480D02*
X1068602Y1155610D01*
G01X1062991Y1153740D02*
X1061121Y1151870D01*
G01X1066732Y1153740D02*
X1064862Y1151870D01*
G01X1066732Y1149999D02*
X1064862Y1148129D01*
G01X1070472Y1149999D02*
X1068602Y1151869D01*
G01X1062991Y1146259D02*
X1061121Y1144389D01*
G01X1066732Y1146259D02*
X1064862Y1144389D01*
G01X1072342Y1174310D02*
X1074212Y1172440D01*
G01X1072342Y1166830D02*
X1070472Y1164960D01*
G01X1072342Y1174310D02*
X1070472Y1172440D01*
G01X1072342Y1166830D02*
X1074212Y1164960D01*
G01X1070472Y1172440D02*
X1068602Y1174310D01*
G01X1064861D02*
X1066732Y1172440D01*
G01X1062991Y1168700D02*
X1064861Y1170570D01*
G01X1066732Y1168700D02*
X1068602Y1170570D01*
G01X1064861Y1166830D02*
X1066732Y1164960D01*
G01X1068602Y1166830D02*
X1070472Y1164960D01*
G01X1062991Y1161220D02*
X1061121Y1159350D01*
G01X1066732Y1161220D02*
X1064862Y1159350D01*
G01X1068602Y1174310D02*
X1066732Y1172440D01*
G01X1076082Y1174310D02*
X1074212Y1172440D01*
G01X1072342Y1181791D02*
X1070472Y1179921D01*
G01X1072342Y1181791D02*
X1074212Y1179921D01*
G01X1066732Y1176180D02*
X1064861Y1174310D01*
G01X1066732Y1179921D02*
X1064861Y1181791D01*
G01X1068602D02*
X1066732Y1179921D01*
G01X1062991Y1176180D02*
X1061120Y1174310D01*
G01X1064861D02*
X1062991Y1176180D01*
G01X1070472Y1179921D02*
X1068602Y1181791D01*
G01Y1174310D02*
X1066732Y1176180D01*
G01X1062991D02*
X1064861Y1178051D01*
G01D02*
X1066732Y1179921D01*
G01X1064861Y1178051D02*
X1066732Y1176180D01*
G01X1076082Y1181791D02*
X1074212Y1179921D01*
G01X1076082Y1178051D02*
X1074212Y1179921D01*
G01X1077952Y1075196D02*
X1076082Y1073326D01*
G01X1085432Y1075196D02*
X1083562Y1073326D01*
G01Y1077066D02*
X1085432Y1075196D01*
G01X1077952Y1078936D02*
X1076082Y1077066D01*
G01X1077952Y1090157D02*
X1076082Y1088287D01*
G01X1081692Y1086417D02*
X1079822Y1084547D01*
G01X1085432Y1078936D02*
X1083562Y1077066D01*
G01X1085432Y1090157D02*
X1083562Y1088287D01*
G01X1081692Y1090157D02*
X1079822Y1088287D01*
G01X1081692Y1082677D02*
X1079822Y1080807D01*
G01X1083562Y1092027D02*
X1085432Y1090157D01*
G01X1083562Y1088287D02*
X1081692Y1086417D01*
G01Y1101377D02*
X1079822Y1099507D01*
G01X1077952Y1093897D02*
X1076082Y1092027D01*
G01X1077952Y1097637D02*
X1076082Y1095767D01*
G01X1077952Y1108858D02*
X1076082Y1106988D01*
G01X1085432Y1097637D02*
X1083562Y1099507D01*
G01X1085432Y1093897D02*
X1083562Y1092027D01*
G01X1085432Y1093897D02*
X1083562Y1095767D01*
G01X1081692Y1108858D02*
X1079822Y1106988D01*
G01X1085432Y1108858D02*
X1083562Y1106988D01*
G01X1081692Y1105117D02*
X1079822Y1103247D01*
G01X1083562Y1095767D02*
X1085432Y1097637D01*
G01X1077952Y1123818D02*
X1076082Y1125688D01*
G01X1077952Y1116338D02*
X1076082Y1114468D01*
G01X1091043Y1110728D02*
X1092913Y1112598D01*
G01X1081692Y1123818D02*
X1083562Y1121948D01*
G01X1085432Y1120078D02*
X1083562Y1118208D01*
G01X1089172Y1120078D02*
X1087302Y1118208D01*
G01X1081692Y1116338D02*
X1079822Y1114468D01*
G01X1085432Y1112598D02*
X1083562Y1110728D01*
G01X1089172Y1112598D02*
X1087302Y1110728D01*
G01X1092913Y1123818D02*
X1091043Y1121948D01*
G01X1092913Y1120078D02*
X1091043Y1118208D01*
G01X1092913Y1116338D02*
X1091043Y1114468D01*
G01X1077952Y1131299D02*
X1076082Y1129429D01*
G01X1092913Y1135039D02*
X1091043Y1133169D01*
G01X1092913Y1127558D02*
X1091043Y1125688D01*
G01X1085432Y1135039D02*
X1083562Y1136909D01*
G01X1089172Y1135039D02*
X1087302Y1136909D01*
G01X1081692Y1131299D02*
X1079822Y1129429D01*
G01X1085432Y1127558D02*
X1083562Y1129428D01*
G01X1089172Y1127558D02*
X1087302Y1129428D01*
G01X1092913Y1138779D02*
X1091043Y1136909D01*
G01X1092913Y1131299D02*
X1091043Y1129429D01*
G01X1077952Y1146259D02*
X1076082Y1144389D01*
G01X1077952Y1149999D02*
X1076082Y1148129D01*
G01X1077952Y1153740D02*
X1076082Y1151870D01*
G01X1077952Y1157480D02*
X1076082Y1155610D01*
G01X1077952Y1142519D02*
X1076082Y1140649D01*
G01X1089172Y1142519D02*
X1087302Y1140649D01*
G01X1085432Y1142519D02*
X1083562Y1140649D01*
G01X1081692Y1142519D02*
X1079822Y1140649D01*
G01X1092913Y1142519D02*
X1091043Y1140649D01*
G01X1089172Y1153740D02*
X1087302Y1151870D01*
G01X1089172Y1157480D02*
X1087302Y1155610D01*
G01X1089172Y1149999D02*
X1087302Y1148129D01*
G01X1085432Y1146259D02*
X1083562Y1144389D01*
G01X1089172Y1146259D02*
X1087302Y1144389D01*
G01X1092913Y1146259D02*
X1091043Y1144389D01*
G01X1092913Y1149999D02*
X1091043Y1148129D01*
G01X1092913Y1153740D02*
X1091043Y1151870D01*
G01X1077952Y1161220D02*
X1076082Y1159350D01*
G01X1077952Y1172440D02*
X1076082Y1174310D01*
G01X1089172Y1168700D02*
X1087302Y1170570D01*
G01X1089172Y1164960D02*
X1087302Y1166830D01*
G01X1089172Y1161220D02*
X1087302Y1159350D01*
G01X1079822Y1170570D02*
X1077952Y1168700D01*
G01X1079822Y1166830D02*
X1077952Y1164960D01*
G01X1089172Y1168700D02*
X1091043Y1170570D01*
G01X1077952Y1172440D02*
X1079822Y1174310D01*
G01X1087302Y1170570D02*
X1089172Y1172440D01*
G01X1087302Y1166830D02*
X1089172Y1168700D01*
G01X1091043Y1170570D02*
X1092913Y1168700D01*
G01X1087302Y1174310D02*
X1089172Y1172440D01*
G01X1092913Y1161220D02*
X1091043Y1159350D01*
G01X1092913Y1164960D02*
X1091043Y1166830D01*
G01X1079822Y1178050D02*
X1077952Y1176180D01*
G01X1081692Y1179921D02*
X1083562Y1181791D01*
G01D02*
X1085432Y1179921D01*
G01D02*
X1087302Y1181791D01*
G01D02*
X1089172Y1179921D01*
G01D02*
X1087302Y1178051D01*
G01D02*
X1089172Y1176180D01*
G01X1087302Y1178051D02*
X1085432Y1179921D01*
G01X1077952D02*
X1076082Y1181791D01*
G01X1077952Y1176180D02*
X1076082Y1178051D01*
G01X1089172Y1176180D02*
X1087302Y1174310D01*
G01X1076082D02*
X1077952Y1176180D01*
G01X1076082Y1178051D02*
X1077952Y1179921D01*
G01X1079822Y1174310D02*
X1077952Y1176180D01*
G01X1081692Y1179921D02*
X1077952D01*
G01X1091043Y1185531D02*
X1092913Y1183661D01*
G01Y1179921D02*
X1091043Y1181791D01*
G01X1092913Y1176180D02*
X1091043Y1178051D01*
G01X1092913Y1176180D02*
X1091043Y1174310D01*
G01Y1178051D02*
X1092913Y1179921D01*
G01X1091043Y1174310D02*
X1092913Y1172440D01*
G01X1094783Y1110728D02*
X1096653Y1112598D01*
G01Y1123818D02*
X1094783Y1121948D01*
G01X1100393Y1123818D02*
X1098523Y1121948D01*
G01X1104133Y1123818D02*
X1102263Y1121948D01*
G01X1107873Y1123818D02*
X1106003Y1121948D01*
G01X1096653Y1120078D02*
X1094783Y1118208D01*
G01X1100393Y1120078D02*
X1098523Y1118208D01*
G01X1104133Y1120078D02*
X1102263Y1118208D01*
G01X1107873Y1120078D02*
X1106003Y1118208D01*
G01X1096653Y1116338D02*
X1094783Y1114468D01*
G01X1096653Y1138779D02*
X1094783Y1136909D01*
G01X1104133Y1138779D02*
X1102263Y1136909D01*
G01X1096653Y1135039D02*
X1094783Y1133169D01*
G01X1100393Y1135039D02*
X1098523Y1133169D01*
G01X1104133Y1135039D02*
X1102263Y1133169D01*
G01X1096653Y1131299D02*
X1094783Y1129429D01*
G01X1100393Y1131299D02*
X1098523Y1129429D01*
G01X1104133Y1131299D02*
X1102263Y1129429D01*
G01X1096653Y1127558D02*
X1094783Y1125688D01*
G01X1100393Y1127558D02*
X1098523Y1125688D01*
G01X1104133Y1127558D02*
X1102263Y1125688D01*
G01X1107873Y1127558D02*
X1106003Y1125688D01*
G01X1094783Y1133169D02*
X1092913Y1135039D01*
G01X1107873Y1138779D02*
X1106003Y1136909D01*
G01X1096653Y1153740D02*
X1094783Y1151870D01*
G01X1096653Y1146259D02*
X1094783Y1144389D01*
G01X1104133Y1146259D02*
X1102263Y1144389D01*
G01X1107873Y1149999D02*
X1109743Y1151869D01*
G01X1107873Y1157480D02*
X1106003Y1155610D01*
G01X1096653Y1149999D02*
X1094783Y1148129D01*
G01X1096653Y1157480D02*
X1094783Y1155610D01*
G01X1096653Y1142519D02*
X1094783Y1140649D01*
G01X1104133Y1142519D02*
X1102263Y1140649D01*
G01X1100393Y1142519D02*
X1098523Y1140649D01*
G01X1107873Y1149999D02*
X1106003Y1148129D01*
G01X1102263Y1151870D02*
X1104133Y1153740D01*
G01X1106003Y1155610D02*
X1104133Y1153740D01*
G01X1100393Y1149999D02*
X1098523Y1148129D01*
G01X1100393Y1157480D02*
X1098523Y1155610D01*
G01X1107873Y1146259D02*
X1106003Y1144389D01*
G01X1107873Y1153740D02*
X1106003Y1151869D01*
G01X1107873Y1153740D02*
X1109743Y1155610D01*
G01X1107873Y1146259D02*
X1109743Y1148129D01*
G01X1100393Y1146259D02*
X1098523Y1144389D01*
G01X1100393Y1153740D02*
X1098523Y1151870D01*
G01X1104133Y1149999D02*
X1102263Y1148129D01*
G01X1096653Y1172440D02*
X1094783Y1174310D01*
G01X1096653Y1172440D02*
X1094783Y1170570D01*
G01D02*
X1096653Y1168700D01*
G01X1094783Y1170570D02*
X1092913Y1168700D01*
G01D02*
X1094783Y1166830D01*
G01D02*
X1096653Y1164960D01*
G01X1094783Y1166830D02*
X1096653Y1168700D01*
G01X1104133D02*
X1102263Y1170570D01*
G01X1096653Y1161220D02*
X1094783Y1159350D01*
G01X1104133Y1161220D02*
X1102263Y1159350D01*
G01X1107873Y1172440D02*
X1109743Y1170570D01*
G01X1107873Y1157480D02*
X1109743Y1159350D01*
G01X1104133Y1168700D02*
X1106003Y1166830D01*
G01X1107873Y1172440D02*
X1106003Y1174310D01*
G01X1102263Y1170570D02*
X1100393Y1172440D01*
G01X1094783Y1159350D02*
X1092913Y1157480D01*
G01X1106003Y1166830D02*
X1107873Y1164960D01*
G01X1100393D02*
X1096653Y1168700D01*
G01Y1172440D02*
X1098523Y1174310D01*
G01D02*
X1100393Y1172440D01*
G01X1107873Y1168700D02*
X1106003Y1170570D01*
G01X1107873Y1161220D02*
X1106003Y1159350D01*
G01X1107873Y1168700D02*
X1109743Y1166830D01*
G01X1102263D02*
X1104133Y1164960D01*
G01Y1172440D02*
X1102263Y1174310D01*
G01X1100393Y1161220D02*
X1098523Y1159350D01*
G01Y1170570D02*
X1100393Y1168700D01*
G01X1109743Y1189271D02*
X1107873Y1187401D01*
G01X1096653Y1183661D02*
X1094783Y1181791D01*
G01D02*
X1096653Y1179921D01*
G01X1104133Y1183661D02*
X1102263Y1185531D01*
G01D02*
X1100393Y1187401D01*
G01X1102263Y1185531D02*
X1104133Y1187401D01*
G01X1096653Y1191141D02*
X1098523Y1189271D01*
G01D02*
X1100393Y1187401D01*
G01X1098523Y1189271D02*
X1100393Y1191141D01*
G01X1098523Y1189271D02*
X1096653Y1187401D01*
G01X1100393Y1179921D02*
X1102263Y1178051D01*
G01X1096653Y1176180D02*
X1094783Y1178051D01*
G01X1107873Y1187401D02*
X1109743Y1185531D01*
G01X1107873Y1179921D02*
X1106003Y1181791D01*
G01X1107873Y1179921D02*
X1109743Y1178051D01*
G01X1102263D02*
X1104133Y1176180D01*
G01X1094783Y1174310D02*
X1096653Y1176180D01*
G01X1094783Y1178051D02*
X1096653Y1179921D01*
G01X1106003Y1181791D02*
X1104133Y1183661D01*
G01X1106003Y1174310D02*
X1104133Y1176180D01*
G01X1098523Y1174310D02*
X1096653Y1176180D01*
G01X1098523Y1181791D02*
X1096653Y1183661D01*
G01Y1179921D02*
X1098523Y1181791D01*
G01D02*
X1100393Y1179921D01*
G01X1107873Y1176180D02*
X1106003Y1178051D01*
G01Y1185531D02*
X1107873Y1183661D01*
G01Y1176180D02*
X1109743Y1174310D01*
G01X1107873Y1183661D02*
X1109743Y1181791D01*
G01X1100393Y1176180D02*
X1098523Y1178051D01*
G01X1104133Y1179921D02*
X1102263Y1181791D01*
G01X1100393Y1194881D02*
X1102263Y1193011D01*
G01D02*
X1104133Y1194881D01*
G01Y1191141D02*
X1102263Y1193011D01*
G01D02*
X1100393Y1191141D01*
G01X1096653Y1206102D02*
X1098523Y1204232D01*
G01D02*
X1100393Y1206102D01*
G01Y1202362D02*
X1098523Y1204232D01*
G01D02*
X1096653Y1202362D01*
G01X1100393Y1206102D02*
X1102263Y1204232D01*
G01D02*
X1104133Y1206102D01*
G01Y1202362D02*
X1102263Y1204232D01*
G01D02*
X1100393Y1202362D01*
G01X1107873D02*
X1109743Y1204232D01*
G01X1107873Y1202362D02*
X1106003Y1204232D01*
G01D02*
X1107873Y1206102D01*
G01X1104133Y1202362D02*
X1106003Y1204232D01*
G01D02*
X1104133Y1206102D01*
G01X1096653Y1202362D02*
X1098523Y1200491D01*
G01D02*
X1100393Y1202362D01*
G01Y1198621D02*
X1098523Y1200491D01*
G01D02*
X1096653Y1198621D01*
G01X1100393Y1202362D02*
X1102263Y1200491D01*
G01D02*
X1104133Y1202362D01*
G01Y1198621D02*
X1102263Y1200491D01*
G01D02*
X1100393Y1198621D01*
G01D02*
X1098523Y1196751D01*
G01D02*
X1096653Y1198621D01*
G01Y1194881D02*
X1098523Y1196751D01*
G01D02*
X1100393Y1194881D01*
G01X1106003Y1200491D02*
X1104133Y1198621D01*
G01D02*
X1106003Y1196751D01*
G01X1104133Y1198621D02*
X1102263Y1196751D01*
G01D02*
X1100393Y1198621D01*
G01X1102263Y1196751D02*
X1104133Y1194881D01*
G01X1100393D02*
X1102263Y1196751D01*
G01X1096653Y1194881D02*
X1098523Y1193011D01*
G01D02*
X1100393Y1194881D01*
G01Y1191141D02*
X1098523Y1193011D01*
G01D02*
X1096653Y1191141D01*
G01X1107873D02*
X1106003Y1193011D01*
G01X1107873Y1213582D02*
X1109743Y1211712D01*
G01X1107873Y1209842D02*
X1109743Y1211712D01*
G01Y1207972D02*
X1107873Y1209842D01*
G01Y1206102D02*
X1109743Y1207972D01*
G01X1107873Y1206102D02*
X1109743Y1204232D01*
G01X1096653Y1209842D02*
X1098523Y1207972D01*
G01D02*
X1096653Y1206102D01*
G01X1100393Y1209842D02*
X1098523Y1207972D01*
G01D02*
X1100393Y1206102D01*
G01X1104133D02*
X1102263Y1207972D01*
G01D02*
X1104133Y1209842D01*
G01X1100393Y1206102D02*
X1102263Y1207972D01*
G01D02*
X1100393Y1209842D01*
G01X1104133D02*
X1102263Y1211712D01*
G01X1096653Y1217322D02*
X1098523Y1219192D01*
G01X1096653Y1209842D02*
X1098523Y1211712D01*
G01D02*
X1100393Y1209842D01*
G01X1096653Y1213582D02*
X1098523Y1211712D01*
G01X1102263D02*
X1100393Y1209842D01*
G01X1102263Y1211712D02*
X1100393Y1213582D01*
G01X1098523Y1211712D02*
X1100393Y1213582D01*
G01X1106003Y1219192D02*
X1107873Y1217322D01*
G01X1104133Y1209842D02*
X1106003Y1207972D01*
G01D02*
X1104133Y1206102D01*
G01X1107873Y1209842D02*
X1106003Y1207972D01*
G01X1107873Y1206102D02*
X1106003Y1207972D01*
G01X1107873Y1209842D02*
X1106003Y1211712D01*
G01D02*
X1104133Y1209842D01*
G01X1106003Y1211712D02*
X1107873Y1213582D01*
G01X1122834Y1120078D02*
X1120964Y1121948D01*
G01X1119094Y1120078D02*
X1117224Y1118208D01*
G01X1120964Y1121948D02*
X1119094Y1120078D01*
G01X1120964Y1121948D02*
X1119094Y1123818D01*
G01X1111613D02*
X1109743Y1121948D01*
G01X1115354Y1123818D02*
X1113484Y1121948D01*
G01X1111613Y1120078D02*
X1109743Y1118208D01*
G01X1115354Y1120078D02*
X1113484Y1118208D01*
G01X1120964D02*
X1122834Y1120078D01*
G01X1120964Y1125688D02*
X1119094Y1123818D01*
G01X1124704Y1121948D02*
X1122834Y1123818D01*
G01Y1120078D02*
X1124704Y1121948D01*
G01X1122834Y1120078D02*
X1124704Y1118208D01*
G01X1122834Y1123818D02*
X1124704Y1125688D01*
G01X1122834Y1123818D02*
X1120964Y1125688D01*
G01X1119094Y1123818D02*
X1117224Y1121948D01*
G01X1122834Y1123818D02*
X1120964Y1121948D01*
G01X1124704Y1125688D02*
X1122834Y1127558D01*
G01X1119094D02*
X1117224Y1125688D01*
G01X1122834Y1127558D02*
X1120964Y1125688D01*
G01X1111613Y1127558D02*
X1109743Y1125688D01*
G01X1122834Y1135039D02*
X1124704Y1133169D01*
G01X1111613Y1135039D02*
X1109743Y1136909D01*
G01X1111613Y1135039D02*
X1113484Y1133169D01*
G01X1115354Y1135039D02*
X1117224Y1133169D01*
G01X1119094Y1135039D02*
X1120964Y1133169D01*
G01X1115354Y1127558D02*
X1113484Y1125688D01*
G01X1111613Y1127558D02*
X1109743Y1129429D01*
G01X1111613Y1131299D02*
X1109743Y1133169D01*
G01X1120964Y1125688D02*
X1119094Y1127558D01*
G01X1109743Y1136909D02*
X1111613Y1138779D01*
G01X1113484Y1133169D02*
X1115354Y1135039D01*
G01X1117224Y1133169D02*
X1119094Y1135039D01*
G01X1120964Y1133169D02*
X1122834Y1135039D01*
G01X1109743Y1129429D02*
X1111613Y1131299D01*
G01X1109743Y1133169D02*
X1111613Y1135039D01*
G01X1117224Y1129429D02*
X1119094Y1131299D01*
G01X1113484Y1129429D02*
X1115354Y1131299D01*
G01X1120964Y1129429D02*
X1122834Y1131299D01*
G01X1115354Y1138779D02*
X1113484Y1136909D01*
G01X1122834Y1138779D02*
X1124704Y1136909D01*
G01X1115354Y1138779D02*
X1117224Y1136909D01*
G01X1119094Y1138779D02*
X1120964Y1136909D01*
G01X1117224D02*
X1119094Y1138779D01*
G01X1120964Y1136909D02*
X1122834Y1138779D01*
G01X1115354Y1142519D02*
X1113484Y1140649D01*
G01X1122834Y1142519D02*
X1124704Y1140649D01*
G01X1111613Y1146259D02*
X1109743Y1144389D01*
G01X1122834Y1149999D02*
X1124704Y1148129D01*
G01X1119094Y1149999D02*
X1120964Y1148129D01*
G01X1115354Y1149999D02*
X1113484Y1148129D01*
G01X1115354Y1149999D02*
X1117224Y1148129D01*
G01X1122834Y1157480D02*
X1120964Y1155610D01*
G01X1119094Y1142519D02*
X1120964Y1140649D01*
G01X1115354Y1142519D02*
X1117224Y1140649D01*
G01X1115354Y1157480D02*
X1113484Y1155610D01*
G01D02*
X1111613Y1153740D01*
G01X1109743Y1151869D02*
X1111613Y1153740D01*
G01X1120964Y1140649D02*
X1122834Y1142519D01*
G01X1117224Y1140649D02*
X1119094Y1142519D01*
G01X1120964Y1148129D02*
X1122834Y1149999D01*
G01X1113484Y1148129D02*
X1111613Y1146259D01*
G01X1117224Y1148129D02*
X1119094Y1149999D01*
G01X1115354Y1146259D02*
X1113484Y1144389D01*
G01X1122834Y1146259D02*
X1124704Y1144389D01*
G01X1115354Y1146259D02*
X1117224Y1144389D01*
G01X1119094Y1146259D02*
X1120964Y1144389D01*
G01X1113484Y1151870D02*
X1115354Y1153740D01*
G01X1117224Y1151870D02*
X1119094Y1153740D01*
G01X1120964Y1151870D02*
X1122834Y1153740D01*
G01X1117224Y1144389D02*
X1119094Y1146259D01*
G01X1120964Y1144389D02*
X1122834Y1146259D01*
G01X1119094Y1157480D02*
X1117224Y1155610D01*
G01X1109743D02*
X1111613Y1157480D01*
G01X1109743Y1148129D02*
X1111613Y1149999D01*
G01X1122834Y1172440D02*
X1120964Y1174310D01*
G01X1122834Y1172440D02*
X1124704Y1170570D01*
G01X1122834Y1157480D02*
X1124704Y1159350D01*
G01X1119094Y1161220D02*
X1117224Y1159350D01*
G01X1119094Y1168700D02*
X1117224Y1170570D01*
G01X1122834Y1164960D02*
X1120964Y1166830D01*
G01X1111613Y1168700D02*
X1113484Y1166830D01*
G01X1115354Y1172440D02*
X1113484Y1174310D01*
G01X1117224Y1170570D02*
X1115354Y1172440D01*
G01X1109743Y1170570D02*
X1111613Y1168700D01*
G01X1113484Y1166830D02*
X1115354Y1164960D01*
G01X1117224Y1159350D02*
X1115354Y1157480D01*
G01X1120964Y1166830D02*
X1119094Y1168700D01*
G01X1109743Y1159350D02*
X1111613Y1161220D01*
G01X1122834Y1168700D02*
X1120964Y1170570D01*
G01X1119094Y1172440D02*
X1117224Y1174310D01*
G01X1122834Y1168700D02*
X1124704Y1166830D01*
G01X1111613Y1157480D02*
X1113484Y1159350D01*
G01X1122834Y1161220D02*
X1120964Y1159350D01*
G01X1115354Y1168700D02*
X1117224Y1166830D01*
G01X1115354Y1168700D02*
X1113484Y1170570D01*
G01Y1159350D02*
X1115354Y1161220D01*
G01X1120964Y1159350D02*
X1119094Y1157480D01*
G01X1109743Y1166830D02*
X1111613Y1164960D01*
G01X1113484Y1170570D02*
X1111613Y1172440D01*
G01X1117224Y1166830D02*
X1119094Y1164960D01*
G01X1109743Y1174310D02*
X1111613Y1172440D01*
G01X1122834Y1187401D02*
X1124704Y1189271D01*
G01X1111613Y1191141D02*
X1109743Y1189271D01*
G01X1122834Y1179921D02*
X1124704Y1181791D01*
G01X1115354Y1187401D02*
X1113484Y1189271D01*
G01X1115354Y1187401D02*
X1117224Y1189271D01*
G01X1119094Y1187401D02*
X1120964Y1189271D01*
G01X1111613Y1183661D02*
X1113484Y1181791D01*
G01X1115354Y1179921D02*
X1117224Y1181791D01*
G01X1119094Y1179921D02*
X1120964Y1181791D01*
G01X1109743Y1189271D02*
X1111613Y1187401D01*
G01X1113484Y1189271D02*
X1111613Y1187401D01*
G01X1117224Y1189271D02*
X1119094Y1187401D01*
G01X1120964Y1189271D02*
X1122834Y1187401D01*
G01X1113484Y1181791D02*
X1115354Y1179921D01*
G01X1117224Y1181791D02*
X1119094Y1179921D01*
G01X1120964Y1181791D02*
X1122834Y1179921D01*
G01X1109743Y1178051D02*
X1111613Y1176180D01*
G01X1109743Y1185531D02*
X1111613Y1183661D01*
G01X1113484Y1174310D02*
X1111613Y1176180D01*
G01X1115354D02*
X1113484Y1178051D01*
G01X1122834Y1176180D02*
X1124704Y1178051D01*
G01X1115354Y1176180D02*
X1117224Y1178051D01*
G01X1119094Y1176180D02*
X1120964Y1178051D01*
G01X1115354Y1183661D02*
X1113484Y1185531D01*
G01X1122834Y1183661D02*
X1124704Y1185531D01*
G01X1119094Y1183661D02*
X1120964Y1185531D01*
G01X1119094Y1183661D02*
X1117224Y1185531D01*
G01Y1178051D02*
X1119094Y1176180D01*
G01X1120964Y1178051D02*
X1122834Y1176180D01*
G01X1120964Y1185531D02*
X1122834Y1183661D01*
G01X1117224Y1185531D02*
X1115354Y1183661D01*
G01X1109743Y1181791D02*
X1111613Y1179921D01*
G01Y1198621D02*
X1109743Y1200491D01*
G01X1122834Y1194881D02*
X1124704Y1196751D01*
G01X1115354Y1206102D02*
X1117224Y1204232D01*
G01D02*
X1119094Y1206102D01*
G01Y1202362D02*
X1117224Y1204232D01*
G01X1122834Y1202362D02*
X1120964Y1204232D01*
G01D02*
X1119094Y1202362D01*
G01X1122834Y1206102D02*
X1120964Y1204232D01*
G01D02*
X1119094Y1206102D01*
G01X1115354Y1202362D02*
X1113484Y1204232D01*
G01D02*
X1111613Y1202362D01*
G01Y1206102D02*
X1113484Y1204232D01*
G01D02*
X1115354Y1206102D01*
G01X1117224Y1204232D02*
X1115354Y1202362D01*
G01X1124704Y1204232D02*
X1122834Y1206102D01*
G01X1124704Y1204232D02*
X1122834Y1202362D01*
G01X1111613D02*
X1109743Y1204232D01*
G01X1111613Y1191141D02*
X1109743Y1193011D01*
G01X1111613Y1194881D02*
X1109743Y1196751D01*
G01X1115354Y1194881D02*
X1113484Y1196751D01*
G01X1115354Y1194881D02*
X1117224Y1196751D01*
G01X1119094Y1194881D02*
X1120964Y1196751D01*
G01X1109743Y1204232D02*
X1111613Y1206102D01*
G01X1109743Y1193011D02*
X1111613Y1194881D01*
G01X1109743Y1196751D02*
X1111613Y1198621D01*
G01X1113484Y1196751D02*
X1111613Y1194881D01*
G01X1117224Y1196751D02*
X1119094Y1194881D01*
G01X1120964Y1196751D02*
X1122834Y1194881D01*
G01X1117224Y1200491D02*
X1119094Y1198621D01*
G01X1120964Y1200491D02*
X1122834Y1198621D01*
G01X1113484Y1200491D02*
X1115354Y1198621D01*
G01X1117224Y1193011D02*
X1115354Y1191141D01*
G01X1120964Y1193011D02*
X1119094Y1191141D01*
G01X1115354D02*
X1113484Y1193011D01*
G01X1119094Y1191141D02*
X1117224Y1193011D01*
G01X1122834Y1191141D02*
X1120964Y1193011D01*
G01X1122834Y1191141D02*
X1124704Y1193011D01*
G01X1122834Y1209842D02*
X1120964Y1207972D01*
G01X1124704D02*
X1122834Y1209842D01*
G01X1124704Y1211712D02*
X1122834Y1209842D01*
G01Y1206102D02*
X1124704Y1207972D01*
G01X1111613Y1209842D02*
X1109743Y1207972D01*
G01X1111613Y1209842D02*
X1113484Y1207972D01*
G01D02*
X1115354Y1206102D01*
G01X1111613D02*
X1113484Y1207972D01*
G01D02*
X1115354Y1209842D01*
G01Y1206102D02*
X1117224Y1207972D01*
G01D02*
X1119094Y1206102D01*
G01X1115354Y1209842D02*
X1117224Y1207972D01*
G01D02*
X1119094Y1209842D01*
G01X1120964Y1207972D02*
X1122834Y1206102D01*
G01X1119094D02*
X1120964Y1207972D01*
G01D02*
X1119094Y1209842D01*
G01X1109743Y1211712D02*
X1111613Y1209842D01*
G01X1109743Y1207972D02*
X1111613Y1206102D01*
G01X1130314Y1116338D02*
X1132184Y1118208D01*
G01D02*
X1134054Y1120078D01*
G01X1132184Y1118208D02*
X1130314Y1120078D01*
G01X1128444Y1114468D02*
X1130314Y1116338D01*
G01X1126574Y1120078D02*
X1128444Y1118208D01*
G01D02*
X1130314Y1116338D01*
G01X1128444Y1118208D02*
X1130314Y1120078D01*
G01D02*
X1132184Y1121948D01*
G01D02*
X1134054Y1120078D01*
G01Y1123818D02*
X1132184Y1121948D01*
G01D02*
X1130314Y1123818D01*
G01X1134054Y1120078D02*
X1135924Y1121948D01*
G01D02*
X1137795Y1120078D01*
G01Y1123818D02*
X1135924Y1121948D01*
G01D02*
X1134054Y1123818D01*
G01X1137795D02*
X1135924Y1125688D01*
G01X1134054Y1120078D02*
X1135924Y1118208D01*
G01X1141535Y1120078D02*
X1139665Y1118208D01*
G01X1132184Y1125688D02*
X1130314Y1123818D01*
G01X1128444Y1125688D02*
X1130314Y1123818D01*
G01X1135924Y1125688D02*
X1134054Y1123818D01*
G01X1139665Y1125688D02*
X1137795Y1123818D01*
G01X1141535D02*
X1139665Y1121948D01*
G01D02*
X1137795Y1123818D01*
G01X1139665Y1121948D02*
X1137795Y1120078D01*
G01X1141535D02*
X1139665Y1121948D01*
G01X1126574Y1120078D02*
X1128444Y1121948D01*
G01D02*
X1130314Y1120078D01*
G01Y1123818D02*
X1128444Y1121948D01*
G01D02*
X1126574Y1123818D01*
G01D02*
X1124704Y1121948D01*
G01Y1125688D02*
X1126574Y1123818D01*
G01X1124704Y1121948D02*
X1126574Y1120078D01*
G01X1135924Y1118208D02*
X1137795Y1120078D01*
G01X1139665Y1118208D02*
X1137795Y1120078D01*
G01X1124704Y1118208D02*
X1126574Y1120078D01*
G01X1134054Y1127558D02*
X1132184Y1125688D01*
G01D02*
X1130314Y1127558D01*
G01X1126574D02*
X1128444Y1125688D01*
G01D02*
X1130314Y1127558D01*
G01X1135924Y1125688D02*
X1134054Y1127558D01*
G01X1137795D02*
X1135924Y1125688D01*
G01X1126574Y1127558D02*
X1124704Y1125688D01*
G01X1137795Y1127558D02*
X1139665Y1125688D01*
G01X1141535Y1123818D02*
X1139665Y1125688D01*
G01D02*
X1141535Y1127558D01*
G01X1137795Y1135039D02*
X1139665Y1133169D01*
G01X1134054Y1135039D02*
X1135924Y1133169D01*
G01X1134054Y1135039D02*
X1132184Y1133169D01*
G01X1130314Y1135039D02*
X1128444Y1133169D01*
G01X1135924D02*
X1137795Y1135039D01*
G01X1132184Y1133169D02*
X1130314Y1135039D01*
G01X1128444Y1133169D02*
X1126574Y1135039D01*
G01X1139665Y1133169D02*
X1141535Y1135039D01*
G01X1124704Y1133169D02*
X1126574Y1135039D01*
G01X1139665Y1129429D02*
X1141535Y1131299D01*
G01X1135924Y1129429D02*
X1137795Y1131299D01*
G01X1128444Y1129429D02*
X1130314Y1131299D01*
G01X1132184Y1129429D02*
X1134054Y1131299D01*
G01X1126574D02*
X1124704Y1129429D01*
G01X1137795Y1138779D02*
X1139665Y1136909D01*
G01X1134054Y1138779D02*
X1135924Y1136909D01*
G01X1134054Y1138779D02*
X1132184Y1136909D01*
G01X1130314Y1138779D02*
X1128444Y1136909D01*
G01X1139665D02*
X1141535Y1138779D01*
G01X1135924Y1136909D02*
X1137795Y1138779D01*
G01X1132184Y1136909D02*
X1130314Y1138779D01*
G01X1128444Y1136909D02*
X1126574Y1138779D01*
G01X1124704Y1136909D02*
X1126574Y1138779D01*
G01X1141535Y1142519D02*
X1139665Y1140649D01*
G01X1126574Y1142519D02*
X1128444Y1140649D01*
G01X1130314Y1142519D02*
X1132184Y1140649D01*
G01X1137795Y1142519D02*
X1135924Y1140649D01*
G01X1130314Y1157480D02*
X1128444Y1155610D01*
G01X1134054Y1149999D02*
X1135924Y1148129D01*
G01X1134054Y1149999D02*
X1132184Y1148129D01*
G01X1130314Y1149999D02*
X1128444Y1148129D01*
G01X1137795Y1157480D02*
X1135924Y1155610D01*
G01X1141535Y1149999D02*
X1139665Y1148129D01*
G01X1128444Y1140649D02*
X1130314Y1142519D01*
G01X1132184Y1140649D02*
X1134054Y1142519D01*
G01X1135924Y1140649D02*
X1134054Y1142519D01*
G01X1135924Y1148129D02*
X1137795Y1149999D01*
G01X1132184Y1148129D02*
X1130314Y1149999D01*
G01X1128444Y1148129D02*
X1126574Y1149999D01*
G01X1139665Y1148129D02*
X1137795Y1149999D01*
G01X1139665Y1140649D02*
X1137795Y1142519D01*
G01X1124704Y1140649D02*
X1126574Y1142519D01*
G01X1124704Y1148129D02*
X1126574Y1149999D01*
G01X1134054Y1146259D02*
X1135924Y1144389D01*
G01X1141535Y1146259D02*
X1139665Y1144389D01*
G01X1135925Y1151870D02*
X1137795Y1153740D01*
G01X1132184Y1151870D02*
X1134054Y1153740D01*
G01X1128444Y1151870D02*
X1130314Y1153740D01*
G01X1139665Y1151870D02*
X1141535Y1153740D01*
G01X1126574Y1146259D02*
X1128444Y1144389D01*
G01X1134054Y1146259D02*
X1132184Y1144389D01*
G01X1128444D02*
X1130314Y1146259D01*
G01X1135924Y1144389D02*
X1137795Y1146259D01*
G01X1132184Y1144389D02*
X1130314Y1146259D01*
G01X1139665Y1144389D02*
X1137795Y1146259D01*
G01X1124704Y1144389D02*
X1126574Y1146259D01*
G01Y1153740D02*
X1124704Y1151870D01*
G01X1134054Y1157480D02*
X1132184Y1155610D01*
G01X1141535Y1157480D02*
X1139665Y1155610D01*
G01X1126574Y1157480D02*
X1124704Y1155610D01*
G01X1134054Y1161220D02*
X1132184Y1159350D01*
G01X1141535Y1161220D02*
X1139665Y1159350D01*
G01X1137795Y1172440D02*
X1139665Y1170570D01*
G01X1134054Y1168700D02*
X1132184Y1170570D01*
G01X1137795Y1164960D02*
X1135925Y1166830D01*
G01X1130314Y1164960D02*
X1128444Y1166830D01*
G01X1137795Y1172440D02*
X1135924Y1174310D01*
G01X1130314Y1172440D02*
X1128444Y1174310D01*
G01X1139665Y1170570D02*
X1141535Y1168700D01*
G01X1139665Y1159350D02*
X1137795Y1157480D01*
G01X1132184Y1170570D02*
X1130314Y1172440D01*
G01X1135925Y1166830D02*
X1134055Y1168700D01*
X1134054D01*
G01X1128444Y1166830D02*
X1126574Y1168700D01*
G01X1132184Y1159350D02*
X1130314Y1157480D01*
G01X1124704Y1170570D02*
X1126574Y1168700D01*
G01X1124704Y1159350D02*
X1126574Y1161220D01*
G01X1134054Y1172440D02*
X1132184Y1174310D01*
G01X1130314Y1161220D02*
X1128444Y1159350D01*
G01X1137795Y1161220D02*
X1135924Y1159350D01*
G01X1137795Y1168700D02*
X1139665Y1166830D01*
G01X1137795Y1168700D02*
X1135924Y1170570D01*
G01X1126574Y1172440D02*
X1128444Y1170570D01*
G01X1134054Y1164960D02*
X1132184Y1166830D01*
G01X1139665D02*
X1141535Y1164960D01*
G01X1135924Y1170570D02*
X1134054Y1172440D01*
G01X1128444Y1170570D02*
X1130314Y1168700D01*
G01X1132184Y1166830D02*
X1130314Y1168700D01*
G01X1128444Y1159350D02*
X1126574Y1157480D01*
G01X1135924Y1159350D02*
X1134054Y1157480D01*
G01X1124704Y1166830D02*
X1126574Y1164960D01*
G01Y1172440D02*
X1124704Y1174310D01*
G01X1141535Y1179921D02*
X1139665Y1181791D01*
G01X1137795Y1187401D02*
X1139665Y1189271D01*
G01X1137795Y1179921D02*
X1135924Y1181791D01*
G01X1134054Y1179921D02*
X1132184Y1181791D01*
G01X1130314Y1179921D02*
X1128444Y1181791D01*
G01X1137795Y1187401D02*
X1135924Y1189271D01*
G01X1134054Y1187401D02*
X1132184Y1189271D01*
G01X1130314Y1187401D02*
X1128444Y1189271D01*
G01X1135924Y1181791D02*
X1134054Y1179921D01*
G01X1132184Y1181791D02*
X1130314Y1179921D01*
G01X1128444Y1181791D02*
X1126574Y1179921D01*
G01X1135924Y1189271D02*
X1134054Y1187401D01*
G01X1132184Y1189271D02*
X1130314Y1187401D01*
G01X1128444Y1189271D02*
X1126574Y1187401D01*
G01X1139665Y1181791D02*
X1137795Y1179921D01*
G01X1139665Y1189271D02*
X1141535Y1187401D01*
G01X1124704Y1189271D02*
X1126574Y1187401D01*
G01X1124704Y1181791D02*
X1126574Y1179921D01*
G01X1141535Y1176180D02*
X1139665Y1178051D01*
G01X1134054Y1176180D02*
X1135924Y1178051D01*
G01X1134054Y1176180D02*
X1132184Y1178051D01*
G01X1130314Y1176180D02*
X1128444Y1178051D01*
G01X1141535Y1183661D02*
X1139665Y1185531D01*
G01X1134054Y1183661D02*
X1132184Y1185531D01*
G01X1130314Y1183661D02*
X1128444Y1185531D01*
G01X1134054Y1183661D02*
X1135924Y1185531D01*
G01X1139665Y1178051D02*
X1137795Y1176180D01*
G01X1135924Y1178051D02*
X1137795Y1176180D01*
G01X1132184Y1178051D02*
X1130314Y1176180D01*
G01X1128444Y1178051D02*
X1126574Y1176180D01*
G01X1139665Y1185531D02*
X1137795Y1183661D01*
G01X1132184Y1185531D02*
X1130314Y1183661D01*
G01X1128444Y1185531D02*
X1126574Y1183661D01*
G01X1135924Y1185531D02*
X1137795Y1183661D01*
G01X1124704Y1178051D02*
X1126574Y1176180D01*
G01X1124704Y1185531D02*
X1126574Y1183661D01*
G01X1141535Y1172440D02*
X1139665Y1174310D01*
G01X1141535Y1206102D02*
X1139665Y1204232D01*
G01D02*
X1141535Y1202362D01*
G01X1137795Y1206102D02*
X1139665Y1204232D01*
G01D02*
X1137795Y1202362D01*
G01D02*
X1135924Y1204232D01*
G01D02*
X1134054Y1202362D01*
G01X1137795Y1206102D02*
X1135924Y1204232D01*
G01D02*
X1134054Y1206102D01*
G01Y1202362D02*
X1132184Y1204232D01*
G01D02*
X1130314Y1202362D01*
G01X1134054Y1206102D02*
X1132184Y1204232D01*
G01D02*
X1130314Y1206102D01*
G01Y1202362D02*
X1128444Y1204232D01*
G01D02*
X1126574Y1202362D01*
G01X1130314Y1206102D02*
X1128444Y1204232D01*
G01D02*
X1126574Y1206102D01*
G01Y1202362D02*
X1124704Y1204232D01*
G01X1141535Y1194881D02*
X1139665Y1196751D01*
G01X1134054Y1194881D02*
X1135924Y1196751D01*
G01X1134054Y1194881D02*
X1132184Y1196751D01*
G01X1130314Y1194881D02*
X1128444Y1196751D01*
G01X1124704Y1204232D02*
X1126574Y1206102D01*
G01X1139665Y1196751D02*
X1137795Y1194881D01*
G01X1135924Y1196751D02*
X1137795Y1194881D01*
G01X1132184Y1196751D02*
X1130314Y1194881D01*
G01X1128444Y1196751D02*
X1126574Y1194881D01*
G01X1124704Y1196751D02*
X1126574Y1194881D01*
G01Y1198621D02*
X1124704Y1200491D01*
G01X1132184D02*
X1134054Y1198621D01*
G01X1128444Y1200491D02*
X1130314Y1198621D01*
G01X1135924Y1200491D02*
X1137795Y1198621D01*
G01X1139665Y1200491D02*
X1141535Y1198621D01*
G01X1124704Y1193011D02*
X1126574Y1191141D01*
G01X1139665Y1193011D02*
X1141535Y1191141D01*
G01X1135924Y1193011D02*
X1137795Y1191141D01*
G01X1132184Y1193011D02*
X1134054Y1191141D01*
G01X1128444Y1193011D02*
X1126574Y1191141D01*
G01X1137795D02*
X1139665Y1193011D01*
G01X1134054Y1191141D02*
X1135924Y1193011D01*
G01X1130314Y1191141D02*
X1128444Y1193011D01*
G01X1130314Y1191141D02*
X1132184Y1193011D01*
G01X1141535Y1206102D02*
X1139665Y1207972D01*
G01D02*
X1141535Y1209842D01*
G01X1137795Y1206102D02*
X1139665Y1207972D01*
G01X1134054Y1206102D02*
X1135924Y1207972D01*
G01D02*
X1137795Y1206102D01*
G01Y1209842D02*
X1135924Y1207972D01*
G01X1139665D02*
X1137795Y1209842D01*
G01X1135924Y1207972D02*
X1134054Y1209842D01*
G01D02*
X1132184Y1207972D01*
G01D02*
X1130314Y1209842D01*
G01X1134054Y1206102D02*
X1132184Y1207972D01*
G01D02*
X1130314Y1206102D01*
G01Y1209842D02*
X1128444Y1207972D01*
G01D02*
X1126574Y1209842D01*
G01X1130314Y1206102D02*
X1128444Y1207972D01*
G01D02*
X1126574Y1206102D01*
G01Y1209842D02*
X1124704Y1207972D01*
G01D02*
X1126574Y1206102D01*
G01X1156495Y1123818D02*
X1158365Y1121948D01*
G01X1156495Y1123818D02*
X1158365Y1125688D01*
G01Y1121948D02*
X1156495Y1120078D01*
G01X1152755Y1123818D02*
X1154625Y1121948D01*
G01D02*
X1156495Y1123818D01*
G01Y1120078D02*
X1154625Y1121948D01*
G01X1150885D02*
X1152755Y1120078D01*
G01X1149015Y1123818D02*
X1150885Y1121948D01*
G01X1152755Y1123818D02*
X1150885Y1125688D01*
G01X1154625Y1121948D02*
X1152755Y1120078D01*
G01X1156495Y1123818D02*
X1154625Y1125688D01*
G01X1150885D02*
X1149015Y1123818D01*
G01X1141535D02*
X1143405Y1125688D01*
G01X1145275Y1116338D02*
X1143405Y1118208D01*
G01D02*
X1145275Y1120078D01*
G01X1143405Y1118208D02*
X1141535Y1120078D01*
G01X1145275D02*
X1143405Y1121948D01*
G01D02*
X1141535Y1120078D01*
G01X1145275Y1123818D02*
X1143405Y1121948D01*
G01D02*
X1141535Y1123818D01*
G01X1143405Y1125688D02*
X1145275Y1123818D01*
G01Y1116338D02*
X1143405Y1114468D01*
G01X1154625Y1125688D02*
X1152755Y1123818D01*
G01X1143405Y1114468D02*
X1145275Y1112598D01*
G01X1156495Y1127558D02*
X1158365Y1125688D01*
G01X1141535Y1127558D02*
X1143405Y1125688D01*
G01X1156495Y1135039D02*
X1158365Y1133169D01*
G01X1149015Y1135039D02*
X1150590Y1133464D01*
X1150885D01*
G01X1152755Y1135039D02*
X1154625Y1133169D01*
G01X1141535Y1135039D02*
Y1134645D01*
X1143503Y1132677D01*
G01X1150885Y1125688D02*
X1149015Y1127558D01*
G01X1143405Y1125688D02*
X1145275Y1127558D01*
G01X1156495D02*
X1154625Y1125688D01*
G01D02*
X1152755Y1127558D01*
G01X1150885Y1125688D02*
X1152755Y1127558D01*
G01X1150885Y1133464D02*
X1152460Y1135039D01*
X1152755D01*
G01X1154625Y1133169D02*
X1156495Y1135039D01*
G01X1143503Y1132677D02*
X1145275Y1134448D01*
Y1135039D01*
G01X1158365Y1129429D02*
X1156495Y1131299D01*
G01X1143405Y1129429D02*
X1145275Y1131299D01*
G01X1150885Y1129429D02*
X1149015Y1131299D01*
G01X1154625Y1129429D02*
X1152755Y1131299D01*
G01X1141535Y1138779D02*
X1143405Y1136909D01*
G01X1156495Y1138779D02*
X1158365Y1136909D01*
G01X1156495Y1138779D02*
X1154625Y1136909D01*
G01X1149015Y1138779D02*
X1150885Y1136909D01*
G01X1143405D02*
X1145275Y1138779D01*
G01X1154625Y1136909D02*
X1152755Y1138779D01*
G01X1150885Y1136909D02*
X1152755Y1138779D01*
G01X1156495Y1149999D02*
X1158365Y1148129D01*
G01X1156495Y1142519D02*
X1158365Y1140649D01*
G01X1152755Y1157480D02*
X1154625Y1155610D01*
G01X1141535Y1142519D02*
X1143405Y1140649D01*
G01X1149015Y1142519D02*
X1150885Y1140649D01*
G01X1156495Y1142519D02*
X1154625Y1140649D01*
G01X1145275Y1157480D02*
X1143405Y1155610D01*
G01X1141535Y1149999D02*
X1143405Y1148129D01*
G01X1149015Y1149999D02*
X1150885Y1148129D01*
G01X1152755Y1149999D02*
X1154625Y1148129D01*
G01X1143405D02*
X1145275Y1149999D01*
G01X1150885Y1148129D02*
X1152755Y1149999D01*
G01X1154625Y1148129D02*
X1156495Y1149999D01*
G01X1143405Y1140649D02*
X1145275Y1142519D01*
G01X1150885Y1140649D02*
X1152755Y1142519D01*
G01X1154625Y1140649D02*
X1152755Y1142519D01*
G01X1141535Y1146259D02*
X1143405Y1144389D01*
G01X1156495Y1153740D02*
X1158365Y1151869D01*
G01X1149015Y1153740D02*
X1150885Y1151869D01*
G01X1156495Y1153740D02*
X1154625Y1151869D01*
G01X1156495Y1146259D02*
X1158365Y1144389D01*
G01X1156495Y1146259D02*
X1154625Y1144389D01*
G01X1149015Y1146259D02*
X1150885Y1144389D01*
G01X1143405Y1151870D02*
X1145275Y1153740D01*
G01X1143405Y1144389D02*
X1145275Y1146259D01*
G01X1150885Y1151869D02*
X1152755Y1153740D01*
G01X1154625Y1151869D02*
X1152755Y1153740D01*
G01X1154625Y1144389D02*
X1152755Y1146259D01*
G01X1150885Y1144389D02*
X1152755Y1146259D01*
G01X1149015Y1157480D02*
X1150885Y1155610D01*
G01X1156495Y1168700D02*
X1158365Y1170570D01*
G01X1156495Y1161220D02*
X1158365Y1159350D01*
G01X1149015Y1161220D02*
X1150885Y1159350D01*
G01X1152755Y1164960D02*
X1154625Y1166830D01*
G01X1149015Y1168700D02*
X1150885Y1170570D01*
G01X1145275Y1164960D02*
X1143405Y1166830D01*
G01X1152755Y1172440D02*
X1154625Y1174310D01*
G01X1145275Y1172440D02*
X1143405Y1174310D01*
G01X1154625Y1166830D02*
X1156495Y1168700D01*
G01X1150885Y1170570D02*
X1152755Y1172440D01*
G01X1143405Y1166830D02*
X1141535Y1168700D01*
G01X1150885Y1159350D02*
X1152755Y1157480D01*
G01X1156495D02*
X1158365Y1155610D01*
G01X1156495Y1172440D02*
X1158365Y1174310D01*
G01X1149015Y1164960D02*
X1150885Y1166830D01*
G01X1149015Y1172440D02*
X1150885Y1174310D01*
G01X1156495Y1164960D02*
X1158365Y1166830D01*
G01X1152755Y1161220D02*
X1154625Y1159350D01*
G01X1145275Y1161220D02*
X1143405Y1159350D01*
G01X1152755Y1168700D02*
X1154625Y1170570D01*
G01X1145275Y1168700D02*
X1143405Y1170570D01*
G01D02*
X1141535Y1172440D01*
G01X1154625Y1159350D02*
X1156495Y1157480D01*
G01X1143405Y1159350D02*
X1141535Y1157480D01*
G01X1154625Y1170570D02*
X1156495Y1172440D01*
G01X1141535Y1179921D02*
X1143405Y1181791D01*
G01X1156495Y1187401D02*
X1158365Y1189271D01*
G01X1156495Y1179921D02*
X1158365Y1181791D01*
G01X1156495Y1179921D02*
X1154625Y1181791D01*
G01X1149015Y1179921D02*
X1150885Y1181791D01*
G01X1149015Y1187401D02*
X1150885Y1189271D01*
G01X1156495Y1187401D02*
X1154625Y1189271D01*
G01X1141535Y1187401D02*
X1143405Y1189271D01*
G01Y1181791D02*
X1145275Y1179921D01*
G01X1154625Y1181791D02*
X1152755Y1179921D01*
G01X1150885Y1181791D02*
X1152755Y1179921D01*
G01X1150885Y1189271D02*
X1152755Y1187401D01*
G01X1154625Y1189271D02*
X1152755Y1187401D01*
G01X1143405Y1189271D02*
X1145275Y1187401D01*
G01X1141535Y1176180D02*
X1143405Y1178051D01*
G01X1141535Y1183661D02*
X1143405Y1185531D01*
G01X1156495Y1183661D02*
X1158365Y1185531D01*
G01X1156495Y1183661D02*
X1154625Y1185531D01*
G01X1149015Y1183661D02*
X1150885Y1185531D01*
G01X1156495Y1176180D02*
X1158365Y1178051D01*
G01X1156495Y1176180D02*
X1154625Y1178051D01*
G01X1149015Y1176180D02*
X1150885Y1178051D01*
G01X1143405D02*
X1145275Y1176180D01*
G01X1143405Y1185531D02*
X1145275Y1183661D01*
G01X1154625Y1185531D02*
X1152755Y1183661D01*
G01X1150885Y1185531D02*
X1152755Y1183661D01*
G01X1154625Y1178051D02*
X1152755Y1176180D01*
G01X1150885Y1178051D02*
X1152755Y1176180D01*
G01Y1206102D02*
X1154625Y1204232D01*
G01D02*
X1156495Y1206102D01*
G01Y1202362D02*
X1154625Y1204232D01*
G01X1156495Y1194881D02*
X1158365Y1196751D01*
G01X1156495Y1202362D02*
X1158365Y1204232D01*
G01X1154625D02*
X1152755Y1202362D01*
G01X1149015Y1206102D02*
X1150885Y1204232D01*
G01D02*
X1152755Y1206102D01*
G01X1149015Y1202362D02*
X1150885Y1204232D01*
G01D02*
X1152755Y1202362D01*
G01X1141535D02*
X1143405Y1204232D01*
G01D02*
X1145275Y1202362D01*
G01Y1206102D02*
X1143405Y1204232D01*
G01D02*
X1141535Y1206102D01*
G01X1149015Y1194881D02*
X1150885Y1196751D01*
G01X1156495Y1194881D02*
X1154625Y1196751D01*
G01X1145275Y1194881D02*
X1143405Y1196751D01*
G01X1150885D02*
X1152755Y1194881D01*
G01X1154625Y1196751D02*
X1152755Y1194881D01*
G01X1143405Y1196751D02*
X1141535Y1194881D01*
G01X1150885Y1200491D02*
X1149015Y1198621D01*
G01X1158365Y1200491D02*
X1156495Y1198621D01*
G01X1143405Y1200491D02*
X1145275Y1198621D01*
G01X1154625Y1200491D02*
X1152755Y1198621D01*
G01X1143405Y1193011D02*
X1141535Y1191141D01*
G01X1150885Y1193011D02*
X1149015Y1191141D01*
G01X1145275D02*
X1143405Y1193011D01*
G01X1152755Y1191141D02*
X1150885Y1193011D01*
G01X1152755Y1191141D02*
X1154625Y1193011D01*
G01X1156495Y1191141D02*
X1158365Y1193011D01*
G01X1152755Y1209842D02*
X1150885Y1207972D01*
G01D02*
X1149015Y1209842D01*
G01X1152755Y1206102D02*
X1150885Y1207972D01*
G01X1156495Y1206102D02*
X1158365Y1204232D01*
G01X1156495Y1209842D02*
X1158365Y1211712D01*
G01X1156495Y1209842D02*
X1158365Y1207972D01*
G01X1156495Y1206102D02*
X1158365Y1207972D01*
G01X1150885D02*
X1149015Y1206102D01*
G01X1152755Y1209842D02*
X1154625Y1207972D01*
G01D02*
X1152755Y1206102D01*
G01X1156495D02*
X1154625Y1207972D01*
G01D02*
X1156495Y1209842D01*
G01X1141535D02*
X1143405Y1207972D01*
G01D02*
X1145275Y1209842D01*
G01X1141535Y1206102D02*
X1143405Y1207972D01*
G01D02*
X1145275Y1206102D01*
G01X1152755Y1209842D02*
X1154625Y1211712D01*
G01D02*
X1156495Y1209842D01*
G01X1163976Y1120078D02*
X1165846Y1121948D01*
G01D02*
X1167716Y1120078D01*
G01X1163976Y1123818D02*
X1165846Y1121948D01*
G01D02*
X1167716Y1123818D01*
G01X1173326Y1121948D02*
X1171456Y1120078D01*
G01X1167716Y1123818D02*
X1165846Y1125688D01*
G01X1171456Y1123818D02*
X1173326Y1121948D01*
G01Y1125688D02*
X1171456Y1123818D01*
G01D02*
X1169586Y1125688D01*
G01D02*
X1167716Y1123818D01*
G01X1165846Y1125688D02*
X1163976Y1123818D01*
G01X1162106Y1125688D02*
X1160235Y1123818D01*
G01Y1120078D02*
X1162106Y1121948D01*
G01D02*
X1163976Y1120078D01*
G01Y1123818D02*
X1162106Y1121948D01*
G01D02*
X1160235Y1123818D01*
G01D02*
X1158365Y1121948D01*
G01X1163976Y1123818D02*
X1162106Y1125688D01*
G01X1171456Y1120078D02*
X1169586Y1121948D01*
G01D02*
X1167716Y1120078D01*
G01X1169586Y1121948D02*
X1171456Y1123818D01*
G01X1167716D02*
X1169586Y1121948D01*
G01X1158365Y1125688D02*
X1160235Y1123818D01*
G01X1158365Y1121948D02*
X1160235Y1120078D01*
G01X1173326Y1125688D02*
X1171456Y1127558D01*
G01D02*
X1169586Y1125688D01*
G01X1163976Y1127558D02*
X1162106Y1125688D01*
G01X1167716Y1127558D02*
X1165846Y1125688D01*
G01D02*
X1163976Y1127558D01*
G01X1169586Y1125688D02*
X1167716Y1127558D01*
G01X1160235D02*
X1158365Y1125688D01*
G01X1162106D02*
X1160235Y1127558D01*
G01X1171456Y1135039D02*
X1173326Y1133169D01*
G01X1160235Y1135039D02*
X1162106Y1133169D01*
G01X1163976Y1135039D02*
X1165846Y1133169D01*
G01X1171456Y1135039D02*
X1169586Y1133169D01*
G01X1162106D02*
X1163976Y1135039D01*
G01X1165846Y1133169D02*
X1167716Y1135039D01*
G01X1169586Y1133169D02*
X1167716Y1135039D01*
G01X1158365Y1133169D02*
X1160235Y1135039D01*
G01X1173326Y1129429D02*
X1171456Y1131299D01*
G01X1162106Y1129429D02*
X1160235Y1131299D01*
G01X1165846Y1129429D02*
X1163976Y1131299D01*
G01X1169586Y1129429D02*
X1167716Y1131299D01*
G01X1171456Y1138779D02*
X1173326Y1136909D01*
G01X1171456Y1138779D02*
X1169586Y1136909D01*
G01X1167716Y1138779D02*
X1165846Y1136909D01*
G01X1160235Y1138779D02*
X1162106Y1136909D01*
G01X1169586D02*
X1167716Y1138779D01*
G01X1165846Y1136909D02*
X1163976Y1138779D01*
G01X1158365Y1136909D02*
X1160235Y1138779D01*
G01X1162106Y1136909D02*
X1163976Y1138779D01*
G01X1171456Y1149999D02*
X1173326Y1148129D01*
G01X1171456Y1142519D02*
X1173326Y1140649D01*
G01X1160235Y1157480D02*
X1162106Y1155610D01*
G01X1167716Y1157480D02*
X1169586Y1155610D01*
G01X1160235Y1142519D02*
X1162106Y1140649D01*
G01X1163976Y1142519D02*
X1165846Y1140649D01*
G01X1171456Y1142519D02*
X1169586Y1140649D01*
G01X1163976Y1149999D02*
X1162106Y1148129D01*
G01X1163976Y1149999D02*
X1165846Y1148129D01*
G01X1171456Y1149999D02*
X1169586Y1148129D01*
G01X1158365Y1140649D02*
X1160235Y1142519D01*
G01X1162106Y1140649D02*
X1163976Y1142519D01*
G01X1165846Y1140649D02*
X1167716Y1142519D01*
G01X1169586Y1140649D02*
X1167716Y1142519D01*
G01X1158365Y1148129D02*
X1160235Y1149999D01*
G01X1162106Y1148129D02*
X1160235Y1149999D01*
G01X1165846Y1148129D02*
X1167716Y1149999D01*
G01X1169586Y1148129D02*
X1167716Y1149999D01*
G01X1171456Y1153740D02*
X1173326Y1151869D01*
G01X1160235Y1153740D02*
X1162106Y1151869D01*
G01X1171456Y1153740D02*
X1169586Y1151869D01*
G01X1167716Y1153740D02*
X1165846Y1151869D01*
G01X1171456Y1146259D02*
X1173326Y1144389D01*
G01X1167716Y1146259D02*
X1165846Y1144389D01*
G01X1160235Y1146259D02*
X1162106Y1144389D01*
G01X1171456Y1146259D02*
X1169586Y1144389D01*
G01X1158365Y1151869D02*
X1160235Y1153740D01*
G01X1162106Y1151869D02*
X1163976Y1153740D01*
G01X1169586Y1151869D02*
X1167716Y1153740D01*
G01X1165846Y1151869D02*
X1163976Y1153740D01*
G01X1165846Y1144389D02*
X1163976Y1146259D01*
G01X1158365Y1144389D02*
X1160235Y1146259D01*
G01X1162106Y1144389D02*
X1163976Y1146259D01*
G01X1169586Y1144389D02*
X1167716Y1146259D01*
G01X1163976Y1157480D02*
X1165846Y1155610D01*
G01X1173326D02*
X1171456Y1157480D01*
G01X1160235Y1172440D02*
X1162106Y1174310D01*
G01X1167716Y1172440D02*
X1169586Y1174310D01*
G01X1171456Y1168700D02*
X1173326Y1170570D01*
G01X1171456Y1161220D02*
X1173326Y1159350D01*
G01X1167716Y1157480D02*
X1165846Y1159350D01*
G01X1171456Y1168700D02*
X1169586Y1166830D01*
G01X1167716Y1172440D02*
X1165846Y1170570D01*
G01X1160235Y1164960D02*
X1162106Y1166830D01*
G01X1158365Y1170570D02*
X1160235Y1172440D01*
G01X1165846Y1170570D02*
X1163976Y1168700D01*
G01X1169586Y1166830D02*
X1167716Y1164960D01*
G01X1158365Y1159350D02*
X1160235Y1157480D01*
G01X1162106Y1166830D02*
X1163976Y1168700D01*
G01X1165846Y1159350D02*
X1163976Y1161220D01*
G01Y1172440D02*
X1165846Y1174310D01*
G01X1173326D02*
X1171456Y1172440D01*
G01Y1157480D02*
X1169586Y1159350D01*
G01X1171456Y1172440D02*
X1169586Y1170570D01*
G01X1163976Y1164960D02*
X1165846Y1166830D01*
G01X1163976Y1172440D02*
X1162106Y1170570D01*
G01X1160235Y1161220D02*
X1162106Y1159350D01*
G01X1171456Y1164960D02*
X1173326Y1166830D01*
G01X1165846D02*
X1167716Y1168700D01*
G01X1169586Y1170570D02*
X1167716Y1168700D01*
G01X1158365Y1166830D02*
X1160235Y1168700D01*
G01X1162106Y1170570D02*
X1160235Y1168700D01*
G01X1169586Y1159350D02*
X1167716Y1161220D01*
G01X1162106Y1159350D02*
X1163976Y1157480D01*
G01X1171456Y1187401D02*
X1173326Y1189271D01*
G01X1171456Y1179921D02*
X1173326Y1181791D01*
G01X1160235Y1179921D02*
X1162106Y1181791D01*
G01X1163976Y1179921D02*
X1165846Y1181791D01*
G01X1171456Y1179921D02*
X1169586Y1181791D01*
G01X1160235Y1187401D02*
X1162106Y1189271D01*
G01X1163976Y1187401D02*
X1165846Y1189271D01*
G01X1171456Y1187401D02*
X1169586Y1189271D01*
G01X1158365Y1181791D02*
X1160235Y1179921D01*
G01X1162106Y1181791D02*
X1163976Y1179921D01*
G01X1165846Y1181791D02*
X1167716Y1179921D01*
G01X1169586Y1181791D02*
X1167716Y1179921D01*
G01X1158365Y1189271D02*
X1160235Y1187401D01*
G01X1162106Y1189271D02*
X1163976Y1187401D01*
G01X1165846Y1189271D02*
X1167716Y1187401D01*
G01X1169586Y1189271D02*
X1167716Y1187401D01*
G01X1171456Y1183661D02*
X1173326Y1185531D01*
G01X1160235Y1183661D02*
X1162106Y1185531D01*
G01X1167716Y1183661D02*
X1169586Y1185531D01*
G01X1167716Y1183661D02*
X1165846Y1185531D01*
G01X1171456Y1176180D02*
X1173326Y1178051D01*
G01X1163976Y1176180D02*
X1165846Y1178051D01*
G01X1163976Y1176180D02*
X1162106Y1178051D01*
G01X1167716Y1176180D02*
X1169586Y1178051D01*
G01X1158365Y1185531D02*
X1160235Y1183661D01*
G01X1162106Y1185531D02*
X1163976Y1183661D01*
G01X1169586Y1185531D02*
X1171456Y1183661D01*
G01X1165846Y1185531D02*
X1163976Y1183661D01*
G01X1165846Y1178051D02*
X1167716Y1176180D01*
G01X1158365Y1178051D02*
X1160235Y1176180D01*
G01X1162106Y1178051D02*
X1160235Y1176180D01*
G01X1169586Y1178051D02*
X1171456Y1176180D01*
G01X1167716Y1206102D02*
X1165846Y1204232D01*
G01D02*
X1163976Y1206102D01*
G01X1165846Y1204232D02*
X1167716Y1202362D01*
G01X1160235D02*
X1162106Y1204232D01*
G01D02*
X1163976Y1202362D01*
G01X1160235Y1206102D02*
X1162106Y1204232D01*
G01D02*
X1163976Y1206102D01*
G01X1173326Y1204232D02*
X1171456Y1206102D01*
G01X1163976Y1194881D02*
X1162106Y1196751D01*
G01X1171456Y1194881D02*
X1173326Y1196751D01*
G01X1171456Y1202362D02*
X1173326Y1204232D01*
G01X1167716Y1194881D02*
X1169586Y1196751D01*
G01X1167716Y1194881D02*
X1165846Y1196751D01*
G01X1160235Y1206102D02*
X1158365Y1204232D01*
G01X1171456Y1206102D02*
X1169586Y1204232D01*
G01D02*
X1167716Y1202362D01*
G01X1169586Y1204232D02*
X1167716Y1206102D01*
G01X1163976Y1202362D02*
X1165846Y1204232D01*
G01X1158365D02*
X1160235Y1202362D01*
G01X1158365Y1196751D02*
X1160235Y1194881D01*
G01X1162106Y1196751D02*
X1160235Y1194881D01*
G01X1165846Y1196751D02*
X1163976Y1194881D01*
G01X1169586Y1196751D02*
X1171456Y1194881D01*
G01X1173326Y1200491D02*
X1171456Y1198621D01*
G01X1165846Y1200491D02*
X1163976Y1198621D01*
G01X1162106Y1200491D02*
X1160235Y1198621D01*
G01X1169586Y1200491D02*
X1167716Y1198621D01*
G01X1171456Y1191141D02*
X1173326Y1193011D01*
G01X1160235Y1191141D02*
X1162106Y1193011D01*
G01X1167716Y1191141D02*
X1169586Y1193011D01*
G01X1163976Y1191141D02*
X1165846Y1193011D01*
G01X1160235Y1206102D02*
X1162106Y1207972D01*
G01D02*
X1163976Y1206102D01*
G01Y1209842D02*
X1162106Y1207972D01*
G01D02*
X1160235Y1209842D01*
G01X1163976D02*
X1165846Y1207972D01*
G01D02*
X1163976Y1206102D01*
G01X1167716D02*
X1165846Y1207972D01*
G01D02*
X1167716Y1209842D01*
G01Y1206102D02*
X1169586Y1207972D01*
G01D02*
X1167716Y1209842D01*
G01X1171456D02*
X1169586Y1207972D01*
G01D02*
X1171456Y1206102D01*
G01Y1209842D02*
X1173326Y1211712D01*
G01Y1207972D02*
X1171456Y1206102D01*
G01Y1209842D02*
X1173326Y1207972D01*
G01X1160235Y1209842D02*
X1158365Y1207972D01*
G01X1171456Y1209842D02*
X1169586Y1211712D01*
G01X1158365Y1207972D02*
X1160235Y1206102D01*
G01X1158365Y1211712D02*
X1160235Y1209842D01*
G01X1169586Y1211712D02*
X1167716Y1209842D01*
G01X1186417Y1123818D02*
X1184546Y1121948D01*
G01D02*
X1186417Y1120078D01*
G01X1182676Y1123818D02*
X1184546Y1121948D01*
G01Y1118208D02*
X1182676Y1120078D01*
G01X1184546Y1121948D02*
X1182676Y1120078D01*
G01X1178936Y1123818D02*
X1180806Y1121948D01*
G01D02*
X1182676Y1120078D01*
G01X1178936D02*
X1180806Y1121948D01*
G01X1182676Y1123818D02*
X1180806Y1125688D01*
G01X1175196Y1123818D02*
X1177066Y1125688D01*
G01X1178936Y1120078D02*
X1177066Y1121948D01*
G01D02*
X1175196Y1120078D01*
G01X1178936Y1123818D02*
X1177066Y1121948D01*
G01D02*
X1175196Y1123818D01*
G01Y1120078D02*
X1173326Y1121948D01*
G01X1190157Y1120078D02*
X1188287Y1118208D01*
G01X1190157Y1120078D02*
X1188287Y1121948D01*
G01X1186417Y1123818D02*
X1184546Y1125688D01*
G01X1180806D02*
X1178936Y1123818D01*
G01X1177066Y1125688D02*
X1178936Y1123818D01*
G01X1173326Y1121948D02*
X1175196Y1123818D01*
G01X1173326Y1125688D02*
X1175196Y1123818D01*
G01X1188287Y1125688D02*
X1186417Y1123818D01*
G01X1188287Y1118208D02*
X1186417Y1120078D01*
G01X1188287Y1121948D02*
X1186417Y1120078D01*
G01X1182676Y1138779D02*
X1184546Y1136909D01*
G01X1175196Y1135039D02*
X1177066Y1133169D01*
G01X1178936Y1135039D02*
X1180806Y1133169D01*
G01X1182676Y1135039D02*
X1184546Y1133169D01*
G01X1182676Y1127558D02*
X1184546Y1129429D01*
G01X1186417Y1127558D02*
X1188287Y1125688D01*
G01X1180806D02*
X1178936Y1127558D01*
G01X1177066Y1125688D02*
X1175196Y1127558D01*
G01X1178936D02*
X1177066Y1125688D01*
G01X1175196Y1127558D02*
X1173326Y1125688D01*
G01X1182676Y1127558D02*
X1180806Y1125688D01*
G01X1184546Y1136909D02*
X1186417Y1135039D01*
G01X1177066Y1133169D02*
X1178936Y1135039D01*
G01X1180806Y1133169D02*
X1182676Y1135039D01*
G01X1184546Y1133169D02*
X1186417Y1135039D01*
G01X1184546Y1125688D02*
X1182676Y1127558D01*
G01X1184546Y1129429D02*
X1182676Y1131299D01*
G01X1173326Y1133169D02*
X1175196Y1135039D01*
G01X1177066Y1129429D02*
X1175196Y1131299D01*
G01X1180806Y1129429D02*
X1178936Y1131299D01*
G01X1186417D02*
X1188287Y1129429D01*
G01X1178936Y1138779D02*
X1180806Y1136909D01*
G01X1175196Y1138779D02*
X1177066Y1136909D01*
G01D02*
X1178936Y1138779D01*
G01X1173326Y1136909D02*
X1175196Y1138779D01*
G01X1188287Y1140649D02*
X1186417Y1138779D01*
G01D02*
X1188287Y1136909D01*
G01X1186417Y1157480D02*
X1184546Y1155610D01*
G01D02*
X1182676Y1157480D01*
G01X1184546Y1155610D02*
X1186417Y1153740D01*
G01D02*
X1188287Y1155610D01*
G01D02*
X1190157Y1153740D01*
G01X1188287Y1155610D02*
X1186417Y1157480D01*
G01X1182676Y1153740D02*
X1184546Y1151869D01*
G01D02*
X1186417Y1153740D01*
G01X1182676Y1149999D02*
X1184546Y1151869D01*
G01D02*
X1186417Y1149999D01*
G01X1190157D02*
X1188287Y1151869D01*
G01D02*
X1186417Y1149999D01*
G01X1188287Y1151869D02*
X1186417Y1153740D01*
G01X1190157Y1149999D02*
X1188287Y1148129D01*
G01D02*
X1186417Y1149999D01*
G01X1188287Y1148129D02*
X1190157Y1146259D01*
G01Y1153740D02*
X1188287Y1151869D01*
G01X1186417Y1149999D02*
X1184546Y1148129D01*
G01X1182676Y1142519D02*
X1184546Y1140649D01*
G01Y1148129D02*
X1182676Y1146259D01*
G01X1184546Y1148129D02*
X1182676Y1149999D01*
G01X1175196Y1142519D02*
X1177066Y1140649D01*
G01X1182676Y1142519D02*
X1180806Y1140649D01*
G01X1175196Y1149999D02*
X1177066Y1148129D01*
G01X1178936Y1149999D02*
X1180806Y1148129D01*
G01X1182676Y1146259D02*
X1184546Y1144389D01*
G01X1175196Y1157480D02*
X1177066Y1155610D01*
G01X1184546D02*
X1182676Y1153740D01*
G01X1177066Y1140649D02*
X1178936Y1142519D01*
G01X1180806Y1140649D02*
X1178936Y1142519D01*
G01X1177066Y1148129D02*
X1178936Y1149999D01*
G01X1180806Y1148129D02*
X1182676Y1149999D01*
G01X1184546Y1144389D02*
X1182676Y1142519D01*
G01X1173326Y1140649D02*
X1175196Y1142519D01*
G01X1173326Y1148129D02*
X1175196Y1149999D01*
G01X1178936Y1153740D02*
X1180806Y1151869D01*
G01X1175196Y1153740D02*
X1177066Y1151869D01*
G01X1178936Y1146259D02*
X1180806Y1144389D01*
G01X1175196Y1146259D02*
X1177066Y1144389D01*
G01Y1151869D02*
X1178936Y1153740D01*
G01X1177066Y1144389D02*
X1178936Y1146259D01*
G01X1173326Y1151869D02*
X1175196Y1153740D01*
G01X1173326Y1144389D02*
X1175196Y1146259D01*
G01X1178936Y1157480D02*
X1180806Y1155610D01*
G01X1188287Y1144389D02*
X1186417Y1142519D01*
G01D02*
X1188287Y1140649D01*
G01X1186417Y1146259D02*
X1188287Y1144389D01*
G01X1182676Y1172440D02*
X1184546Y1174310D01*
G01X1175196Y1164960D02*
X1177066Y1166830D01*
G01X1186417Y1172440D02*
X1188287Y1174310D01*
G01X1175196Y1172440D02*
X1177066Y1174310D01*
G01X1186417Y1164960D02*
X1188287Y1166830D01*
G01X1186417Y1161220D02*
X1188287Y1159350D01*
G01X1186417Y1168700D02*
X1188287Y1170570D01*
G01X1184546Y1174310D02*
X1186417Y1172440D01*
G01X1188287Y1166830D02*
X1186417Y1168700D01*
G01X1188287Y1159350D02*
X1186417Y1157480D01*
G01X1188287Y1170570D02*
X1186417Y1172440D01*
G01X1173326Y1159350D02*
X1175196Y1157480D01*
G01X1173326Y1170570D02*
X1175196Y1172440D01*
G01X1182676Y1168700D02*
X1184546Y1170570D01*
G01X1178936Y1168700D02*
X1180806Y1170570D01*
G01X1178936Y1168700D02*
X1177066Y1170570D01*
G01X1182676Y1164960D02*
X1184546Y1166830D01*
G01X1182676Y1164960D02*
X1180806Y1166830D01*
G01X1182676Y1161220D02*
X1184546Y1159350D01*
G01X1178936Y1161220D02*
X1180806Y1159350D01*
G01X1178936Y1161220D02*
X1177066Y1159350D01*
G01X1180806Y1170570D02*
X1182676Y1168700D01*
G01X1177066Y1170570D02*
X1175196Y1168700D01*
G01X1180806Y1166830D02*
X1178936Y1164960D01*
G01X1177066Y1159350D02*
X1175196Y1161220D01*
G01X1180806Y1159350D02*
X1182676Y1161220D01*
G01X1178936Y1172440D02*
X1180806Y1174310D01*
G01X1182676Y1187401D02*
X1184546Y1189271D01*
G01X1178936Y1187401D02*
X1180806Y1189271D01*
G01D02*
X1182676Y1191141D01*
G01X1180806Y1189271D02*
X1182676Y1187401D01*
G01X1190157Y1183661D02*
X1188287Y1181791D01*
G01X1182676Y1176180D02*
X1184546Y1178051D01*
G01X1175196Y1187401D02*
X1177066Y1189271D01*
G01X1184546Y1185531D02*
X1182676Y1183661D01*
G01X1175196Y1179921D02*
X1177066Y1181791D01*
G01X1182676Y1183661D02*
X1180806Y1181791D01*
G01X1184546Y1174310D02*
X1182676Y1176180D01*
G01X1188287Y1174310D02*
X1190157Y1176180D01*
G01X1177066Y1189271D02*
X1178936Y1187401D01*
G01X1177066Y1181791D02*
X1178936Y1179921D01*
G01X1180806Y1181791D02*
X1178936Y1179921D01*
G01X1173326Y1189271D02*
X1175196Y1187401D01*
G01X1173326Y1181791D02*
X1175196Y1179921D01*
G01Y1183661D02*
X1177066Y1185531D01*
G01X1175196Y1176180D02*
X1177066Y1178051D01*
G01X1178936Y1183661D02*
X1180806Y1185531D01*
G01X1178936Y1176180D02*
X1180806Y1178051D01*
G01X1173326Y1185531D02*
X1175196Y1183661D01*
G01X1173326Y1178051D02*
X1175196Y1176180D01*
G01X1182676Y1179921D02*
X1184546Y1181791D01*
G01X1186417Y1187401D02*
X1188287Y1189271D01*
G01X1186417Y1183661D02*
X1188287Y1185531D01*
G01X1186417Y1176180D02*
X1188287Y1178051D01*
G01X1186417Y1206102D02*
X1184546Y1204232D01*
G01D02*
X1182676Y1202362D01*
G01X1184546Y1204232D02*
X1186417Y1202362D01*
G01X1178936Y1206102D02*
X1180806Y1204232D01*
G01D02*
X1182676Y1206102D01*
G01Y1202362D02*
X1180806Y1204232D01*
G01D02*
X1178936Y1202362D01*
G01X1182676D02*
X1184546Y1200491D01*
G01D02*
X1182676Y1198621D01*
G01X1184546Y1200491D02*
X1186417Y1202362D01*
G01X1178936D02*
X1177066Y1204232D01*
G01D02*
X1175196Y1202362D01*
G01X1178936Y1206102D02*
X1177066Y1204232D01*
G01D02*
X1175196Y1206102D01*
G01X1182676Y1198621D02*
X1180806Y1196751D01*
G01D02*
X1182676Y1194881D01*
G01X1180806Y1196751D02*
X1178936Y1194881D01*
G01X1186417D02*
X1184546Y1193011D01*
G01D02*
X1182676Y1191141D01*
G01X1184546Y1193011D02*
X1182676Y1194881D01*
G01X1188287Y1196751D02*
X1186417Y1194881D01*
G01X1182676D02*
X1184527Y1196732D01*
X1184566D01*
G01D02*
X1186417Y1194881D01*
G01X1184566Y1196732D02*
X1182676Y1198621D01*
G01X1184546Y1204232D02*
X1182676Y1206102D01*
G01X1175196Y1202362D02*
X1173326Y1204232D01*
G01X1178936Y1194881D02*
X1177066Y1196751D01*
G01X1186417Y1206102D02*
X1188287Y1204232D01*
G01X1173326D02*
X1175196Y1206102D01*
G01X1177066Y1196751D02*
X1175196Y1194881D01*
G01X1188287Y1204232D02*
X1186417Y1202362D01*
G01X1173326Y1196751D02*
X1175196Y1194881D01*
G01X1180806Y1200491D02*
X1178936Y1198621D01*
G01X1177066Y1200491D02*
X1175196Y1198621D01*
G01X1186417D02*
X1188287Y1200491D01*
G01X1178936Y1191141D02*
X1180806Y1193011D01*
G01X1175196Y1191141D02*
X1177066Y1193011D01*
G01X1186417Y1191141D02*
X1188287Y1193011D01*
G01X1182676Y1206102D02*
X1184546Y1207972D01*
G01D02*
X1186417Y1206102D01*
G01Y1209842D02*
X1184546Y1207972D01*
G01D02*
X1182676Y1209842D01*
G01X1190157D02*
X1188287Y1207972D01*
G01D02*
X1186417Y1206102D01*
G01Y1209842D02*
X1188287Y1207972D01*
G01X1178936Y1206102D02*
X1180806Y1207972D01*
G01D02*
X1182676Y1206102D01*
G01Y1209842D02*
X1180806Y1207972D01*
G01D02*
X1178936Y1209842D01*
G01X1175196Y1206102D02*
X1177066Y1207972D01*
G01D02*
X1178936Y1206102D01*
G01Y1209842D02*
X1177066Y1207972D01*
G01D02*
X1175196Y1209842D01*
G01Y1206102D02*
X1173326Y1207972D01*
G01X1186417Y1209842D02*
X1184546Y1211712D01*
G01X1178936Y1209842D02*
X1177066Y1211712D01*
G01X1182676Y1209842D02*
X1180806Y1211712D01*
G01X1173326Y1207972D02*
X1175196Y1209842D01*
G01X1184546Y1211712D02*
X1182676Y1209842D01*
G01X1177066Y1211712D02*
X1175196Y1209842D01*
G01X1180806Y1211712D02*
X1178936Y1209842D01*
G01X1173326Y1211712D02*
X1175196Y1209842D01*
G01X1190157Y1120078D02*
X1192027Y1118208D01*
G01X1193897Y1123818D02*
X1192027Y1121948D01*
G01Y1125688D02*
X1193897Y1123818D01*
G01X1192027Y1118208D02*
X1193897Y1120078D01*
G01X1192027Y1121948D02*
X1193897Y1120078D01*
G01Y1135039D02*
X1192027Y1136909D01*
G01D02*
X1190157Y1138779D01*
G01X1192027Y1136909D02*
X1193897Y1138779D01*
G01D02*
X1192027Y1140649D01*
G01X1205117Y1138779D02*
X1206987Y1136909D01*
G01X1193897Y1138779D02*
X1195767Y1140649D01*
G01X1193897Y1135039D02*
X1192027Y1133169D01*
G01X1193897Y1138779D02*
X1195767Y1136909D01*
G01X1193897Y1127558D02*
X1192027Y1125688D01*
G01X1193897Y1127558D02*
X1192027Y1129429D01*
G01Y1140649D02*
X1190157Y1138779D01*
G01X1192027Y1133169D02*
X1193897Y1131299D01*
G01X1195767Y1136909D02*
X1193897Y1135039D01*
G01X1192027Y1129429D02*
X1193897Y1131299D01*
G01Y1146259D02*
X1192027Y1144389D01*
G01D02*
X1190157Y1146259D01*
G01X1192027Y1144389D02*
X1190157Y1142519D01*
G01X1195767Y1155610D02*
X1193897Y1157480D01*
G01X1205117Y1153740D02*
X1206987Y1151869D01*
G01X1201377Y1153740D02*
X1203247Y1155610D01*
G01D02*
X1201377Y1157480D01*
G01X1205117D02*
X1203247Y1155610D01*
G01X1205117Y1146259D02*
X1206987Y1144389D01*
G01X1205117Y1149999D02*
X1206987Y1151869D01*
G01X1203247Y1155610D02*
X1205117Y1153740D01*
G01D02*
X1203247Y1151869D01*
G01D02*
X1201377Y1153740D01*
G01X1203247Y1151869D02*
X1205117Y1149999D01*
G01Y1142519D02*
X1203247Y1144389D01*
G01X1205117Y1142519D02*
X1206987Y1144389D01*
G01X1197637Y1153740D02*
X1199507Y1151869D01*
G01X1193897Y1153740D02*
X1195767Y1151869D01*
G01X1193897Y1149999D02*
Y1150000D01*
X1192027Y1151870D01*
G01X1195767Y1151869D02*
X1193897Y1149999D01*
G01X1195767Y1151869D02*
X1197637Y1153740D01*
G01X1193897Y1149999D02*
X1192027Y1148129D01*
G01D02*
X1193897Y1146259D01*
G01X1192027Y1148129D02*
X1190157Y1146259D01*
G01Y1149999D02*
X1192027Y1148129D01*
G01X1193897Y1146259D02*
X1195767Y1148129D01*
G01X1193897Y1142519D02*
X1192027Y1140649D01*
G01D02*
X1190157Y1142519D01*
G01X1193897D02*
X1192027Y1144389D01*
G01X1195767Y1140649D02*
X1193897Y1142519D01*
G01X1195767Y1148129D02*
X1193897Y1149999D01*
G01X1199507Y1151869D02*
X1201377Y1153740D01*
G01X1203247Y1144389D02*
X1205117Y1146259D01*
G01X1192027Y1151870D02*
X1190157Y1153740D01*
G01X1199507Y1155610D02*
X1197637Y1157480D01*
G01X1192027Y1155610D02*
X1190157Y1157480D01*
G01X1205117Y1161220D02*
X1206987Y1159350D01*
G01X1205117Y1157480D02*
X1203247Y1159350D01*
G01D02*
X1205117Y1161220D01*
G01X1201377Y1157480D02*
X1203247Y1159350D01*
G01D02*
X1201377Y1161220D01*
G01X1205117Y1157480D02*
X1206987Y1159350D01*
G01X1205117Y1164960D02*
X1206987Y1166830D01*
G01X1205117Y1168700D02*
X1203247Y1166830D01*
G01D02*
X1205117Y1164960D01*
G01X1201377D02*
X1203247Y1166830D01*
G01D02*
X1201377Y1168700D01*
G01X1205117D02*
X1203247Y1170570D01*
G01D02*
X1205117Y1172440D01*
G01X1201377Y1168700D02*
X1203247Y1170570D01*
G01D02*
X1201377Y1172440D01*
G01D02*
X1203247Y1174310D01*
G01D02*
X1205117Y1172440D01*
G01Y1168700D02*
X1206987Y1166830D01*
G01X1205117Y1172440D02*
X1206987Y1174310D01*
G01X1195767Y1159350D02*
X1193897Y1161220D01*
G01Y1168700D02*
X1195767Y1166830D01*
G01X1193897Y1172440D02*
X1195767Y1174310D01*
G01X1193897Y1168700D02*
X1195767Y1170570D01*
G01D02*
X1193897Y1172440D01*
G01X1195767Y1166830D02*
X1193897Y1164960D01*
G01X1199507Y1174310D02*
X1197637Y1172440D01*
G01X1199507Y1159350D02*
X1197637Y1161220D01*
G01X1199507Y1166830D02*
X1197637Y1164960D01*
G01X1199507Y1170570D02*
X1197637Y1168700D01*
G01X1192027Y1170570D02*
X1190157Y1168700D01*
G01X1192027Y1166830D02*
X1190157Y1168700D01*
G01Y1172440D02*
X1192027Y1170570D01*
G01X1190157Y1172440D02*
X1192027Y1174310D01*
G01X1190157Y1164960D02*
X1192027Y1166830D01*
G01Y1159350D02*
X1190157Y1161220D01*
G01Y1191141D02*
X1192027Y1189271D01*
G01D02*
X1193897Y1191141D01*
G01X1192027Y1189271D02*
X1190157Y1187401D01*
G01X1193897D02*
X1195767Y1189271D01*
G01D02*
X1197637Y1191141D01*
G01X1195767Y1189271D02*
X1193897Y1191141D01*
G01X1190157Y1176180D02*
X1192027Y1178051D01*
G01X1205117Y1176180D02*
X1206987Y1174310D01*
G01X1205117Y1187401D02*
X1206987Y1189271D01*
G01X1205117Y1176180D02*
X1203247Y1174310D01*
G01X1201377Y1176180D02*
X1203247Y1178051D01*
G01D02*
X1205117Y1176180D01*
G01Y1179921D02*
X1203247Y1178051D01*
G01X1205117Y1179921D02*
X1206987Y1181791D01*
G01X1205117Y1183661D02*
X1206987Y1181791D01*
G01X1197637Y1187401D02*
X1199507Y1185531D01*
G01X1205117Y1183661D02*
X1203247Y1185531D01*
G01Y1174310D02*
X1201377Y1176180D01*
G01X1193897Y1187401D02*
X1192027Y1189271D01*
G01X1193897Y1187401D02*
X1192027Y1185531D01*
G01X1197637Y1179921D02*
X1199507Y1181791D01*
G01X1197637Y1176180D02*
X1195767Y1174310D01*
G01X1192027Y1178051D02*
X1190157Y1179921D01*
G01X1193897Y1176180D02*
X1192027Y1178051D01*
G01X1193897Y1176180D02*
X1195767Y1178051D01*
G01D02*
X1197637Y1176180D01*
G01X1195767Y1178051D02*
X1197637Y1179921D01*
G01Y1183661D02*
X1195767Y1185531D01*
G01D02*
X1193897Y1183661D01*
G01X1195767Y1185531D02*
X1193897Y1187401D01*
G01Y1183661D02*
X1192027Y1181791D01*
G01D02*
X1190157Y1179921D01*
G01X1192027Y1181791D02*
X1190157Y1183661D01*
G01X1192027Y1185531D02*
X1190157Y1187401D01*
G01X1192027Y1185531D02*
X1193897Y1183661D01*
G01X1190157D02*
X1192027Y1185531D01*
G01X1195767Y1174310D02*
X1193897Y1176180D01*
G01X1203247Y1185531D02*
X1205117Y1187401D01*
G01X1199507Y1181791D02*
X1197637Y1183661D01*
G01X1193897Y1179921D02*
X1195767Y1181791D01*
G01X1193897Y1202362D02*
X1195767Y1204232D01*
G01X1197637Y1191141D02*
X1199507Y1193011D01*
G01X1197637Y1191141D02*
X1195767Y1193011D01*
G01D02*
X1193897Y1194881D01*
G01Y1191141D02*
X1195767Y1193011D01*
G01X1193897Y1191141D02*
X1192027Y1193011D01*
G01D02*
X1193897Y1194881D01*
G01X1192027Y1193011D02*
X1190157Y1191141D01*
G01X1205117D02*
X1206987Y1189271D01*
G01X1205117Y1194881D02*
X1203247Y1193011D01*
G01X1193897Y1194881D02*
X1195767Y1196751D01*
G01Y1204232D02*
X1193897Y1206102D01*
G01X1203247Y1193011D02*
X1205117Y1191141D01*
G01X1195767Y1196751D02*
X1193897Y1198621D01*
G01X1208858Y1194881D02*
X1205117D01*
G01X1197637D02*
X1199507Y1196751D01*
G01X1190157Y1194881D02*
X1192027Y1196751D01*
G01X1190157Y1198621D02*
X1192027Y1200491D01*
G01X1190157Y1202362D02*
X1192027Y1204232D01*
G01X1201377Y1198621D02*
X1199507Y1200491D01*
G01X1193897Y1209842D02*
X1192027Y1211712D01*
G01D02*
X1190157Y1209842D01*
G01X1221948Y1140649D02*
X1220078Y1138779D01*
G01D02*
X1218208Y1140649D01*
G01D02*
X1216338Y1138779D01*
G01X1214468Y1140649D02*
X1216338Y1138779D01*
G01X1208858Y1149999D02*
X1210728Y1151869D01*
G01X1220078Y1153740D02*
X1218208Y1155610D01*
G01X1220078Y1146259D02*
X1218208Y1148129D01*
G01X1212598Y1157480D02*
X1214468Y1155610D01*
G01X1212598Y1149999D02*
X1214468Y1151869D01*
G01X1208858Y1142519D02*
X1210728Y1144389D01*
G01X1212598Y1149999D02*
X1214468Y1148129D01*
G01X1212598Y1142519D02*
X1214468Y1140649D01*
G01X1216338Y1146259D02*
X1214468Y1144389D01*
G01X1221948Y1148129D02*
X1220078Y1146259D01*
G01X1221948Y1155610D02*
X1220078Y1153740D01*
G01X1206987Y1151869D02*
X1208858Y1149999D01*
G01X1206987Y1144389D02*
X1208858Y1142519D01*
G01X1210728Y1151869D02*
X1212598Y1149999D01*
G01X1218208Y1155610D02*
X1216338Y1153740D01*
G01X1218208Y1148129D02*
X1216338Y1146259D01*
G01X1214468Y1155610D02*
X1216338Y1153740D01*
G01X1214468Y1151869D02*
X1216338Y1153740D01*
G01X1214468Y1148129D02*
X1216338Y1146259D01*
G01X1214468Y1144389D02*
X1212598Y1142519D01*
G01X1210728Y1144389D02*
X1212598Y1142519D01*
G01X1221948Y1170570D02*
X1220078Y1168700D01*
G01X1208858Y1157480D02*
X1210728Y1159350D01*
G01X1212598Y1157480D02*
X1214468Y1159350D01*
G01X1208858Y1164960D02*
X1210728Y1166830D01*
G01X1220078Y1168700D02*
X1218208Y1170570D01*
G01X1216338Y1168700D02*
X1214468Y1170570D01*
G01X1212598Y1164960D02*
X1214468Y1166830D01*
G01X1220078Y1161220D02*
X1221948Y1159350D01*
G01X1212598Y1172440D02*
X1210728Y1174310D01*
G01X1206987Y1159350D02*
X1208858Y1157480D01*
G01X1206987Y1166830D02*
X1208858Y1164960D01*
G01X1206987Y1174310D02*
X1208858Y1172440D01*
G01X1214468Y1174310D02*
X1212598Y1172440D01*
G01X1210728Y1174310D02*
X1208858Y1172440D01*
G01X1210728Y1159350D02*
X1212598Y1157480D01*
G01X1214468Y1159350D02*
X1216338Y1161220D01*
G01X1210728Y1166830D02*
X1212598Y1164960D01*
G01X1218208Y1170570D02*
X1216338Y1168700D01*
G01X1214468Y1170570D02*
X1212598Y1172440D01*
G01X1214468Y1166830D02*
X1216338Y1168700D01*
G01X1221948Y1178051D02*
X1220078Y1176180D01*
G01X1221948Y1185531D02*
X1220078Y1183661D01*
G01X1212598Y1179921D02*
X1210728Y1181791D01*
G01X1208858Y1187401D02*
X1210728Y1189271D01*
G01X1220078Y1183661D02*
X1218208Y1185531D01*
G01X1220078Y1176180D02*
X1218208Y1178051D01*
G01X1216338Y1191141D02*
X1214468Y1189271D01*
G01X1212598Y1187401D02*
X1214468Y1185531D01*
G01X1212598Y1179921D02*
X1214468Y1181791D01*
G01X1212598Y1179921D02*
X1214468Y1178051D01*
G01X1216338Y1176180D02*
X1214468Y1174310D01*
G01X1206987Y1181791D02*
X1208858Y1179921D01*
G01X1206987Y1189271D02*
X1208858Y1187401D01*
G01X1210728Y1181791D02*
X1208858Y1179921D01*
G01X1210728Y1189271D02*
X1212598Y1187401D01*
G01X1218208Y1185531D02*
X1216338Y1183661D01*
G01X1218208Y1178051D02*
X1216338Y1176180D01*
G01X1214468Y1189271D02*
X1212598Y1187401D01*
G01X1214468Y1185531D02*
X1216338Y1183661D01*
G01X1214468Y1181791D02*
X1216338Y1183661D01*
G01X1214468Y1178051D02*
X1216338Y1176180D01*
G01X1221948Y1193011D02*
X1220078Y1191141D01*
G01X1216338D02*
X1218208Y1193011D01*
G01X1212598Y1194881D02*
X1214468Y1193011D01*
G01X1218208D02*
X1220078Y1191141D01*
G01X1214468Y1193011D02*
X1216338Y1191141D01*
G01X1208858Y1194881D02*
X1212598D01*
G01X1231298Y1138779D02*
X1229428Y1136909D01*
G01X1235039Y1135039D02*
X1233169Y1136909D01*
G01X1221948Y1140649D02*
X1223818Y1138779D01*
G01X1233169Y1140649D02*
X1231298Y1138779D01*
G01X1229428Y1136909D02*
X1227558Y1138779D01*
G01X1233169Y1136909D02*
X1231298Y1138779D01*
G01X1227558Y1153740D02*
X1225688Y1151869D01*
G01D02*
X1223818Y1149999D01*
G01X1225688Y1151869D02*
X1223818Y1153740D01*
G01Y1142519D02*
X1221948Y1140649D01*
G01X1235039Y1142519D02*
X1233169Y1140649D01*
G01X1223818Y1142519D02*
X1225688Y1144389D01*
G01D02*
X1223818Y1146259D01*
G01X1225688Y1144389D02*
X1227558Y1146259D01*
G01X1223818Y1149999D02*
X1221948Y1148129D01*
G01X1223818Y1157480D02*
X1221948Y1155610D01*
G01X1235039Y1142519D02*
X1236909Y1140649D01*
G01X1235039Y1149999D02*
X1236909Y1148129D01*
G01X1235039Y1157480D02*
X1236909Y1155610D01*
G01X1231298Y1146259D02*
X1233169Y1144389D01*
G01X1231298Y1146259D02*
X1229428Y1144389D01*
G01X1235039Y1157480D02*
X1233169Y1155610D01*
G01X1227558Y1153740D02*
X1229428Y1151869D01*
G01X1231298Y1153740D02*
X1233169Y1151869D01*
G01X1235039Y1149999D02*
X1233169Y1148129D01*
G01X1221948D02*
X1223818Y1146259D01*
G01X1221948Y1155610D02*
X1223818Y1153740D01*
G01X1236909Y1140649D02*
X1238779Y1142519D01*
G01X1236909Y1148129D02*
X1238779Y1149999D01*
G01X1236909Y1155610D02*
X1238779Y1157480D01*
G01X1233169Y1144389D02*
X1235039Y1142519D01*
G01X1229428Y1144389D02*
X1227558Y1146259D01*
G01X1233169Y1155610D02*
X1231298Y1153740D01*
G01X1229428Y1151869D02*
X1231298Y1153740D01*
G01X1233169Y1151869D02*
X1235039Y1149999D01*
G01X1233169Y1148129D02*
X1231298Y1146259D01*
G01X1227558Y1168700D02*
X1225688Y1166830D01*
G01D02*
X1223818Y1164960D01*
G01X1225688Y1166830D02*
X1223818Y1168700D01*
G01Y1172440D02*
X1221948Y1170570D01*
G01X1238779Y1172440D02*
X1236909Y1170570D01*
G01X1238779Y1164960D02*
X1236909Y1166830D01*
G01X1227558Y1168700D02*
X1229428Y1166830D01*
G01X1235039Y1172440D02*
X1233169Y1170570D01*
G01X1235039Y1164960D02*
X1233169Y1166830D01*
G01X1225688Y1174310D02*
X1223818Y1172440D01*
G01X1231298Y1161220D02*
X1229428Y1159350D01*
G01X1235039Y1157480D02*
X1233169Y1159350D01*
G01X1227558Y1161220D02*
X1225688Y1159350D01*
G01D02*
X1223818Y1157480D01*
G01X1225688Y1159350D02*
X1223818Y1161220D01*
G01X1221948Y1170570D02*
X1223818Y1168700D01*
G01X1233169Y1174310D02*
X1235039Y1172440D01*
G01X1236909Y1170570D02*
X1235039Y1172440D01*
G01X1236909Y1166830D02*
X1235039Y1164960D01*
G01X1229428Y1159350D02*
X1227558Y1161220D01*
G01X1233169Y1159350D02*
X1231298Y1161220D01*
G01X1229428Y1166830D02*
X1231298Y1168700D01*
G01X1233169Y1170570D02*
X1231298Y1168700D01*
G01X1233169Y1166830D02*
X1231298Y1168700D01*
G01Y1176180D02*
X1233169Y1174310D01*
G01X1227558Y1176180D02*
X1225688Y1174310D01*
G01D02*
X1223818Y1176180D01*
G01Y1179921D02*
X1225688Y1181791D01*
G01D02*
X1223818Y1183661D01*
G01X1225688Y1181791D02*
X1227558Y1183661D01*
G01X1223818Y1187401D02*
X1225688Y1189271D01*
G01D02*
X1227558Y1191141D01*
G01X1223818D02*
X1225688Y1189271D01*
G01X1223818Y1176180D02*
X1221948Y1178051D01*
G01X1223818Y1183661D02*
X1221948Y1185531D01*
G01X1238779Y1179921D02*
X1236909Y1178051D01*
G01X1238779Y1187401D02*
X1236909Y1185531D01*
G01X1231298Y1183661D02*
X1229428Y1181791D01*
G01X1231298Y1191141D02*
X1229428Y1189271D01*
G01X1231298Y1191141D02*
X1233169Y1189271D01*
G01X1231298Y1183661D02*
X1233169Y1185531D01*
G01X1235039Y1179921D02*
X1233169Y1181791D01*
G01X1235039Y1179921D02*
X1233169Y1178051D01*
G01X1231298Y1176180D02*
X1229428Y1174310D01*
G01X1221948Y1178051D02*
X1223818Y1179921D01*
G01X1221948Y1185531D02*
X1223818Y1187401D01*
G01X1236909Y1178051D02*
X1235039Y1179921D01*
G01X1236909Y1185531D02*
X1235039Y1187401D01*
G01X1229428Y1181791D02*
X1227558Y1183661D01*
G01X1229428Y1189271D02*
X1227558Y1191141D01*
G01X1233169Y1189271D02*
X1235039Y1187401D01*
G01X1233169Y1185531D02*
X1235039Y1187401D01*
G01X1233169Y1181791D02*
X1231298Y1183661D01*
G01X1233169Y1178051D02*
X1231298Y1176180D01*
G01X1229428Y1174310D02*
X1227558Y1176180D01*
G01X1223818Y1194881D02*
X1221948Y1193011D01*
G01X1231298Y1191141D02*
X1233169Y1193011D01*
G01X1221948D02*
X1223818Y1191141D01*
G01X1238779Y1157480D02*
X1240649Y1155610D01*
G01X1238779Y1149999D02*
X1240649Y1148129D01*
G01X1238779Y1142519D02*
X1240649Y1140649D01*
G01X1238779Y1164960D02*
X1240649Y1166830D01*
G01X1238779Y1172440D02*
X1240649Y1170570D01*
G01X1238779Y1179921D02*
X1240649Y1178051D01*
G01X1238779Y1187401D02*
X1240649Y1185531D01*
G01X1527559Y1075196D02*
X1525689Y1073326D01*
G01X1520078Y1075196D02*
X1521948Y1077066D01*
G01X1527559Y1078936D02*
X1525689Y1077066D01*
G01X1520078Y1078936D02*
X1518208Y1077066D01*
G01X1516338Y1078936D02*
X1518208Y1080806D01*
G01X1531299Y1082677D02*
X1529429Y1080807D01*
G01X1523819Y1082677D02*
X1521949Y1080807D01*
G01X1531299Y1086417D02*
X1529429Y1084547D01*
G01X1523819Y1086417D02*
X1521949Y1084547D01*
G01X1520078Y1086417D02*
X1518208Y1084547D01*
G01X1531299Y1090157D02*
X1529429Y1088287D01*
G01X1527559Y1090157D02*
X1525689Y1088287D01*
G01X1523819Y1090157D02*
X1521949Y1088287D01*
G01X1516338Y1086417D02*
X1514468Y1084547D01*
G01X1523819Y1105117D02*
X1521949Y1103247D01*
G01X1520078Y1105117D02*
X1518208Y1103247D01*
G01X1531299Y1108858D02*
X1529429Y1106988D01*
G01X1527559Y1108858D02*
X1525689Y1106988D01*
G01X1523819Y1108858D02*
X1521949Y1106988D01*
G01X1527559Y1097637D02*
X1525689Y1095767D01*
G01X1520078Y1097637D02*
X1518208Y1095767D01*
G01X1531299Y1101377D02*
X1529429Y1099507D01*
G01X1523819Y1101377D02*
X1521949Y1099507D01*
G01X1531299Y1105117D02*
X1529429Y1103247D01*
G01X1527559Y1093897D02*
X1525689Y1092027D01*
G01X1520078Y1093897D02*
X1518208Y1092027D01*
G01X1516338Y1093897D02*
X1514468Y1092027D01*
G01X1516338Y1097637D02*
X1514468Y1095767D01*
G01Y1103247D02*
X1516338Y1105117D01*
G01X1531299Y1112598D02*
X1529429Y1110728D01*
G01X1520078Y1112598D02*
X1518208Y1110728D01*
G01X1531299Y1116338D02*
X1529429Y1114468D01*
G01X1527559Y1116338D02*
X1525689Y1114468D01*
G01X1523819Y1116338D02*
X1521949Y1114468D01*
G01X1531299Y1120078D02*
X1529429Y1118208D01*
G01X1520078Y1120078D02*
X1518208Y1118208D01*
G01X1531299Y1123818D02*
X1529429Y1121948D01*
G01X1527559Y1123818D02*
X1525689Y1121948D01*
G01X1523819Y1123818D02*
X1521949Y1121948D01*
G01X1516338Y1112598D02*
X1514468Y1110728D01*
G01X1516338Y1120078D02*
X1514468Y1118208D01*
G01X1516338Y1135039D02*
X1514468Y1133169D01*
G01X1531299Y1127558D02*
X1529429Y1125688D01*
G01X1520078Y1127558D02*
X1518208Y1125688D01*
G01X1531299Y1131299D02*
X1529429Y1129429D01*
G01X1527559Y1131299D02*
X1525689Y1129429D01*
G01X1523819Y1131299D02*
X1521949Y1129429D01*
G01X1520078Y1135039D02*
X1518208Y1133169D01*
G01X1523819Y1138779D02*
X1521949Y1136909D01*
G01X1516338Y1127558D02*
X1514468Y1125688D01*
G01X1516338Y1153740D02*
X1514468Y1151870D01*
G01X1516338Y1146259D02*
X1514468Y1144389D01*
G01X1516338Y1142519D02*
X1514468Y1140649D01*
G01X1520078Y1142519D02*
X1518208Y1140649D01*
G01X1523819Y1142519D02*
X1521949Y1140649D01*
G01X1527559Y1142519D02*
X1525689Y1140649D01*
G01X1531299Y1142519D02*
X1529429Y1140649D01*
G01X1523819Y1146259D02*
X1521949Y1144389D01*
G01X1520078Y1146259D02*
X1518208Y1144389D01*
G01X1531299Y1149999D02*
X1529429Y1151869D01*
G01X1527559Y1149999D02*
X1525689Y1151869D01*
G01X1523819Y1149999D02*
X1521949Y1148129D01*
G01X1523819Y1153740D02*
X1521949Y1151870D01*
G01X1520078Y1153740D02*
X1518208Y1151870D01*
G01X1531299Y1157480D02*
X1529429Y1155610D01*
G01X1527559Y1157480D02*
X1525689Y1155610D01*
G01X1523819Y1157480D02*
X1521949Y1155610D01*
G01X1516338Y1161220D02*
X1514468Y1159350D01*
G01X1523819Y1172440D02*
X1525689Y1174310D01*
G01X1521948D02*
X1523819Y1172440D01*
G01X1525689Y1174310D02*
X1527559Y1172440D01*
G01X1523819Y1161220D02*
X1521949Y1159350D01*
G01X1520078Y1161220D02*
X1518208Y1159350D01*
G01X1525689Y1166830D02*
X1527559Y1164960D01*
G01X1531299D02*
X1529429Y1166830D01*
G01D02*
X1527559Y1164960D01*
G01X1521948Y1166830D02*
X1523819Y1164960D01*
G01Y1168700D02*
X1525689Y1170570D01*
G01X1520078Y1168700D02*
X1521948Y1170570D01*
G01X1518209Y1166830D02*
X1516338Y1168700D01*
G01X1514468Y1166829D02*
X1516338Y1168700D01*
G01X1529429Y1174310D02*
X1527559Y1172440D01*
G01X1520078Y1176180D02*
X1521948Y1174310D01*
G01D02*
X1523819Y1176180D01*
G01X1531299Y1172440D02*
X1529429Y1174310D01*
G01X1525689D02*
X1523819Y1176180D01*
G01Y1179921D02*
X1521948Y1178051D01*
G01D02*
X1523819Y1176180D01*
G01X1520078D02*
X1521948Y1178051D01*
G01X1516338Y1176180D02*
Y1176179D01*
X1518207Y1174310D01*
G01X1514468Y1174309D02*
X1516338Y1176180D01*
G01X1518207Y1174310D02*
X1520078Y1176180D01*
G01X1523819Y1179921D02*
X1527559D01*
G01D02*
X1531299D01*
G01X1542519Y1075196D02*
X1540649Y1073326D01*
G01X1535039Y1075196D02*
X1533169Y1073326D01*
G01X1540649Y1077066D02*
X1542519Y1075196D01*
G01Y1078936D02*
X1540649Y1077066D01*
G01X1538779Y1086417D02*
X1536909Y1084547D01*
G01X1542519Y1090157D02*
X1540649Y1088287D01*
G01X1542519Y1090157D02*
X1540649Y1092027D01*
G01Y1088287D02*
X1538779Y1086417D01*
G01X1535039Y1078936D02*
X1533169Y1077066D01*
G01X1538779Y1082677D02*
X1536909Y1080807D01*
G01X1538779Y1090157D02*
X1536909Y1088287D01*
G01X1535039Y1090157D02*
X1533169Y1088287D01*
G01X1542519Y1097637D02*
X1540649Y1099507D01*
G01X1542519Y1093897D02*
X1540649Y1095767D01*
G01X1544389Y1099507D02*
X1542519Y1097637D01*
G01X1535039D02*
X1533169Y1095767D01*
G01X1538779Y1101377D02*
X1536909Y1099507D01*
G01X1538779Y1105117D02*
X1536909Y1103247D01*
G01X1542519Y1108858D02*
X1540649Y1106988D01*
G01X1538779Y1108858D02*
X1536909Y1106988D01*
G01X1535039Y1108858D02*
X1533169Y1106988D01*
G01X1544389D02*
X1546259Y1108858D01*
G01X1540649Y1095767D02*
X1542519Y1097637D01*
G01X1535039Y1093897D02*
X1533169Y1092027D01*
G01X1540649D02*
X1542519Y1093897D01*
G01X1546259Y1108858D02*
X1546260D01*
X1548130Y1110728D01*
G01X1546259Y1120078D02*
X1544389Y1118208D01*
G01X1542519Y1120078D02*
X1540649Y1118208D01*
G01X1538779Y1123818D02*
X1540649Y1121948D01*
G01X1535039Y1123818D02*
X1533169Y1125688D01*
G01X1546259Y1112598D02*
X1544389Y1110728D01*
G01X1542519Y1112598D02*
X1540649Y1110728D01*
G01X1538779Y1116338D02*
X1536909Y1114468D01*
G01X1535039Y1116338D02*
X1533169Y1114468D01*
G01X1546259Y1127558D02*
X1544389Y1129428D01*
G01X1542519Y1127558D02*
X1540649Y1129428D01*
G01X1538779Y1131299D02*
X1536909Y1129429D01*
G01X1535039Y1131299D02*
X1533169Y1129429D01*
G01X1546259Y1135039D02*
X1544389Y1136909D01*
G01X1531299Y1135039D02*
X1533169Y1133169D01*
G01X1542519Y1135039D02*
X1540649Y1136909D01*
G01X1535039Y1142519D02*
X1533169Y1140649D01*
G01X1538779Y1142519D02*
X1536909Y1140649D01*
G01X1542519Y1142519D02*
X1540649Y1140649D01*
G01X1546259Y1142519D02*
X1544389Y1140649D01*
G01X1546259Y1146259D02*
X1544389Y1144389D01*
G01X1542519Y1146259D02*
X1540649Y1144389D01*
G01X1535039Y1146259D02*
X1533169Y1144389D01*
G01X1535039Y1149999D02*
X1533169Y1148129D01*
G01X1535039Y1153740D02*
X1533169Y1151870D01*
G01X1535039Y1157480D02*
X1533169Y1155610D01*
G01X1546259Y1149999D02*
X1544389Y1148129D01*
G01X1546259Y1157480D02*
X1544389Y1155610D01*
G01X1546259Y1153740D02*
X1544389Y1151870D01*
G01X1546259Y1168700D02*
X1548130Y1170570D01*
G01X1531299Y1172440D02*
X1533169Y1174310D01*
G01D02*
X1535039Y1172440D01*
G01X1546259D02*
X1544389Y1170570D01*
G01X1546259Y1164960D02*
X1544389Y1166830D01*
G01X1535039Y1161220D02*
X1533169Y1159350D01*
G01X1536909Y1166830D02*
X1535039Y1164960D01*
G01X1536909Y1170570D02*
X1535039Y1168700D01*
G01X1546259Y1161220D02*
X1544389Y1159350D01*
G01Y1166830D02*
X1546259Y1168700D01*
G01X1544389Y1170570D02*
X1546259Y1168700D01*
G01X1536909Y1174310D02*
X1535039Y1172440D01*
G01X1544389Y1174310D02*
X1546259Y1172440D01*
G01Y1176180D02*
X1544389Y1174310D01*
G01X1546259Y1179921D02*
X1544389Y1181791D01*
G01D02*
X1542519Y1179921D01*
G01X1535039D02*
X1533169Y1178051D01*
G01D02*
X1531299Y1179921D01*
G01X1533169Y1174310D02*
X1535039Y1176180D01*
G01D02*
X1536909Y1174310D01*
G01X1533169Y1178051D02*
X1535039Y1176180D01*
G01X1546259Y1179921D02*
X1544389Y1178051D01*
G01D02*
X1542519Y1179921D01*
G01X1544389Y1178051D02*
X1546259Y1176180D01*
G01X1538779Y1179921D02*
X1540649Y1181791D01*
G01D02*
X1542519Y1179921D01*
G01X1535039D02*
X1538779D01*
G01X1550000Y1112598D02*
X1548130Y1110728D01*
G01X1553740Y1116338D02*
X1551870Y1114468D01*
G01X1550000Y1116338D02*
X1548130Y1114468D01*
G01X1561220Y1120078D02*
X1559350Y1118208D01*
G01X1557480Y1120078D02*
X1555610Y1118208D01*
G01X1553740Y1120078D02*
X1551870Y1118208D01*
G01X1550000Y1120078D02*
X1548130Y1118208D01*
G01X1561220Y1123818D02*
X1559350Y1121948D01*
G01X1557480Y1123818D02*
X1555610Y1121948D01*
G01X1553740Y1123818D02*
X1551870Y1121948D01*
G01X1550000Y1123818D02*
X1548130Y1121948D01*
G01X1553740Y1112598D02*
X1551870Y1110728D01*
G01X1561220Y1127558D02*
X1559350Y1125688D01*
G01X1557480Y1127558D02*
X1555610Y1125688D01*
G01X1553740Y1127558D02*
X1551870Y1125688D01*
G01X1550000Y1127558D02*
X1548130Y1125688D01*
G01X1561220Y1131299D02*
X1559350Y1129429D01*
G01X1557480Y1131299D02*
X1555610Y1129429D01*
G01X1553740Y1131299D02*
X1551870Y1129429D01*
G01X1550000Y1131299D02*
X1548130Y1129429D01*
G01X1561220Y1135039D02*
X1559350Y1133169D01*
G01X1557480Y1135039D02*
X1555610Y1133169D01*
G01X1550000Y1135039D02*
X1548130Y1133169D01*
G01X1550000Y1135039D02*
X1551870Y1133169D01*
G01D02*
X1553740Y1135039D01*
G01X1561220Y1138779D02*
X1559350Y1136909D01*
G01X1553740Y1138779D02*
X1551870Y1136909D01*
G01X1550000Y1138779D02*
X1548130Y1136909D01*
G01X1553740Y1142519D02*
X1551870Y1140649D01*
G01X1557480Y1142519D02*
X1555610Y1140649D01*
G01X1561220Y1142519D02*
X1559350Y1140649D01*
G01X1550000Y1142519D02*
X1548130Y1140649D01*
G01X1559350Y1151870D02*
X1561220Y1153740D01*
G01D02*
X1563090Y1155610D01*
G01X1553740Y1157480D02*
X1551870Y1155610D01*
G01X1553740Y1153740D02*
X1551870Y1151870D01*
G01X1561220Y1146259D02*
X1559350Y1144389D01*
G01X1553740Y1146259D02*
X1551870Y1144389D01*
G01X1553740Y1149999D02*
X1551870Y1148129D01*
G01X1557480Y1146259D02*
X1555610Y1144389D01*
G01X1550000Y1153740D02*
X1548130Y1151870D01*
G01X1550000Y1149999D02*
X1548130Y1148129D01*
G01X1550000Y1146259D02*
X1548130Y1144389D01*
G01X1557480Y1153740D02*
X1555610Y1151870D01*
G01X1561220Y1149999D02*
X1559350Y1148129D01*
G01X1550000Y1168700D02*
X1551870Y1166830D01*
G01D02*
X1553740Y1168700D01*
G01X1551870Y1166830D02*
X1553740Y1164960D01*
G01Y1168700D02*
X1551870Y1170570D01*
G01D02*
X1550000Y1168700D01*
G01X1551870Y1170570D02*
X1553740Y1172440D01*
G01X1561220Y1168700D02*
X1559350Y1170570D01*
G01X1561220Y1168700D02*
X1563090Y1166830D01*
G01X1559350Y1170570D02*
X1557480Y1172440D01*
G01X1561220Y1161220D02*
X1559350Y1159350D01*
G01X1553740Y1161220D02*
X1551870Y1159350D01*
G01D02*
X1550000Y1157480D01*
G01X1548130Y1170570D02*
X1550000Y1168700D01*
G01X1551870Y1174310D02*
X1553740Y1172440D01*
G01X1557480Y1164960D02*
X1553740Y1168700D01*
G01X1557480Y1172440D02*
X1555610Y1174310D01*
G01D02*
X1553740Y1172440D01*
G01X1548130Y1174310D02*
X1550000Y1172440D01*
G01Y1164960D02*
X1548130Y1166830D01*
G01X1550000Y1161220D02*
X1548130Y1159350D01*
G01X1555610Y1170570D02*
X1557480Y1168700D01*
G01X1561220Y1172440D02*
X1559350Y1174310D01*
G01Y1166830D02*
X1561220Y1164960D01*
G01X1557480Y1161220D02*
X1555610Y1159350D01*
G01X1551870Y1185531D02*
X1553740Y1183661D01*
G01Y1187401D02*
X1551870Y1185531D01*
G01X1561220Y1183661D02*
X1559350Y1185531D01*
G01D02*
X1557480Y1187401D01*
G01X1559350Y1185531D02*
X1561220Y1187401D01*
G01X1557480D02*
X1555610Y1189271D01*
G01D02*
X1553740Y1187401D01*
G01Y1191141D02*
X1555610Y1189271D01*
G01D02*
X1557480Y1191141D01*
G01X1551870Y1189271D02*
X1553740Y1187401D01*
G01Y1191141D02*
X1551870Y1189271D01*
G01Y1181791D02*
X1553740Y1183661D01*
G01X1551870Y1181791D02*
X1553740Y1179921D01*
G01Y1176180D02*
X1551870Y1174310D01*
G01X1553740Y1176180D02*
X1551870Y1178051D01*
G01X1561220Y1176180D02*
X1559350Y1178051D01*
G01X1561220Y1183661D02*
X1563090Y1181791D01*
G01X1561220Y1176180D02*
X1563090Y1174310D01*
G01X1551870Y1178051D02*
X1553740Y1179921D01*
G01X1559350Y1178051D02*
X1557480Y1179921D01*
G01X1555610Y1181791D02*
X1557480Y1179921D01*
G01X1553740D02*
X1555610Y1181791D01*
G01D02*
X1553740Y1183661D01*
G01X1555610Y1174310D02*
X1553740Y1176180D01*
G01X1550000Y1183661D02*
X1548130Y1185531D01*
G01X1550000Y1176180D02*
X1548130Y1174310D01*
G01Y1181791D02*
X1550000Y1179921D01*
G01D02*
X1548130Y1178051D01*
G01D02*
X1550000Y1176180D01*
G01X1561220Y1179921D02*
X1559350Y1181791D01*
G01X1557480Y1176180D02*
X1555610Y1178051D01*
G01X1561220Y1206102D02*
X1563090Y1204232D01*
G01X1557480Y1191141D02*
X1559350Y1193011D01*
G01D02*
X1561220Y1191141D01*
G01Y1194881D02*
X1559350Y1193011D01*
G01D02*
X1557480Y1194881D01*
G01X1553740Y1191141D02*
X1555610Y1193011D01*
G01D02*
X1557480Y1191141D01*
G01Y1194881D02*
X1555610Y1193011D01*
G01D02*
X1553740Y1194881D01*
G01Y1191141D02*
X1551870Y1193011D01*
G01D02*
X1553740Y1194881D01*
G01X1557480D02*
X1559350Y1196751D01*
G01D02*
X1561220Y1194881D01*
G01Y1198621D02*
X1559350Y1196751D01*
G01D02*
X1557480Y1198621D01*
G01X1561220D02*
X1563090Y1196751D01*
G01X1561220Y1198621D02*
X1563090Y1200491D01*
G01X1557480Y1194881D02*
X1555610Y1196751D01*
G01D02*
X1553740Y1194881D01*
G01Y1198621D02*
X1555610Y1196751D01*
G01D02*
X1557480Y1198621D01*
G01D02*
X1559350Y1200491D01*
G01D02*
X1561220Y1198621D01*
G01Y1202362D02*
X1559350Y1200491D01*
G01X1553740Y1202362D02*
X1555610Y1204232D01*
G01D02*
X1557480Y1202362D01*
G01Y1206102D02*
X1555610Y1204232D01*
G01D02*
X1553740Y1206102D01*
G01X1559350Y1200491D02*
X1557480Y1202362D01*
G01X1553740Y1198621D02*
X1555610Y1200491D01*
G01D02*
X1557480Y1198621D01*
G01Y1202362D02*
X1555610Y1200491D01*
G01D02*
X1553740Y1202362D01*
G01X1563090Y1204232D02*
X1561220Y1202362D01*
G01D02*
X1559350Y1204232D01*
G01D02*
X1557480Y1202362D01*
G01X1559350Y1204232D02*
X1557480Y1206102D01*
G01X1561220D02*
X1559350Y1204232D01*
G01X1557480Y1209842D02*
X1559350Y1211712D01*
G01D02*
X1557480Y1213582D01*
G01X1559350Y1211712D02*
X1561220Y1209842D01*
G01X1553740D02*
X1555610Y1211712D01*
G01D02*
X1557480Y1209842D01*
G01Y1213582D02*
X1555610Y1211712D01*
G01D02*
X1553740Y1213582D01*
G01X1563090Y1207972D02*
X1561220Y1206102D01*
G01D02*
X1559350Y1207972D01*
G01D02*
X1561220Y1209842D01*
G01X1557480Y1206102D02*
X1559350Y1207972D01*
G01D02*
X1557480Y1209842D01*
G01Y1206102D02*
X1555610Y1207972D01*
G01D02*
X1553740Y1206102D01*
G01X1555610Y1207972D02*
X1557480Y1209842D01*
G01X1555610Y1207972D02*
X1553740Y1209842D01*
G01X1563090Y1211712D02*
X1561220Y1209842D01*
G01D02*
X1563090Y1207972D01*
G01X1564960Y1123818D02*
X1563090Y1121948D01*
G01X1564960Y1120078D02*
X1563090Y1118208D01*
G01X1579921Y1120078D02*
X1578051Y1118208D01*
G01X1576181Y1120078D02*
X1574311Y1118208D01*
G01X1576181Y1120078D02*
X1578051Y1121948D01*
G01D02*
X1579921Y1120078D01*
G01Y1123818D02*
X1578051Y1121948D01*
G01D02*
X1576181Y1123818D01*
G01D02*
X1574311Y1121948D01*
G01X1578051Y1125688D02*
X1576181Y1123818D01*
G01X1568700D02*
X1566830Y1121948D01*
G01X1572441Y1120078D02*
X1570571Y1118208D01*
G01X1568700Y1120078D02*
X1566830Y1118208D01*
G01X1572441Y1123818D02*
X1570571Y1121948D01*
G01X1564960Y1127558D02*
X1563090Y1125688D01*
G01X1579921Y1127558D02*
X1578051Y1125688D01*
G01D02*
X1579921Y1123818D01*
G01X1576181Y1127558D02*
X1578051Y1125688D01*
G01X1576181Y1127558D02*
X1574311Y1125688D01*
G01X1579921Y1135039D02*
X1578051Y1133169D01*
G01X1576181Y1135039D02*
X1574311Y1133169D01*
G01X1572441Y1135039D02*
X1570571Y1133169D01*
G01X1568700Y1138779D02*
X1566830Y1136909D01*
G01X1568700Y1127558D02*
X1566830Y1129429D01*
G01X1568700Y1127558D02*
X1566830Y1125688D01*
G01X1568700Y1131299D02*
X1566830Y1133169D01*
G01D02*
X1568700Y1135039D01*
G01X1566830Y1129429D02*
X1568700Y1131299D01*
G01X1572441Y1127558D02*
X1570571Y1125688D01*
G01X1578051Y1133169D02*
X1576181Y1135039D01*
G01X1574311Y1133169D02*
X1572441Y1135039D01*
G01X1570571Y1133169D02*
X1568700Y1135039D01*
G01X1566830Y1136909D02*
X1568700Y1135039D01*
G01X1570571Y1136909D02*
X1572441Y1138779D01*
G01X1576181D02*
X1578051Y1136909D01*
G01X1576181Y1138779D02*
X1574311Y1136909D01*
G01X1578051D02*
X1579921Y1138779D01*
G01X1574311Y1136909D02*
X1572441Y1138779D01*
G01X1574311Y1129429D02*
X1576181Y1131299D01*
G01X1570571Y1129429D02*
X1572441Y1131299D01*
G01X1578051Y1129429D02*
X1579921Y1131299D01*
G01X1564960Y1138779D02*
X1563090Y1136909D01*
G01X1576181Y1149999D02*
X1574311Y1148129D01*
G01X1566830Y1144389D02*
X1568700Y1146259D01*
G01D02*
X1570571Y1148129D01*
G01X1576181Y1149999D02*
X1578051Y1148129D01*
G01X1570571Y1140649D02*
X1572441Y1142519D01*
G01X1576181D02*
X1574311Y1140649D01*
G01X1576181Y1142519D02*
X1578051Y1140649D01*
G01Y1155610D02*
X1579921Y1157480D01*
G01X1574311Y1140649D02*
X1572441Y1142519D01*
G01X1578051Y1140649D02*
X1579921Y1142519D01*
G01X1574311Y1148129D02*
X1572441Y1149999D01*
G01X1570571Y1148129D02*
X1572441Y1149999D01*
G01X1578051Y1148129D02*
X1579921Y1149999D01*
G01X1568700Y1153740D02*
X1570571Y1155610D01*
G01X1563090Y1148129D02*
X1564960Y1149999D01*
G01D02*
X1566830Y1151869D01*
G01X1570571Y1155610D02*
X1572441Y1157480D01*
G01X1566830Y1151869D02*
X1568700Y1153740D01*
G01X1563090Y1155610D02*
X1564960Y1157480D01*
G01X1576181Y1146259D02*
X1578051Y1144389D01*
G01X1570571D02*
X1572441Y1146259D01*
G01D02*
X1574311Y1144389D01*
G01X1578051D02*
X1579921Y1146259D01*
G01X1574311Y1144389D02*
X1576181Y1146259D01*
G01X1570571Y1151870D02*
X1572441Y1153740D01*
G01X1574311Y1151870D02*
X1576181Y1153740D01*
G01X1578051Y1151870D02*
X1579921Y1153740D01*
G01X1563090Y1151869D02*
X1564960Y1153740D01*
G01D02*
X1566830Y1155610D01*
G01D02*
X1568700Y1157480D01*
G01X1563090Y1144389D02*
X1564960Y1146259D01*
G01D02*
X1566830Y1148129D01*
G01D02*
X1568700Y1149999D01*
G01X1574311Y1155610D02*
X1576181Y1157480D01*
G01X1572441Y1172440D02*
X1570571Y1174310D01*
G01X1579921Y1164960D02*
X1578051Y1166830D01*
G01X1576181Y1168700D02*
X1574311Y1170570D01*
G01X1572441Y1164960D02*
X1570571Y1166830D01*
G01X1568700Y1168700D02*
X1566830Y1170570D01*
G01X1572441Y1157480D02*
X1574311Y1159350D01*
G01X1564960Y1157480D02*
X1566830Y1159350D01*
G01D02*
X1568700Y1161220D01*
G01X1578051Y1166830D02*
X1576181Y1168700D01*
G01X1574311Y1159350D02*
X1576181Y1161220D01*
G01X1570571Y1166830D02*
X1568700Y1168700D01*
G01X1566830Y1170570D02*
X1564960Y1172440D01*
G01X1574311Y1170570D02*
X1572441Y1172440D01*
G01X1563090Y1166830D02*
X1564960Y1164960D01*
G01X1563090Y1174310D02*
X1564960Y1172440D01*
G01X1568700Y1157480D02*
X1570571Y1159350D01*
G01D02*
X1572441Y1161220D01*
G01X1576181Y1157480D02*
X1578051Y1159350D01*
G01D02*
X1579921Y1161220D01*
G01X1564960Y1168700D02*
X1563090Y1170570D01*
G01X1568700Y1164960D02*
X1566830Y1166830D01*
G01D02*
X1564960Y1168700D01*
G01Y1161220D02*
X1563090Y1159350D01*
G01X1572441Y1168700D02*
X1574311Y1166830D01*
G01X1568700Y1172440D02*
X1566830Y1174310D01*
G01X1568700Y1172440D02*
X1570571Y1170570D01*
G01X1574311Y1166830D02*
X1576181Y1164960D01*
G01X1570571Y1170570D02*
X1572441Y1168700D01*
G01X1578051Y1170570D02*
X1579921Y1168700D01*
G01X1576181Y1172440D02*
X1574311Y1174310D01*
G01X1576181Y1179921D02*
X1578051Y1181791D01*
G01X1572441Y1179921D02*
X1574311Y1181791D01*
G01X1572441Y1179921D02*
X1570571Y1181791D01*
G01X1564960Y1187401D02*
X1566830Y1189271D01*
G01D02*
X1568700Y1191141D01*
G01X1566830Y1189271D02*
X1568700Y1187401D01*
G01X1579921D02*
X1578051Y1189271D01*
G01X1576181Y1187401D02*
X1574311Y1189271D01*
G01X1572441Y1187401D02*
X1570571Y1189271D01*
G01X1564960Y1187401D02*
X1566830Y1185531D01*
G01X1564960Y1179921D02*
X1566830Y1178051D01*
G01X1578051Y1174310D02*
X1579921Y1172440D01*
G01X1578051Y1181791D02*
X1579921Y1179921D01*
G01X1574311Y1181791D02*
X1576181Y1179921D01*
G01X1570571Y1181791D02*
X1568700Y1183661D01*
G01X1578051Y1189271D02*
X1576181Y1187401D01*
G01X1574311Y1189271D02*
X1572441Y1187401D01*
G01X1570571Y1189271D02*
X1568700Y1187401D01*
G01X1566830Y1178051D02*
X1568700Y1176180D01*
G01X1570571Y1174310D02*
X1568700Y1176180D01*
G01X1566830Y1185531D02*
X1568700Y1183661D01*
G01X1563090Y1181791D02*
X1564960Y1179921D01*
G01X1576181Y1176180D02*
X1578051Y1178051D01*
G01X1570571D02*
X1572441Y1176180D01*
G01D02*
X1574311Y1178051D01*
G01X1578051D02*
X1579921Y1176180D01*
G01X1574311Y1178051D02*
X1576181Y1176180D01*
G01X1570571Y1185531D02*
X1572441Y1183661D01*
G01D02*
X1574311Y1185531D01*
G01X1576181Y1183661D02*
X1578051Y1185531D01*
G01X1574311D02*
X1576181Y1183661D01*
G01X1578051Y1185531D02*
X1579921Y1183661D01*
G01X1563090Y1178051D02*
X1564960Y1176180D01*
G01X1566830Y1174310D02*
X1564960Y1176180D01*
G01X1563090Y1185531D02*
X1564960Y1183661D01*
G01D02*
X1566830Y1181791D01*
G01D02*
X1568700Y1179921D01*
G01X1576181Y1194881D02*
X1578051Y1196751D01*
G01X1572441Y1194881D02*
X1574311Y1196751D01*
G01X1568700Y1194881D02*
X1570571Y1196751D01*
G01X1568700Y1198621D02*
X1566830Y1196751D01*
G01X1568700Y1194881D02*
X1566830Y1193011D01*
G01Y1200491D02*
X1568700Y1198621D01*
G01X1576181Y1206102D02*
X1578051Y1204232D01*
G01D02*
X1579921Y1206102D01*
G01X1576181Y1202362D02*
X1578051Y1204232D01*
G01D02*
X1579921Y1202362D01*
G01X1568700D02*
X1570571Y1204232D01*
G01D02*
X1572441Y1202362D01*
G01Y1206102D02*
X1570571Y1204232D01*
G01D02*
X1568700Y1206102D01*
G01X1564960Y1202362D02*
X1566830Y1204232D01*
G01D02*
X1568700Y1202362D01*
G01Y1206102D02*
X1566830Y1204232D01*
G01D02*
X1564960Y1206102D01*
G01X1572441D02*
X1574311Y1204232D01*
G01D02*
X1572441Y1202362D01*
G01X1576181D02*
X1574311Y1204232D01*
G01D02*
X1576181Y1206102D01*
G01X1564960Y1202362D02*
X1563090Y1204232D01*
G01D02*
X1564960Y1206102D01*
G01X1578051Y1196751D02*
X1579921Y1194881D01*
G01X1574311Y1196751D02*
X1576181Y1194881D01*
G01X1570571Y1196751D02*
X1572441Y1194881D01*
G01X1566830Y1196751D02*
X1568700Y1194881D01*
G01X1566830Y1193011D02*
X1568700Y1191141D01*
G01X1578051Y1193011D02*
X1576181Y1191141D01*
G01X1574311Y1193011D02*
X1572441Y1191141D01*
G01X1579921D02*
X1578051Y1193011D01*
G01X1576181Y1191141D02*
X1574311Y1193011D01*
G01X1570571D02*
X1572441Y1191141D01*
G01X1570571Y1200491D02*
X1572441Y1198621D01*
G01X1578051Y1200491D02*
X1579921Y1198621D01*
G01X1574311Y1200491D02*
X1576181Y1198621D01*
G01X1564960Y1191141D02*
X1563090Y1193011D01*
G01X1568700Y1206102D02*
X1566830Y1207972D01*
G01D02*
X1564960Y1206102D01*
G01Y1209842D02*
X1566830Y1207972D01*
G01D02*
X1568700Y1209842D01*
G01X1564960D02*
X1566830Y1211712D01*
G01D02*
X1568700Y1209842D01*
G01X1566830Y1211712D02*
X1564960Y1213582D01*
G01X1579921Y1206102D02*
X1578051Y1207972D01*
G01D02*
X1576181Y1206102D01*
G01Y1209842D02*
X1578051Y1207972D01*
G01D02*
X1579921Y1209842D01*
G01X1572441Y1206102D02*
X1574311Y1207972D01*
G01D02*
X1576181Y1206102D01*
G01Y1209842D02*
X1574311Y1207972D01*
G01D02*
X1572441Y1209842D01*
G01X1568700Y1206102D02*
X1570571Y1207972D01*
G01D02*
X1572441Y1206102D01*
G01Y1209842D02*
X1570571Y1207972D01*
G01D02*
X1568700Y1209842D01*
G01X1564960D02*
X1563090Y1211712D01*
G01X1564960Y1206102D02*
X1563090Y1207972D01*
G01D02*
X1564960Y1209842D01*
G01X1563090Y1219192D02*
X1564960Y1217322D01*
G01X1563090Y1211712D02*
X1564960Y1213582D01*
G01X1594882Y1120078D02*
X1593011Y1118208D01*
G01X1583661Y1120078D02*
X1585531Y1121948D01*
G01D02*
X1587401Y1120078D01*
G01Y1123818D02*
X1585531Y1121948D01*
G01D02*
X1583661Y1123818D01*
G01Y1120078D02*
X1581791Y1121948D01*
G01D02*
X1579921Y1120078D01*
G01Y1123818D02*
X1581791Y1121948D01*
G01D02*
X1583661Y1123818D01*
G01D02*
X1581791Y1125688D01*
G01X1583661Y1120078D02*
X1581791Y1118208D01*
G01X1585531Y1125688D02*
X1587401Y1123818D01*
G01X1589271Y1125688D02*
X1587401Y1123818D01*
G01X1594882D02*
X1596752Y1121948D01*
G01X1593011Y1125688D02*
X1594882Y1123818D01*
G01X1581791Y1125688D02*
X1579921Y1123818D01*
G01X1594882Y1120078D02*
X1596752Y1121948D01*
G01X1594882Y1120078D02*
X1596752Y1118208D01*
G01X1587401Y1116338D02*
X1589271Y1118208D01*
G01D02*
X1591141Y1120078D01*
G01X1589271Y1118208D02*
X1587401Y1120078D01*
G01Y1116338D02*
X1585531Y1114468D01*
G01X1587401Y1116338D02*
X1585531Y1118208D01*
G01D02*
X1583661Y1120078D01*
G01X1585531Y1118208D02*
X1587401Y1120078D01*
G01D02*
X1589271Y1121948D01*
G01D02*
X1591141Y1120078D01*
G01Y1123818D02*
X1589271Y1121948D01*
G01D02*
X1587401Y1123818D01*
G01X1591141D02*
X1593011Y1125688D01*
G01X1591141Y1120078D02*
X1593011Y1121948D01*
G01D02*
X1594882Y1120078D01*
G01Y1123818D02*
X1593011Y1121948D01*
G01D02*
X1591141Y1123818D01*
G01X1596752Y1125688D02*
X1594882Y1123818D01*
G01X1593011Y1118208D02*
X1591141Y1120078D01*
G01X1581791Y1118208D02*
X1579921Y1120078D01*
G01X1587401Y1127558D02*
X1585531Y1125688D01*
G01D02*
X1583661Y1127558D01*
G01X1591141D02*
X1589271Y1125688D01*
G01X1587401Y1127558D02*
X1589271Y1125688D01*
G01X1591141Y1127558D02*
X1593011Y1125688D01*
G01X1594882Y1127558D02*
X1596752Y1125688D01*
G01X1593011D02*
X1594882Y1127558D01*
G01X1583661D02*
X1581791Y1125688D01*
G01X1579921Y1127558D02*
X1581791Y1125688D01*
G01X1594882Y1135039D02*
X1596752Y1133169D01*
G01X1591141Y1135039D02*
X1593011Y1133169D01*
G01X1587401Y1135039D02*
X1589271Y1133169D01*
G01X1579921Y1135039D02*
X1581791Y1133169D01*
G01X1583661Y1135039D02*
X1585531Y1133169D01*
G01X1581791D02*
X1583661Y1135039D01*
G01X1593011Y1133169D02*
X1594882Y1135039D01*
G01X1589271Y1133169D02*
X1591141Y1135039D01*
G01X1585531Y1133169D02*
X1587401Y1135039D01*
G01X1594882Y1138779D02*
X1596752Y1136909D01*
G01X1591141Y1138779D02*
X1593011Y1136909D01*
G01X1587401Y1138779D02*
X1589271Y1136909D01*
G01X1587401Y1138779D02*
X1585531Y1136909D01*
G01X1579921Y1138779D02*
X1581791Y1136909D01*
G01X1593011D02*
X1594882Y1138779D01*
G01X1589271Y1136909D02*
X1591141Y1138779D01*
G01X1585531Y1136909D02*
X1583661Y1138779D01*
G01X1581791Y1136909D02*
X1583661Y1138779D01*
G01X1589271Y1129429D02*
X1591141Y1131299D01*
G01X1585531Y1129429D02*
X1587401Y1131299D01*
G01X1581791Y1129429D02*
X1583661Y1131299D01*
G01X1593011Y1129429D02*
X1594882Y1131299D01*
G01Y1149999D02*
X1596752Y1148129D01*
G01X1591141Y1149999D02*
X1593011Y1148129D01*
G01X1587401Y1149999D02*
X1589271Y1148129D01*
G01X1583661Y1149999D02*
X1585531Y1148129D01*
G01X1579921Y1149999D02*
X1581791Y1148129D01*
G01X1593011Y1155610D02*
X1594882Y1157480D01*
G01X1579921Y1142519D02*
X1581791Y1140649D01*
G01X1583661Y1142519D02*
X1585531Y1140649D01*
G01X1587401Y1142519D02*
X1589271Y1140649D01*
G01X1594882Y1142519D02*
X1596752Y1140649D01*
G01X1594882Y1142519D02*
X1593011Y1140649D01*
G01X1581791D02*
X1583661Y1142519D01*
G01X1585531Y1140649D02*
X1587401Y1142519D01*
G01X1589271Y1140649D02*
X1591141Y1142519D01*
G01X1593011Y1140649D02*
X1591141Y1142519D01*
G01X1593011Y1148129D02*
X1594882Y1149999D01*
G01X1589271Y1148129D02*
X1591141Y1149999D01*
G01X1585531Y1148129D02*
X1587401Y1149999D01*
G01X1581791Y1148129D02*
X1583661Y1149999D01*
G01X1585531Y1155610D02*
X1587401Y1157480D01*
G01X1594882Y1146259D02*
X1596752Y1144389D01*
G01X1591141Y1146259D02*
X1593011Y1144389D01*
G01X1587401Y1146259D02*
X1585531Y1144389D01*
G01X1583661Y1146259D02*
X1581791Y1144389D01*
G01X1587401Y1146259D02*
X1589271Y1144389D01*
G01X1585531D02*
X1583661Y1146259D01*
G01X1581791Y1144389D02*
X1579921Y1146259D01*
G01X1593011Y1144389D02*
X1594882Y1146259D01*
G01X1589271Y1144389D02*
X1591141Y1146259D01*
G01X1581791Y1151870D02*
X1583661Y1153740D01*
G01X1585531Y1151870D02*
X1587401Y1153740D01*
G01X1589271Y1151870D02*
X1591141Y1153740D01*
G01X1593012Y1151870D02*
X1594882Y1153740D01*
G01X1589271Y1155610D02*
X1591141Y1157480D01*
G01X1583661D02*
X1581791Y1155610D01*
G01X1593011Y1174310D02*
X1594882Y1172440D01*
G01D02*
X1596752Y1170570D01*
G01X1594882Y1157480D02*
X1596752Y1159350D01*
G01X1587401Y1157480D02*
X1589271Y1159350D01*
G01X1585531Y1174310D02*
X1587401Y1172440D01*
G01X1591141Y1168700D02*
X1589271Y1170570D01*
G01X1591141Y1168700D02*
X1591142D01*
X1593012Y1166830D01*
G01X1589271Y1170570D02*
X1587401Y1172440D01*
G01X1593012Y1166830D02*
X1594882Y1164960D01*
G01X1587401D02*
X1585531Y1166830D01*
G01X1583661Y1168700D02*
X1581791Y1170570D01*
G01X1585531Y1166830D02*
X1583661Y1168700D01*
G01Y1161220D02*
X1581791Y1159350D01*
G01D02*
X1579921Y1157480D01*
G01X1589271Y1159350D02*
X1591141Y1161220D01*
G01X1581791Y1170570D02*
X1579921Y1172440D01*
G01X1591141Y1157480D02*
X1593011Y1159350D01*
G01D02*
X1594882Y1161220D01*
G01X1583661Y1157480D02*
X1585531Y1159350D01*
G01D02*
X1587401Y1161220D01*
G01X1579921Y1168700D02*
X1581791Y1166830D01*
G01D02*
X1583661Y1164960D01*
G01X1581791Y1174310D02*
X1583661Y1172440D01*
G01D02*
X1585531Y1170570D01*
G01X1591141Y1164960D02*
X1589271Y1166830D01*
G01X1585531Y1170570D02*
X1587401Y1168700D01*
G01X1589271Y1166830D02*
X1587401Y1168700D01*
G01X1589271Y1174310D02*
X1591141Y1172440D01*
G01X1594882Y1168700D02*
X1596752Y1166830D01*
G01X1594882Y1168700D02*
X1593011Y1170570D01*
G01D02*
X1591141Y1172440D01*
G01X1594882Y1179921D02*
X1596752Y1181791D01*
G01X1594882Y1179921D02*
X1593011Y1181791D01*
G01X1591141Y1179921D02*
X1589271Y1181791D01*
G01X1587401Y1179921D02*
X1585531Y1181791D01*
G01X1583661Y1179921D02*
X1581791Y1181791D01*
G01X1594882Y1187401D02*
X1596752Y1189271D01*
G01X1594882Y1187401D02*
X1593011Y1189271D01*
G01X1591141Y1187401D02*
X1589271Y1189271D01*
G01X1587401Y1187401D02*
X1585531Y1189271D01*
G01X1583661Y1187401D02*
X1581791Y1189271D01*
G01X1593011Y1181791D02*
X1591141Y1179921D01*
G01X1589271Y1181791D02*
X1587401Y1179921D01*
G01X1585531Y1181791D02*
X1583661Y1179921D01*
G01X1581791Y1181791D02*
X1579921Y1179921D01*
G01X1593011Y1189271D02*
X1591141Y1187401D01*
G01X1589271Y1189271D02*
X1587401Y1187401D01*
G01X1585531Y1189271D02*
X1583661Y1187401D01*
G01X1581791Y1189271D02*
X1579921Y1187401D01*
G01X1594882Y1176180D02*
X1596752Y1178051D01*
G01X1594882Y1176180D02*
X1593011Y1178051D01*
G01X1579921Y1176180D02*
X1581791Y1178051D01*
G01X1583661Y1176180D02*
X1585531Y1178051D01*
G01X1591141Y1176180D02*
X1589271Y1178051D01*
G01X1581791D02*
X1583661Y1176180D01*
G01X1593011Y1178051D02*
X1591141Y1176180D01*
G01X1589271Y1178051D02*
X1587401Y1176180D01*
G01X1585531Y1178051D02*
X1587401Y1176180D01*
G01X1591141Y1183661D02*
X1589271Y1185531D01*
G01X1587401Y1183661D02*
X1585531Y1185531D01*
G01X1583661Y1183661D02*
X1581791Y1185531D01*
G01X1594882Y1183661D02*
X1596752Y1185531D01*
G01X1594882Y1183661D02*
X1593011Y1185531D01*
G01X1589271D02*
X1587401Y1183661D01*
G01X1585531Y1185531D02*
X1583661Y1183661D01*
G01X1581791Y1185531D02*
X1579921Y1183661D01*
G01X1593011Y1185531D02*
X1591141Y1183661D01*
G01X1594882Y1194881D02*
X1596752Y1196751D01*
G01X1591141Y1194881D02*
X1593011Y1196751D01*
G01X1587401Y1194881D02*
X1589271Y1196751D01*
G01X1583661Y1194881D02*
X1585531Y1196751D01*
G01X1579921Y1194881D02*
X1581791Y1196751D01*
G01X1596752Y1204232D02*
X1594882Y1202362D01*
G01X1591141D02*
X1593011Y1204232D01*
G01D02*
X1594882Y1202362D01*
G01Y1206102D02*
X1593011Y1204232D01*
G01D02*
X1591141Y1206102D01*
G01X1587401Y1202362D02*
X1589271Y1204232D01*
G01D02*
X1591141Y1202362D01*
G01Y1206102D02*
X1589271Y1204232D01*
G01D02*
X1587401Y1206102D01*
G01X1583661Y1202362D02*
X1585531Y1204232D01*
G01D02*
X1587401Y1202362D01*
G01Y1206102D02*
X1585531Y1204232D01*
G01D02*
X1583661Y1206102D01*
G01Y1202362D02*
X1581791Y1204232D01*
G01D02*
X1583661Y1206102D01*
G01X1579921D02*
X1581791Y1204232D01*
G01D02*
X1579921Y1202362D01*
G01X1593011Y1196751D02*
X1594882Y1194881D01*
G01X1589271Y1196751D02*
X1591141Y1194881D01*
G01X1585531Y1196751D02*
X1587401Y1194881D01*
G01X1581791Y1196751D02*
X1583661Y1194881D01*
G01X1581791Y1193011D02*
X1579921Y1191141D01*
G01X1593011Y1193011D02*
X1594882Y1191141D01*
G01X1589271Y1193011D02*
X1591141Y1191141D01*
G01X1585531Y1193011D02*
X1583661Y1191141D01*
G01X1591141D02*
X1593011Y1193011D01*
G01X1594882Y1191141D02*
X1596752Y1193011D01*
G01X1583661Y1191141D02*
X1581791Y1193011D01*
G01X1587401Y1191141D02*
X1585531Y1193011D01*
G01X1587401Y1191141D02*
X1589271Y1193011D01*
G01Y1200491D02*
X1591141Y1198621D01*
G01X1585531Y1200491D02*
X1587401Y1198621D01*
G01X1581791Y1200491D02*
X1583661Y1198621D01*
G01X1593011Y1200491D02*
X1594882Y1198621D01*
G01Y1206102D02*
X1596752Y1207972D01*
G01X1594882Y1206102D02*
X1596752Y1204232D01*
G01X1591141Y1206102D02*
X1593011Y1207972D01*
G01D02*
X1594882Y1206102D01*
G01Y1209842D02*
X1593011Y1207972D01*
G01D02*
X1591141Y1209842D01*
G01X1596752Y1207972D02*
X1594882Y1209842D01*
G01X1587401Y1206102D02*
X1589271Y1207972D01*
G01D02*
X1591141Y1206102D01*
G01Y1209842D02*
X1589271Y1207972D01*
G01D02*
X1587401Y1209842D01*
G01X1583661Y1206102D02*
X1585531Y1207972D01*
G01D02*
X1587401Y1206102D01*
G01Y1209842D02*
X1585531Y1207972D01*
G01D02*
X1583661Y1209842D01*
G01Y1206102D02*
X1581791Y1207972D01*
G01D02*
X1579921Y1206102D01*
G01Y1209842D02*
X1581791Y1207972D01*
G01D02*
X1583661Y1209842D01*
G01X1579921D02*
X1581791Y1211712D01*
G01X1591141Y1217322D02*
X1593011Y1219192D01*
G01X1598622Y1120078D02*
X1600492Y1121948D01*
G01D02*
X1602362Y1120078D01*
G01Y1123818D02*
X1600492Y1121948D01*
G01D02*
X1598622Y1123818D01*
G01D02*
X1600492Y1125688D01*
G01X1602362Y1116338D02*
X1600492Y1118208D01*
G01D02*
X1598622Y1120078D01*
G01X1602362D02*
X1600492Y1118208D01*
G01X1598622Y1123818D02*
X1596752Y1121948D01*
G01X1602362Y1116338D02*
X1600492Y1114468D01*
G01Y1125688D02*
X1602362Y1123818D01*
G01X1611712Y1125688D02*
X1609842Y1123818D01*
G01X1611712Y1121948D02*
X1609842Y1123818D01*
G01X1607972Y1121948D02*
X1609842Y1120078D01*
G01X1606102Y1123818D02*
X1607972Y1121948D01*
G01Y1125688D02*
X1609842Y1123818D01*
G01Y1120078D02*
X1611712Y1121948D01*
G01X1606102Y1123818D02*
X1607972Y1125688D01*
G01X1596752Y1121948D02*
X1598622Y1120078D01*
G01X1596752Y1125688D02*
X1598622Y1123818D01*
G01X1600492Y1114468D02*
X1602362Y1112598D01*
G01X1596752Y1118208D02*
X1598622Y1120078D01*
G01X1602362Y1127558D02*
X1600492Y1125688D01*
G01X1598622Y1127558D02*
X1600492Y1125688D01*
G01X1598622Y1127558D02*
X1596752Y1125688D01*
G01X1609842Y1127558D02*
X1611712Y1125688D01*
G01X1606102Y1127558D02*
X1607972Y1125688D01*
G01X1609842Y1127558D02*
X1607972Y1125688D01*
G01X1609842Y1135039D02*
X1611712Y1133169D01*
G01X1606102Y1135039D02*
X1607677Y1133464D01*
X1607972D01*
G01D02*
X1609547Y1135039D01*
X1609842D01*
G01X1598622D02*
Y1134645D01*
X1600590Y1132677D01*
G01D02*
X1602362Y1134448D01*
Y1135039D01*
G01X1596752Y1133169D02*
X1598622Y1135039D01*
G01Y1138779D02*
X1600492Y1136909D01*
G01D02*
X1602362Y1138779D01*
G01X1596752Y1136909D02*
X1598622Y1138779D01*
G01X1609842D02*
X1611712Y1136909D01*
G01X1606102Y1138779D02*
X1607972Y1136909D01*
G01D02*
X1609842Y1138779D01*
G01X1611712Y1129429D02*
X1609842Y1131299D01*
G01X1607972Y1129429D02*
X1606102Y1131299D01*
G01X1600492Y1129429D02*
X1602362Y1131299D01*
G01X1596752Y1129429D02*
X1598622Y1131299D01*
G01X1609842Y1149999D02*
X1611712Y1148129D01*
G01X1609842Y1142519D02*
X1611712Y1140649D01*
G01X1606102Y1142519D02*
X1607972Y1140649D01*
G01X1609842Y1149999D02*
X1607972Y1148129D01*
G01X1602362Y1149999D02*
X1600492Y1148129D01*
G01D02*
X1598622Y1149999D01*
G01X1596752Y1148129D02*
X1598622Y1149999D01*
G01X1607972Y1148129D02*
X1606102Y1149999D01*
G01X1602362Y1157480D02*
X1600492Y1155610D01*
G01X1611712D02*
X1609842Y1157480D01*
G01X1598622Y1142519D02*
X1600492Y1140649D01*
G01X1596752D02*
X1598622Y1142519D01*
G01X1600492Y1140649D02*
X1602362Y1142519D01*
G01X1607972Y1140649D02*
X1609842Y1142519D01*
G01X1598622Y1146259D02*
X1600492Y1144389D01*
G01D02*
X1602362Y1146259D01*
G01X1596752Y1144389D02*
X1598622Y1146259D01*
G01X1596752Y1151870D02*
X1598622Y1153740D01*
G01X1600492Y1151870D02*
X1602362Y1153740D01*
G01X1609842Y1146259D02*
X1611712Y1144389D01*
G01X1606102Y1146259D02*
X1607972Y1144389D01*
G01D02*
X1609842Y1146259D01*
G01Y1153740D02*
X1611712Y1151869D01*
G01X1606102Y1153740D02*
X1607972Y1151869D01*
G01D02*
X1609842Y1153740D01*
G01X1606102Y1157480D02*
X1607972Y1155610D01*
G01X1596752D02*
X1598622Y1157480D01*
G01X1609842Y1164960D02*
X1611712Y1166830D01*
G01X1606102Y1161220D02*
X1607972Y1159350D01*
G01X1602362Y1164960D02*
X1600492Y1166830D01*
G01X1596752Y1170570D02*
X1598622Y1168700D01*
G01X1596752Y1159350D02*
X1598622Y1161220D01*
G01X1611712Y1174310D02*
X1609842Y1172440D01*
G01X1606102Y1168700D02*
X1607972Y1170570D01*
G01D02*
X1609842Y1172440D01*
G01X1600492Y1166830D02*
X1598622Y1168700D01*
G01X1607972Y1159350D02*
X1609842Y1157480D01*
G01X1602362Y1172440D02*
X1600492Y1174310D01*
G01X1598622Y1157480D02*
X1600492Y1159350D01*
G01D02*
X1602362Y1161220D01*
G01X1609842D02*
X1611712Y1159350D01*
G01X1596752Y1166830D02*
X1598622Y1164960D01*
G01X1596752Y1174310D02*
X1598622Y1172440D01*
G01X1602362Y1168700D02*
X1600492Y1170570D01*
G01D02*
X1598622Y1172440D01*
G01X1609842Y1168700D02*
X1611712Y1170570D01*
G01X1606102Y1164960D02*
X1607972Y1166830D01*
G01X1606102Y1172440D02*
X1607972Y1174310D01*
G01X1602362Y1179921D02*
X1600492Y1181791D01*
G01X1602362Y1187401D02*
X1600492Y1189271D01*
G01Y1181791D02*
X1598622Y1179921D01*
G01X1609842Y1187401D02*
X1611712Y1189271D01*
G01X1609842Y1187401D02*
X1607972Y1189271D01*
G01X1609842Y1179921D02*
X1611712Y1181791D01*
G01X1609842Y1179921D02*
X1607972Y1181791D01*
G01D02*
X1606102Y1179921D01*
G01X1607972Y1189271D02*
X1606102Y1187401D01*
G01X1596752Y1181791D02*
X1598622Y1179921D01*
G01X1600492Y1189271D02*
X1598622Y1187401D01*
G01X1596752Y1189271D02*
X1598622Y1187401D01*
G01X1602362Y1176180D02*
X1600492Y1178051D01*
G01D02*
X1598622Y1176180D01*
G01X1596752Y1178051D02*
X1598622Y1176180D01*
G01Y1183661D02*
X1600492Y1185531D01*
G01D02*
X1602362Y1183661D01*
G01X1596752Y1185531D02*
X1598622Y1183661D01*
G01X1609842Y1176180D02*
X1611712Y1178051D01*
G01X1606102Y1176180D02*
X1607972Y1178051D01*
G01D02*
X1609842Y1176180D01*
G01Y1183661D02*
X1611712Y1185531D01*
G01X1606102Y1183661D02*
X1607972Y1185531D01*
G01D02*
X1609842Y1183661D01*
G01X1602362Y1194881D02*
X1600492Y1196751D01*
G01X1609842Y1202362D02*
X1607972Y1204232D01*
G01D02*
X1609842Y1206102D01*
G01X1607972Y1204232D02*
X1606102Y1206102D01*
G01X1611712Y1204232D02*
X1609842Y1206102D01*
G01Y1194881D02*
X1611712Y1196751D01*
G01X1609842Y1202362D02*
X1611712Y1204232D01*
G01X1607972D02*
X1606102Y1202362D01*
G01Y1194881D02*
X1607972Y1196751D01*
G01X1598622Y1202362D02*
X1600492Y1204232D01*
G01D02*
X1602362Y1202362D01*
G01Y1206102D02*
X1600492Y1204232D01*
G01D02*
X1598622Y1206102D01*
G01D02*
X1596752Y1204232D01*
G01D02*
X1598622Y1202362D01*
G01X1607972Y1196751D02*
X1609842Y1194881D01*
G01X1600492Y1196751D02*
X1598622Y1194881D01*
G01X1596752Y1196751D02*
X1598622Y1194881D01*
G01X1607972Y1193011D02*
X1606102Y1191141D01*
G01X1609842D02*
X1607972Y1193011D01*
G01X1609842Y1191141D02*
X1611712Y1193011D01*
G01X1596752D02*
X1598622Y1191141D01*
G01X1600492Y1193011D02*
X1598622Y1191141D01*
G01X1602362D02*
X1600492Y1193011D01*
G01Y1200491D02*
X1602362Y1198621D01*
G01X1596752Y1200491D02*
X1598622Y1198621D01*
G01X1611712Y1200491D02*
X1609842Y1198621D01*
G01X1607972Y1200491D02*
X1606102Y1198621D01*
G01X1611712Y1207972D02*
X1609842Y1209842D01*
G01D02*
X1607972Y1207972D01*
G01D02*
X1606102Y1209842D01*
G01Y1206102D02*
X1607972Y1207972D01*
G01D02*
X1609842Y1206102D01*
G01Y1209842D02*
X1611712Y1211712D01*
G01X1609842Y1206102D02*
X1611712Y1207972D01*
G01X1598622Y1206102D02*
X1600492Y1207972D01*
G01D02*
X1602362Y1206102D01*
G01Y1209842D02*
X1600492Y1207972D01*
G01D02*
X1598622Y1209842D01*
G01Y1206102D02*
X1596752Y1207972D01*
G01D02*
X1598622Y1209842D01*
G01X1613582Y1120078D02*
X1615452Y1121948D01*
G01D02*
X1617322Y1120078D01*
G01Y1123818D02*
X1615452Y1121948D01*
G01D02*
X1613582Y1123818D01*
G01X1624803Y1120078D02*
X1626673Y1121948D01*
G01D02*
X1628543Y1120078D01*
G01Y1123818D02*
X1626673Y1121948D01*
G01D02*
X1624803Y1123818D01*
G01X1621063D02*
X1622933Y1121948D01*
G01D02*
X1621063Y1120078D01*
G01X1624803Y1123818D02*
X1622933Y1121948D01*
G01D02*
X1624803Y1120078D01*
G01X1621063Y1123818D02*
X1619193Y1121948D01*
G01D02*
X1617322Y1123818D01*
G01Y1120078D02*
X1619193Y1121948D01*
G01D02*
X1621063Y1120078D01*
G01X1617322Y1123818D02*
X1619193Y1125688D01*
G01X1617322Y1123818D02*
X1615452Y1125688D01*
G01X1621063Y1123818D02*
X1622933Y1125688D01*
G01X1613582Y1120078D02*
X1611712Y1121948D01*
G01X1619193Y1125688D02*
X1621063Y1123818D01*
G01X1615452Y1125688D02*
X1613582Y1123818D01*
G01X1622933Y1125688D02*
X1624803Y1123818D01*
G01X1626673Y1125688D02*
X1624803Y1123818D01*
G01X1611712Y1125688D02*
X1613582Y1123818D01*
G01X1611712Y1121948D02*
X1613582Y1123818D01*
G01Y1127558D02*
X1611712Y1125688D01*
G01X1621063Y1127558D02*
X1619193Y1125688D01*
G01X1613582Y1127558D02*
X1615452Y1125688D01*
G01X1624803Y1127558D02*
X1622933Y1125688D01*
G01X1615452D02*
X1617322Y1127558D01*
G01X1622933Y1125688D02*
X1621063Y1127558D01*
G01X1619193Y1125688D02*
X1617322Y1127558D01*
G01X1624803D02*
X1626673Y1125688D01*
G01X1628543Y1127558D02*
X1626673Y1125688D01*
G01X1628543Y1123818D02*
X1626673Y1125688D01*
G01X1613582Y1135039D02*
X1615452Y1133169D01*
G01X1617322Y1135039D02*
X1619193Y1133169D01*
G01X1621063Y1135039D02*
X1622933Y1133169D01*
G01X1624803Y1135039D02*
X1626673Y1133169D01*
G01X1615452D02*
X1617322Y1135039D01*
G01X1619193Y1133169D02*
X1621063Y1135039D01*
G01X1622933Y1133169D02*
X1624803Y1135039D01*
G01X1626673Y1133169D02*
X1628543Y1135039D01*
G01X1611712Y1133169D02*
X1613582Y1135039D01*
G01X1624803Y1138779D02*
X1626673Y1136909D01*
G01X1621063Y1138779D02*
X1622933Y1136909D01*
G01X1613582Y1138779D02*
X1615452Y1136909D01*
G01X1617322Y1138779D02*
X1619193Y1136909D01*
G01X1626673D02*
X1628543Y1138779D01*
G01X1622933Y1136909D02*
X1624803Y1138779D01*
G01X1615452Y1136909D02*
X1617322Y1138779D01*
G01X1619193Y1136909D02*
X1621063Y1138779D01*
G01X1611712Y1136909D02*
X1613582Y1138779D01*
G01X1626673Y1129429D02*
X1624803Y1131299D01*
G01X1622933Y1129429D02*
X1621063Y1131299D01*
G01X1619193Y1129429D02*
X1617322Y1131299D01*
G01X1615452Y1129429D02*
X1613582Y1131299D01*
G01X1617322Y1142519D02*
X1615452Y1140649D01*
G01X1621063Y1142519D02*
X1619193Y1140649D01*
G01X1624803Y1142519D02*
X1622933Y1140649D01*
G01X1628543Y1142519D02*
X1626673Y1140649D01*
G01X1613582Y1149999D02*
X1615452Y1148129D01*
G01X1621063Y1149999D02*
X1619193Y1148129D01*
G01X1621063Y1149999D02*
X1622933Y1148129D01*
G01X1624803Y1149999D02*
X1626673Y1148129D01*
G01X1615452Y1140649D02*
X1613582Y1142519D01*
G01X1619193Y1140649D02*
X1617322Y1142519D01*
G01X1622933Y1140649D02*
X1621063Y1142519D01*
G01X1626673Y1140649D02*
X1624803Y1142519D01*
G01X1615452Y1148129D02*
X1617322Y1149999D01*
G01X1619193Y1148129D02*
X1617322Y1149999D01*
G01X1622933Y1148129D02*
X1624803Y1149999D01*
G01X1626673Y1148129D02*
X1628543Y1149999D01*
G01X1619193Y1155610D02*
X1617322Y1157480D01*
G01X1626673Y1155610D02*
X1624803Y1157480D01*
G01X1611712Y1148129D02*
X1613582Y1149999D01*
G01X1611712Y1140649D02*
X1613582Y1142519D01*
G01X1624803Y1146259D02*
X1622933Y1144389D01*
G01X1613582Y1146259D02*
X1615452Y1144389D01*
G01X1617322Y1146259D02*
X1619193Y1144389D01*
G01X1624803Y1146259D02*
X1626673Y1144389D01*
G01X1622933D02*
X1621063Y1146259D01*
G01X1615452Y1144389D02*
X1617322Y1146259D01*
G01X1619193Y1144389D02*
X1621063Y1146259D01*
G01X1626673Y1144389D02*
X1628543Y1146259D01*
G01X1611712Y1144389D02*
X1613582Y1146259D01*
G01X1617322Y1153740D02*
X1619193Y1151869D01*
G01X1624803Y1153740D02*
X1622933Y1151869D01*
G01X1617322Y1153740D02*
X1615452Y1151869D01*
G01X1624803Y1153740D02*
X1626673Y1151869D01*
G01X1615452D02*
X1613582Y1153740D01*
G01X1619193Y1151869D02*
X1621063Y1153740D01*
G01X1626673Y1151869D02*
X1628543Y1153740D01*
G01X1622933Y1151869D02*
X1621063Y1153740D01*
G01X1611712Y1151869D02*
X1613582Y1153740D01*
G01X1615452Y1155610D02*
X1613582Y1157480D01*
G01X1622933Y1155610D02*
X1621063Y1157480D01*
G01X1628543Y1168700D02*
X1626673Y1166830D01*
G01X1617322Y1157480D02*
X1615452Y1159350D01*
G01X1624803Y1157480D02*
X1622933Y1159350D01*
G01X1619193Y1174310D02*
X1617322Y1172440D01*
G01D02*
X1615452Y1170570D01*
G01D02*
X1613582Y1168700D01*
G01X1626673Y1174310D02*
X1624803Y1172440D01*
G01X1621063Y1168700D02*
X1622933Y1170570D01*
G01X1617322Y1164960D02*
X1619193Y1166830D01*
G01X1622933Y1170570D02*
X1624803Y1172440D01*
G01X1626673Y1166830D02*
X1624803Y1164960D01*
G01X1615452Y1159350D02*
X1613582Y1161220D01*
G01X1619193Y1166830D02*
X1621063Y1168700D01*
G01X1622933Y1159350D02*
X1621063Y1161220D01*
G01X1611712Y1166830D02*
X1613582Y1168700D01*
G01X1611712Y1159350D02*
X1613582Y1157480D01*
G01X1621063D02*
X1619193Y1159350D01*
G01D02*
X1617322Y1161220D01*
G01X1624803D02*
X1626673Y1159350D01*
G01D02*
X1628543Y1157480D01*
G01X1615452Y1174310D02*
X1613582Y1172440D01*
G01X1611712Y1170570D02*
X1613582Y1172440D01*
G01X1621063Y1164960D02*
X1622933Y1166830D01*
G01X1624803Y1168700D02*
X1626673Y1170570D01*
G01X1622933Y1166830D02*
X1624803Y1168700D01*
G01X1626673Y1170570D02*
X1628543Y1172440D01*
G01X1622933Y1174310D02*
X1621063Y1172440D01*
G01X1613582Y1164960D02*
X1615452Y1166830D01*
G01X1617322Y1168700D02*
X1619193Y1170570D01*
G01X1615452Y1166830D02*
X1617322Y1168700D01*
G01X1619193Y1170570D02*
X1621063Y1172440D01*
G01X1613582Y1187401D02*
X1615452Y1189271D01*
G01X1617322Y1187401D02*
X1619193Y1189271D01*
G01X1621063Y1187401D02*
X1622933Y1189271D01*
G01X1624803Y1187401D02*
X1626673Y1189271D01*
G01X1617322Y1179921D02*
X1615452Y1181791D01*
G01X1617322Y1179921D02*
X1619193Y1181791D01*
G01X1621063Y1179921D02*
X1622933Y1181791D01*
G01X1624803Y1179921D02*
X1626673Y1181791D01*
G01X1615452D02*
X1613582Y1179921D01*
G01X1619193Y1181791D02*
X1621063Y1179921D01*
G01X1622933Y1181791D02*
X1624803Y1179921D01*
G01X1626673Y1181791D02*
X1628543Y1179921D01*
G01X1615452Y1189271D02*
X1617322Y1187401D01*
G01X1619193Y1189271D02*
X1621063Y1187401D01*
G01X1622933Y1189271D02*
X1624803Y1187401D01*
G01X1626673Y1189271D02*
X1628543Y1187401D01*
G01X1611712Y1181791D02*
X1613582Y1179921D01*
G01X1611712Y1189271D02*
X1613582Y1187401D01*
G01X1621063Y1176180D02*
X1622933Y1178051D01*
G01X1613582Y1176180D02*
X1615452Y1178051D01*
G01X1617322Y1176180D02*
X1619193Y1178051D01*
G01X1624803Y1176180D02*
X1626673Y1178051D01*
G01X1622933D02*
X1624803Y1176180D01*
G01X1615452Y1178051D02*
X1617322Y1176180D01*
G01X1619193Y1178051D02*
X1621063Y1176180D01*
G01X1626673Y1178051D02*
X1628543Y1176180D01*
G01X1611712Y1178051D02*
X1613582Y1176180D01*
G01X1628543Y1183661D02*
X1626673Y1185531D01*
G01X1613582Y1183661D02*
X1615452Y1185531D01*
G01X1621063Y1183661D02*
X1619193Y1185531D01*
G01X1621063Y1183661D02*
X1622933Y1185531D01*
G01X1619193D02*
X1617322Y1183661D01*
G01X1626673Y1185531D02*
X1624803Y1183661D01*
G01X1622933Y1185531D02*
X1624803Y1183661D01*
G01X1615452Y1185531D02*
X1617322Y1183661D01*
G01X1611712Y1185531D02*
X1613582Y1183661D01*
G01X1628543Y1206102D02*
X1626673Y1204232D01*
G01D02*
X1624803Y1206102D01*
G01X1626673Y1204232D02*
X1624803Y1202362D01*
G01D02*
X1622933Y1204232D01*
G01D02*
X1624803Y1206102D01*
G01X1622933Y1204232D02*
X1621063Y1206102D01*
G01Y1202362D02*
X1622933Y1204232D01*
G01X1613582Y1202362D02*
X1615452Y1204232D01*
G01D02*
X1617322Y1202362D01*
G01Y1206102D02*
X1615452Y1204232D01*
G01D02*
X1613582Y1206102D01*
G01X1617322D02*
X1619193Y1204232D01*
G01D02*
X1621063Y1206102D01*
G01Y1202362D02*
X1619193Y1204232D01*
G01D02*
X1617322Y1202362D01*
G01X1613582Y1206102D02*
X1611712Y1204232D01*
G01X1613582Y1194881D02*
X1615452Y1196751D01*
G01X1617322Y1194881D02*
X1619193Y1196751D01*
G01X1621063Y1194881D02*
X1622933Y1196751D01*
G01X1624803Y1194881D02*
X1626673Y1196751D01*
G01X1611712Y1204232D02*
X1613582Y1202362D01*
G01X1615452Y1196751D02*
X1617322Y1194881D01*
G01X1619193Y1196751D02*
X1621063Y1194881D01*
G01X1622933Y1196751D02*
X1624803Y1194881D01*
G01X1626673Y1196751D02*
X1628543Y1194881D01*
G01X1611712Y1196751D02*
X1613582Y1194881D01*
G01X1621063Y1191141D02*
X1622933Y1193011D01*
G01X1624803Y1191141D02*
X1626673Y1193011D01*
G01X1613582Y1191141D02*
X1615452Y1193011D01*
G01X1617322Y1191141D02*
X1619193Y1193011D01*
G01X1622933Y1200491D02*
X1621063Y1198621D01*
G01X1619193Y1200491D02*
X1617322Y1198621D01*
G01X1615452Y1200491D02*
X1613582Y1198621D01*
G01X1626673Y1200491D02*
X1624803Y1198621D01*
G01X1613582Y1209842D02*
X1615452Y1207972D01*
G01D02*
X1617322Y1209842D01*
G01Y1206102D02*
X1615452Y1207972D01*
G01D02*
X1613582Y1206102D01*
G01X1617322D02*
X1619193Y1207972D01*
G01D02*
X1621063Y1206102D01*
G01Y1209842D02*
X1619193Y1207972D01*
G01D02*
X1617322Y1209842D01*
G01X1621063Y1206102D02*
X1622933Y1207972D01*
G01D02*
X1621063Y1209842D01*
G01X1624803Y1206102D02*
X1622933Y1207972D01*
G01D02*
X1624803Y1209842D01*
G01Y1206102D02*
X1626673Y1207972D01*
G01D02*
X1624803Y1209842D01*
G01X1628543D02*
X1626673Y1207972D01*
G01D02*
X1628543Y1206102D01*
G01X1613582D02*
X1611712Y1207972D01*
G01X1628543Y1209842D02*
X1626673Y1211712D01*
G01X1613582Y1209842D02*
X1615452Y1211712D01*
G01X1611712Y1207972D02*
X1613582Y1209842D01*
G01X1626673Y1211712D02*
X1624803Y1209842D01*
G01X1615452Y1211712D02*
X1617322Y1209842D01*
G01X1611712Y1211712D02*
X1613582Y1209842D01*
G01X1643504Y1120078D02*
X1645374Y1121948D01*
G01X1643504Y1120078D02*
X1645374Y1118208D01*
G01X1634153Y1125688D02*
X1636023Y1123818D01*
G01X1637893Y1125688D02*
X1636023Y1123818D01*
G01X1630413Y1125688D02*
X1632283Y1123818D01*
G01X1643504D02*
X1641633Y1121948D01*
G01D02*
X1643504Y1120078D01*
G01X1639763Y1123818D02*
X1641633Y1121948D01*
G01D02*
X1639763Y1120078D01*
G01Y1123818D02*
X1637893Y1125688D01*
G01X1639763Y1120078D02*
X1641633Y1118208D01*
G01X1636023Y1123818D02*
X1637893Y1121948D01*
G01D02*
X1639763Y1120078D01*
G01X1636023D02*
X1637893Y1121948D01*
G01X1632283Y1120078D02*
X1634153Y1121948D01*
G01D02*
X1636023Y1120078D01*
G01Y1123818D02*
X1634153Y1121948D01*
G01D02*
X1632283Y1123818D01*
G01X1628543Y1120078D02*
X1630413Y1121948D01*
G01D02*
X1632283Y1120078D01*
G01Y1123818D02*
X1630413Y1121948D01*
G01D02*
X1628543Y1123818D01*
G01X1632283D02*
X1634153Y1125688D01*
G01X1628543Y1123818D02*
X1630413Y1125688D01*
G01X1645374D02*
X1643504Y1123818D01*
G01X1641633Y1125688D02*
X1643504Y1123818D01*
G01X1636023Y1127558D02*
X1637893Y1125688D01*
G01X1636023Y1127558D02*
X1634153Y1125688D01*
G01X1632283Y1127558D02*
X1634153Y1125688D01*
G01X1637893D02*
X1639763Y1127558D01*
G01X1643504D02*
X1645374Y1125688D01*
G01X1639763Y1127558D02*
X1641633Y1125688D01*
G01X1632283Y1127558D02*
X1630413Y1125688D01*
G01X1628543Y1127558D02*
X1630413Y1125688D01*
G01X1639763Y1127558D02*
X1641633Y1129429D01*
G01X1639763Y1138779D02*
X1641633Y1136909D01*
G01X1628543Y1135039D02*
X1630413Y1133169D01*
G01X1632283Y1135039D02*
X1634153Y1133169D01*
G01X1636023Y1135039D02*
X1637893Y1133169D01*
G01X1639763Y1135039D02*
X1641633Y1133169D01*
G01Y1136909D02*
X1643504Y1135039D01*
G01X1630413Y1133169D02*
X1632283Y1135039D01*
G01X1634153Y1133169D02*
X1636023Y1135039D01*
G01X1637893Y1133169D02*
X1639763Y1135039D01*
G01X1641633Y1133169D02*
X1643504Y1135039D01*
G01X1641633Y1129429D02*
X1639763Y1131299D01*
G01X1637893Y1136909D02*
X1636023Y1138779D01*
G01X1628543D02*
X1630413Y1136909D01*
G01X1632283Y1138779D02*
X1634153Y1136909D01*
G01X1630413D02*
X1632283Y1138779D01*
G01X1634153Y1136909D02*
X1636023Y1138779D01*
G01X1630413Y1129429D02*
X1628543Y1131299D01*
G01X1637893Y1129429D02*
X1636023Y1131299D01*
G01X1634153Y1129429D02*
X1632283Y1131299D01*
G01X1643504D02*
X1645374Y1129429D01*
G01Y1140649D02*
X1643504Y1138779D01*
G01X1645374Y1136909D02*
X1643504Y1138779D01*
G01X1628543Y1149999D02*
X1630413Y1148129D01*
G01X1636023Y1149999D02*
X1634153Y1148129D01*
G01X1645374D02*
X1643504Y1149999D01*
G01X1645374Y1151869D02*
X1643504Y1149999D01*
G01Y1157480D02*
X1641633Y1155610D01*
G01D02*
X1643504Y1153740D01*
G01X1641633Y1155610D02*
X1639763Y1157480D01*
G01X1645374Y1151869D02*
X1643504Y1153740D01*
G01D02*
X1645374Y1155610D01*
G01X1639763Y1153740D02*
X1641633Y1151869D01*
G01D02*
X1643504Y1153740D01*
G01X1639763Y1149999D02*
X1641633Y1151869D01*
G01D02*
X1643504Y1149999D01*
G01X1639763D02*
X1641633Y1148129D01*
G01D02*
X1643504Y1149999D01*
G01X1641633Y1148129D02*
X1639763Y1146259D01*
G01Y1149999D02*
X1637893Y1148129D01*
G01X1641633Y1140649D02*
X1639763Y1142519D01*
G01D02*
X1641633Y1144389D01*
G01X1632283Y1142519D02*
X1634153Y1140649D01*
G01X1636023Y1142519D02*
X1637893Y1140649D01*
G01X1628543Y1142519D02*
X1630413Y1140649D01*
G01X1641633Y1155610D02*
X1639763Y1153740D01*
G01X1634153Y1140649D02*
X1636023Y1142519D01*
G01X1637893Y1140649D02*
X1639763Y1142519D01*
G01X1630413Y1140649D02*
X1632283Y1142519D01*
G01X1630413Y1148129D02*
X1632283Y1149999D01*
G01X1634153Y1148129D02*
X1632283Y1149999D01*
G01X1637893Y1148129D02*
X1636023Y1149999D01*
G01X1641633Y1144389D02*
X1639763Y1146259D01*
G01X1634153Y1155610D02*
X1632283Y1157480D01*
G01X1637893Y1144389D02*
X1636023Y1146259D01*
G01D02*
X1634153Y1144389D01*
G01X1628543Y1146259D02*
X1630413Y1144389D01*
G01X1634153D02*
X1632283Y1146259D01*
G01X1630413Y1144389D02*
X1632283Y1146259D01*
G01X1637893Y1151869D02*
X1636023Y1153740D01*
G01X1628543D02*
X1630413Y1151869D01*
G01X1632283Y1153740D02*
X1634153Y1151869D01*
G01X1630413D02*
X1632283Y1153740D01*
G01X1634153Y1151869D02*
X1636023Y1153740D01*
G01X1628543Y1157480D02*
X1630413Y1155610D01*
G01X1636023Y1157480D02*
X1637893Y1155610D01*
G01X1645374Y1144389D02*
X1643504Y1146259D01*
G01Y1142519D02*
X1645374Y1144389D01*
G01X1643504Y1142519D02*
X1645374Y1140649D01*
G01X1643504Y1172440D02*
X1645374Y1174310D01*
G01X1643504Y1172440D02*
X1641633Y1174310D01*
G01D02*
X1639763Y1172440D01*
G01X1643504Y1164960D02*
X1645374Y1166830D01*
G01X1643504Y1168700D02*
X1645374Y1170570D01*
G01Y1166830D02*
X1643504Y1168700D01*
G01Y1157480D02*
X1645374Y1155610D01*
G01X1643504Y1161220D02*
X1645374Y1159350D01*
G01D02*
X1643504Y1157480D01*
G01X1645374Y1170570D02*
X1643504Y1172440D01*
G01X1634153Y1174310D02*
X1632283Y1172440D01*
G01X1628543Y1168700D02*
X1630413Y1170570D01*
G01X1628543Y1161220D02*
X1630413Y1159350D01*
G01X1632283Y1164960D02*
X1634153Y1166830D01*
G01X1630413Y1159350D02*
X1632283Y1157480D01*
G01X1630413Y1170570D02*
X1632283Y1172440D01*
G01X1641633Y1159350D02*
X1639763Y1161220D01*
G01D02*
X1637893Y1159350D01*
G01X1632283Y1161220D02*
X1634153Y1159350D01*
G01X1637893D02*
X1636023Y1161220D01*
G01X1634153Y1159350D02*
X1636023Y1161220D01*
G01X1641633Y1166830D02*
X1639763Y1164960D01*
G01D02*
X1637893Y1166830D01*
G01D02*
X1636023Y1164960D01*
G01X1639763Y1168700D02*
X1641633Y1170570D01*
G01X1636023Y1168700D02*
X1637893Y1170570D01*
G01X1632283Y1168700D02*
X1634153Y1170570D01*
G01X1637893D02*
X1639763Y1168700D01*
G01X1634153Y1170570D02*
X1636023Y1168700D01*
G01X1628543Y1172440D02*
X1630413Y1174310D01*
G01X1628543Y1164960D02*
X1630413Y1166830D01*
G01X1636023Y1172440D02*
X1637893Y1174310D01*
G01X1641633Y1178051D02*
X1639763Y1176180D01*
G01X1641633Y1174310D02*
X1639763Y1176180D01*
G01X1636023Y1187401D02*
X1637893Y1189271D01*
G01D02*
X1639763Y1191141D01*
G01X1637893Y1189271D02*
X1639763Y1187401D01*
G01D02*
X1641633Y1189271D01*
G01X1632283Y1187401D02*
X1634153Y1189271D01*
G01X1628543Y1187401D02*
X1630413Y1189271D01*
G01X1634153D02*
X1636023Y1187401D01*
G01X1632283Y1179921D02*
X1630413Y1181791D01*
G01X1636023Y1179921D02*
X1634153Y1181791D01*
G01X1639763Y1183661D02*
X1641633Y1185531D01*
G01X1639763Y1183661D02*
X1637893Y1181791D01*
G01X1630413D02*
X1628543Y1179921D01*
G01X1634153Y1181791D02*
X1632283Y1179921D01*
G01X1637893Y1181791D02*
X1636023Y1179921D01*
G01X1630413Y1189271D02*
X1632283Y1187401D01*
G01X1639763Y1179921D02*
X1641633Y1181791D01*
G01X1634153Y1178051D02*
X1632283Y1176180D01*
G01X1628543D02*
X1630413Y1178051D01*
G01D02*
X1632283Y1176180D01*
G01X1634153Y1185531D02*
X1632283Y1183661D01*
G01X1628543D02*
X1630413Y1185531D01*
G01D02*
X1632283Y1183661D01*
G01X1636023Y1176180D02*
X1637893Y1178051D01*
G01X1636023Y1183661D02*
X1637893Y1185531D01*
G01X1643504Y1183661D02*
X1645374Y1185531D01*
G01X1643504Y1187401D02*
X1645374Y1189271D01*
G01X1643504Y1176180D02*
X1645374Y1178051D01*
G01X1628543Y1206102D02*
X1630413Y1204232D01*
G01D02*
X1628543Y1202362D01*
G01X1632283D02*
X1630413Y1204232D01*
G01D02*
X1632283Y1206102D01*
G01X1639763D02*
X1641633Y1204232D01*
G01D02*
X1643504Y1206102D01*
G01Y1202362D02*
X1641633Y1204232D01*
G01D02*
X1639763Y1202362D01*
G01X1636023Y1206102D02*
X1637893Y1204232D01*
G01D02*
X1639763Y1206102D01*
G01Y1202362D02*
X1637893Y1204232D01*
G01D02*
X1636023Y1202362D01*
G01X1639763D02*
X1641633Y1200491D01*
G01D02*
X1643504Y1202362D01*
G01Y1194881D02*
X1645374Y1196751D01*
G01X1643504Y1194881D02*
X1641653Y1196732D01*
G01D02*
X1639763Y1198621D01*
G01X1641653Y1196732D02*
X1641614D01*
X1639763Y1194881D01*
G01X1641633Y1200491D02*
X1639763Y1198621D01*
G01X1636023Y1206102D02*
X1634153Y1204232D01*
G01D02*
X1632283Y1206102D01*
G01Y1202362D02*
X1634153Y1204232D01*
G01D02*
X1636023Y1202362D01*
G01X1639763Y1194881D02*
X1637893Y1196751D01*
G01D02*
X1639763Y1198621D01*
G01X1637893Y1196751D02*
X1636023Y1194881D01*
G01X1632283D02*
X1634153Y1196751D01*
G01X1643504Y1202362D02*
X1645374Y1204232D01*
G01X1632283Y1194881D02*
X1630413Y1196751D01*
G01X1643504Y1194881D02*
X1641633Y1193011D01*
G01D02*
X1639763Y1194881D01*
G01X1641633Y1193011D02*
X1639763Y1191141D01*
G01X1630413Y1196751D02*
X1628543Y1194881D01*
G01X1634153Y1196751D02*
X1636023Y1194881D01*
G01X1632283Y1191141D02*
X1634153Y1193011D01*
G01X1636023Y1191141D02*
X1637893Y1193011D01*
G01X1628543Y1191141D02*
X1630413Y1193011D01*
G01Y1200491D02*
X1628543Y1198621D01*
G01X1637893Y1200491D02*
X1636023Y1198621D01*
G01X1634153Y1200491D02*
X1632283Y1198621D01*
G01X1643504D02*
X1645374Y1200491D01*
G01X1643504Y1191141D02*
X1645374Y1193011D01*
G01X1639763Y1206102D02*
X1641633Y1207972D01*
G01D02*
X1643504Y1206102D01*
G01Y1209842D02*
X1641633Y1207972D01*
G01D02*
X1639763Y1209842D01*
G01X1643504Y1206102D02*
X1645374Y1207972D01*
G01X1643504Y1209842D02*
X1645374Y1207972D01*
G01X1636023Y1206102D02*
X1637893Y1207972D01*
G01D02*
X1639763Y1206102D01*
G01Y1209842D02*
X1637893Y1207972D01*
G01D02*
X1636023Y1209842D01*
G01X1632283Y1206102D02*
X1634153Y1207972D01*
G01D02*
X1636023Y1206102D01*
G01Y1209842D02*
X1634153Y1207972D01*
G01D02*
X1632283Y1209842D01*
G01X1628543Y1206102D02*
X1630413Y1207972D01*
G01D02*
X1632283Y1206102D01*
G01Y1209842D02*
X1630413Y1207972D01*
G01D02*
X1628543Y1209842D01*
G01X1639763D02*
X1641633Y1211712D01*
G01X1632283Y1209842D02*
X1634153Y1211712D01*
G01X1636023Y1209842D02*
X1637893Y1211712D01*
G01X1632283Y1209842D02*
X1630413Y1211712D01*
G01X1645374Y1204232D02*
X1643504Y1206102D01*
G01X1641633Y1211712D02*
X1643504Y1209842D01*
G01X1634153Y1211712D02*
X1636023Y1209842D01*
G01X1637893Y1211712D02*
X1639763Y1209842D01*
G01X1630413Y1211712D02*
X1628543Y1209842D01*
G01X1647244Y1120078D02*
X1649114Y1118208D01*
G01X1650984Y1123818D02*
X1649114Y1121948D01*
G01X1650984Y1123818D02*
X1649114Y1125688D01*
G01X1645374Y1118208D02*
X1647244Y1120078D01*
G01X1649114Y1118208D02*
X1650984Y1120078D01*
G01X1649114Y1121948D02*
X1650984Y1120078D01*
G01X1645374Y1121948D02*
X1647244Y1120078D01*
G01X1650984Y1131299D02*
X1649114Y1129429D01*
G01X1650984Y1131299D02*
X1649114Y1133169D01*
G01X1650984Y1138779D02*
X1649114Y1140649D01*
G01X1650984Y1138779D02*
X1652854Y1136909D01*
G01X1649114Y1140649D02*
X1647244Y1138779D01*
G01X1650984D02*
X1649114Y1136909D01*
G01D02*
X1647244Y1138779D01*
G01X1649114Y1136909D02*
X1650984Y1135039D01*
G01X1649114Y1133169D02*
X1650984Y1135039D01*
G01X1652854Y1136909D02*
X1650984Y1135039D01*
G01X1649114Y1125688D02*
X1650984Y1127558D01*
G01X1649114Y1129429D02*
X1650984Y1127558D01*
G01X1652854Y1140649D02*
X1650984Y1138779D01*
G01X1660334Y1151869D02*
X1658464Y1153740D01*
G01X1660334Y1155610D02*
X1658464Y1153740D01*
G01Y1157480D02*
X1660334Y1155610D01*
G01X1650984Y1153740D02*
X1652854Y1151869D01*
G01D02*
X1654724Y1153740D01*
G01X1650984Y1142519D02*
X1652854Y1140649D01*
G01X1649114D02*
X1650984Y1142519D01*
G01X1647244D02*
X1649114Y1140649D01*
G01X1647244Y1142519D02*
X1649114Y1144389D01*
G01D02*
X1650984Y1142519D01*
G01Y1146259D02*
X1649114Y1144389D01*
G01D02*
X1647244Y1146259D01*
G01D02*
X1649114Y1148129D01*
G01D02*
X1650984Y1146259D01*
G01Y1149999D02*
X1649114Y1148129D01*
G01D02*
X1647244Y1149999D01*
G01X1652854Y1151869D02*
X1650984Y1149999D01*
G01X1647244D02*
X1645374Y1148129D01*
G01X1647244Y1153740D02*
X1645374Y1151869D01*
G01X1650984Y1146259D02*
X1652854Y1148129D01*
G01X1654724Y1153740D02*
X1656594Y1151869D01*
G01X1647244Y1153740D02*
X1649114Y1151870D01*
G01X1645374Y1148129D02*
X1647244Y1146259D01*
G01X1645374Y1151869D02*
X1647244Y1149999D01*
G01X1645374Y1155610D02*
X1647244Y1153740D01*
G01X1652854Y1148129D02*
X1650984Y1149999D01*
G01X1652854Y1155610D02*
X1650984Y1157480D01*
G01X1656594Y1151869D02*
X1658464Y1153740D01*
G01X1649114Y1151870D02*
X1650984Y1150000D01*
Y1149999D01*
G01X1649114Y1155610D02*
X1647244Y1157480D01*
G01X1656594Y1155610D02*
X1654724Y1157480D01*
G01X1652854Y1174310D02*
X1650984Y1172440D01*
G01D02*
X1652854Y1170570D01*
G01X1650984Y1168700D02*
X1652854Y1166830D01*
G01X1658464Y1157480D02*
X1660334Y1159350D01*
G01D02*
X1658464Y1161220D01*
G01X1660334Y1166830D02*
X1658464Y1164960D01*
G01Y1168700D02*
X1660334Y1166830D01*
G01Y1170570D02*
X1658464Y1168700D01*
G01Y1172440D02*
X1660334Y1170570D01*
G01Y1174310D02*
X1658464Y1172440D01*
G01X1652854Y1159350D02*
X1650984Y1161220D01*
G01X1652854Y1170570D02*
X1650984Y1168700D01*
G01X1652854Y1166830D02*
X1650984Y1164960D01*
G01X1649114Y1159350D02*
X1647244Y1161220D01*
G01X1649114Y1166830D02*
X1647244Y1168700D01*
G01X1649114Y1170570D02*
X1647244Y1168700D01*
G01Y1172440D02*
X1649114Y1170570D01*
G01X1647244Y1164960D02*
X1649114Y1166830D01*
G01Y1174310D02*
X1647244Y1172440D01*
G01X1656594Y1159350D02*
X1654724Y1161220D01*
G01X1656594Y1166830D02*
X1654724Y1164960D01*
G01X1656594Y1170570D02*
X1654724Y1168700D01*
G01X1656594Y1174310D02*
X1654724Y1172440D01*
G01X1647244Y1183661D02*
X1645374Y1181791D01*
G01X1647244Y1179921D02*
X1649114Y1178051D01*
G01D02*
X1650984Y1176180D01*
G01X1649114Y1178051D02*
X1647244Y1176180D01*
G01X1650984D02*
X1652854Y1178051D01*
G01D02*
X1654724Y1176180D01*
G01X1652854Y1178051D02*
X1654724Y1179921D01*
G01X1647244Y1187401D02*
X1649114Y1189271D01*
G01D02*
X1650984Y1187401D01*
G01Y1191141D02*
X1649114Y1189271D01*
G01D02*
X1647244Y1191141D01*
G01X1650984Y1187401D02*
X1652854Y1185531D01*
G01D02*
X1650984Y1183661D01*
G01X1652854Y1185531D02*
X1654724Y1183661D01*
G01X1650984D02*
X1649114Y1181791D01*
G01D02*
X1647244Y1179921D01*
G01Y1183661D02*
X1649114Y1181791D01*
G01X1647244Y1183661D02*
X1649114Y1185531D01*
G01D02*
X1650984Y1183661D01*
G01Y1187401D02*
X1649114Y1185531D01*
G01D02*
X1647244Y1187401D01*
G01X1650984D02*
X1652854Y1189271D01*
G01D02*
X1654724Y1191141D01*
G01X1652854Y1189271D02*
X1650984Y1191141D01*
G01Y1176180D02*
X1652854Y1174310D01*
G01X1654724Y1183661D02*
X1656594Y1181791D01*
G01X1652854Y1174310D02*
X1654724Y1176180D01*
G01X1658464D02*
X1660334Y1174310D01*
G01X1658464Y1176180D02*
X1660334Y1178051D01*
G01X1656594Y1181791D02*
X1654724Y1179921D01*
G01Y1187401D02*
X1656594Y1185531D01*
G01X1645374Y1174310D02*
X1647244Y1176180D01*
G01X1650984Y1179921D02*
X1652854Y1181791D01*
G01X1654724Y1191141D02*
X1656594Y1193011D01*
G01X1650984Y1191141D02*
X1649114Y1193011D01*
G01D02*
X1647244Y1191141D01*
G01X1649114Y1193011D02*
X1650984Y1194881D01*
G01Y1191141D02*
X1652854Y1193011D01*
G01D02*
X1650984Y1194881D01*
G01X1652854Y1193011D02*
X1654724Y1191141D01*
G01X1650984Y1194881D02*
X1652854Y1196751D01*
G01X1650984Y1206102D02*
X1652854Y1204232D01*
G01D02*
X1650984Y1202362D01*
G01X1652854Y1196751D02*
X1650984Y1198621D01*
G01X1654724Y1194881D02*
X1656594Y1196751D01*
G01X1647244Y1202362D02*
X1649114Y1204232D01*
G01X1647244Y1194881D02*
X1649114Y1196751D01*
G01X1647244Y1198621D02*
X1649114Y1200491D01*
G01X1658464Y1198621D02*
X1656594Y1200491D01*
G01X1647244Y1209842D02*
X1649114Y1211712D01*
G01X1645374Y1207972D02*
X1647244Y1209842D01*
G01X1649114Y1211712D02*
X1650984Y1209842D01*
G01X1677165Y1138779D02*
X1675295Y1140649D01*
G01X1673425Y1138779D02*
X1671555Y1136909D01*
G01X1675295Y1140649D02*
X1673425Y1138779D01*
G01X1671555Y1140649D02*
X1673425Y1138779D01*
G01X1669685Y1142519D02*
X1671555Y1140649D01*
G01X1673425Y1153740D02*
X1675295Y1155610D01*
G01X1673425Y1146259D02*
X1675295Y1148129D01*
G01X1669685Y1157480D02*
X1671555Y1155610D01*
G01X1665945Y1149999D02*
X1664074Y1151869D01*
G01D02*
X1662204Y1153740D01*
G01X1664074Y1151869D02*
X1662204Y1149999D01*
G01D02*
X1660334Y1151869D01*
G01X1662204Y1153740D02*
X1660334Y1155610D01*
G01X1665945Y1149999D02*
X1667815Y1151869D01*
G01X1669685Y1149999D02*
X1671555Y1151869D01*
G01X1669685Y1149999D02*
X1671555Y1148129D01*
G01X1669685Y1142519D02*
X1671555Y1144389D01*
G01X1662204Y1142519D02*
X1664074Y1144389D01*
G01D02*
X1665945Y1142519D01*
G01X1664074Y1144389D02*
X1662204Y1146259D01*
G01X1665945Y1142519D02*
X1667815Y1144389D01*
G01X1662204Y1146259D02*
X1660334Y1144389D01*
G01Y1151869D02*
X1662204Y1153740D01*
G01X1660334Y1155610D02*
X1662204Y1157480D01*
G01X1667815Y1151869D02*
X1669685Y1149999D01*
G01X1675295Y1155610D02*
X1677165Y1153740D01*
G01X1675295Y1148129D02*
X1677165Y1146259D01*
G01X1671555Y1155610D02*
X1673425Y1153740D01*
G01X1671555Y1151869D02*
X1673425Y1153740D01*
G01X1671555Y1148129D02*
X1673425Y1146259D01*
G01X1671555Y1144389D02*
X1673425Y1146259D01*
G01X1667815Y1144389D02*
X1669685Y1142519D01*
G01X1660334Y1144389D02*
X1662204Y1142519D01*
G01X1673425Y1161220D02*
X1671555Y1159350D01*
G01X1662204Y1157480D02*
X1664074Y1159350D01*
G01D02*
X1665945Y1157480D01*
G01X1664074Y1159350D02*
X1662204Y1161220D01*
G01X1665945Y1157480D02*
X1667815Y1159350D01*
G01X1662204Y1161220D02*
X1660334Y1159350D01*
G01D02*
X1662204Y1157480D01*
G01Y1164960D02*
X1660334Y1166830D01*
G01X1662204Y1168700D02*
X1660334Y1170570D01*
G01X1662204Y1164960D02*
X1664074Y1166830D01*
G01D02*
X1662204Y1168700D01*
G01X1664074Y1166830D02*
X1665945Y1164960D01*
G01X1662204Y1172440D02*
X1664074Y1174310D01*
G01X1673425Y1168700D02*
X1671555Y1170570D01*
G01X1669685Y1164960D02*
X1671555Y1166830D01*
G01X1673425Y1168700D02*
X1675295Y1170570D01*
G01X1669685Y1172440D02*
X1667815Y1174310D01*
G01X1665945Y1164960D02*
X1667815Y1166830D01*
G01X1664074Y1174310D02*
X1665945Y1172440D01*
G01X1660334Y1174310D02*
X1662204Y1172440D01*
G01X1660334Y1166830D02*
X1662204Y1168700D01*
G01X1660334Y1170570D02*
X1662204Y1172440D01*
G01X1667815Y1159350D02*
X1669685Y1157480D01*
G01X1671555Y1159350D02*
X1669685Y1157480D01*
G01X1667815Y1166830D02*
X1669685Y1164960D01*
G01X1675295Y1170570D02*
X1677165Y1168700D01*
G01X1671555Y1170570D02*
X1669685Y1172440D01*
G01X1671555Y1166830D02*
X1673425Y1168700D01*
G01X1671555Y1174310D02*
X1669685Y1172440D01*
G01X1667815Y1174310D02*
X1665945Y1172440D01*
G01X1662204Y1191141D02*
X1664074Y1189271D01*
G01D02*
X1665945Y1187401D01*
G01X1664074Y1189271D02*
X1662204Y1187401D01*
G01X1669685D02*
X1671555Y1185531D01*
G01X1669685Y1179921D02*
X1671555Y1181791D01*
G01X1669685Y1179921D02*
X1671555Y1178051D01*
G01X1673425Y1176180D02*
X1671555Y1174310D01*
G01X1662204Y1176180D02*
X1660334Y1174310D01*
G01X1665945Y1179921D02*
X1664074Y1181791D01*
G01D02*
X1662204Y1183661D01*
G01X1664074Y1181791D02*
X1662204Y1179921D01*
G01D02*
X1660334Y1178051D01*
G01X1665945Y1179921D02*
X1667815Y1181791D01*
G01X1669685Y1187401D02*
X1667815Y1189271D01*
G01X1673425Y1183661D02*
X1675295Y1185531D01*
G01X1673425Y1176180D02*
X1675295Y1178051D01*
G01X1673425Y1191141D02*
X1671555Y1189271D01*
G01X1662204Y1183661D02*
X1660334Y1185531D01*
G01X1664074Y1174310D02*
X1662204Y1176180D01*
G01X1660334Y1178051D02*
X1662204Y1176180D01*
G01X1671555Y1185531D02*
X1673425Y1183661D01*
G01X1671555Y1181791D02*
X1673425Y1183661D01*
G01X1671555Y1178051D02*
X1673425Y1176180D01*
G01X1667815Y1181791D02*
X1669685Y1179921D01*
G01X1667815Y1189271D02*
X1665945Y1187401D01*
G01X1675295Y1185531D02*
X1677165Y1183661D01*
G01X1675295Y1178051D02*
X1677165Y1176180D01*
G01X1671555Y1189271D02*
X1669685Y1187401D01*
G01X1660334Y1185531D02*
X1662204Y1187401D01*
G01Y1206102D02*
X1664074Y1204232D01*
G01D02*
X1662204Y1202362D01*
G01X1677165Y1191141D02*
X1675295Y1193011D01*
G01X1673425Y1191141D02*
X1671555Y1193011D01*
G01X1662204Y1206102D02*
X1660334Y1204232D01*
G01X1662204Y1202362D02*
Y1202361D01*
X1660334Y1200491D01*
G01X1662204Y1194881D02*
X1660334Y1193011D01*
G01X1662204Y1194881D02*
X1660334Y1196751D01*
G01X1675295Y1193011D02*
X1673425Y1191141D01*
G01X1671555Y1193011D02*
X1669685Y1194881D01*
G01X1660334Y1204232D02*
X1662204Y1202362D01*
G01X1660334Y1200491D02*
X1662204Y1198621D01*
G01X1660334Y1193011D02*
X1662204Y1191141D01*
G01X1660334Y1196751D02*
X1662204Y1198621D01*
G01X1665945Y1194881D02*
X1665944D01*
G01D02*
X1662204D01*
G01X1665944D02*
X1662204Y1198621D01*
G01X1669685Y1194881D02*
X1665945D01*
G01X1662204Y1209842D02*
X1660334Y1211712D01*
G01X1662204Y1209842D02*
X1660334Y1207972D01*
G01X1662204Y1213582D02*
X1660334Y1215452D01*
G01Y1207972D02*
X1662204Y1206102D01*
G01X1660334Y1215452D02*
X1662204Y1217322D01*
G01X1660334Y1211712D02*
X1662204Y1213582D01*
G01X1684645Y1138779D02*
X1682775Y1136909D01*
G01D02*
X1680905Y1138779D01*
G01X1677165D02*
X1679035Y1140649D01*
G01X1688385Y1138779D02*
X1686515Y1136909D01*
G01X1679035Y1140649D02*
X1680905Y1138779D01*
G01X1690256Y1140649D02*
X1688385Y1138779D01*
G01X1686515Y1136909D02*
X1684645Y1138779D01*
G01X1690256Y1136909D02*
X1688385Y1138779D01*
G01X1692126Y1149999D02*
X1693996Y1148129D01*
G01X1692126Y1157480D02*
X1690256Y1155610D01*
G01X1680905Y1157480D02*
X1679035Y1155610D01*
G01D02*
X1677165Y1153740D01*
G01X1679035Y1155610D02*
X1680905Y1153740D01*
G01X1684645D02*
X1682775Y1151869D01*
G01D02*
X1680905Y1153740D01*
G01X1682775Y1151869D02*
X1680905Y1149999D01*
G01X1677165Y1146259D02*
X1679035Y1148129D01*
G01D02*
X1680905Y1149999D01*
G01X1679035Y1140649D02*
X1680905Y1142519D01*
G01X1692126D02*
X1690256Y1140649D01*
G01X1692126Y1142519D02*
X1693996Y1140649D01*
G01X1680905Y1142519D02*
X1682775Y1144389D01*
G01D02*
X1684645Y1146259D01*
G01X1682775Y1144389D02*
X1680905Y1146259D01*
G01X1679035Y1148129D02*
X1680905Y1146259D01*
G01X1688385D02*
X1690256Y1144389D01*
G01X1688385Y1146259D02*
X1686515Y1144389D01*
G01X1684645Y1153740D02*
X1686515Y1151869D01*
G01X1688385Y1153740D02*
X1690256Y1151869D01*
G01X1692126Y1149999D02*
X1690256Y1148129D01*
G01Y1144389D02*
X1692126Y1142519D01*
G01X1686515Y1144389D02*
X1684645Y1146259D01*
G01X1690256Y1155610D02*
X1688385Y1153740D01*
G01X1686515Y1151869D02*
X1688385Y1153740D01*
G01X1690256Y1151869D02*
X1692126Y1149999D01*
G01X1690256Y1148129D02*
X1688385Y1146259D01*
G01X1684645Y1161220D02*
X1682775Y1159350D01*
G01D02*
X1680905Y1157480D01*
G01X1682775Y1159350D02*
X1680905Y1161220D01*
G01X1692126Y1157480D02*
X1693996Y1155610D01*
G01X1688385Y1161220D02*
X1686515Y1159350D01*
G01X1692126Y1157480D02*
X1690256Y1159350D01*
G01X1692126Y1164960D02*
X1693996Y1166830D01*
G01X1682775Y1174310D02*
X1680905Y1172440D01*
G01X1692126D02*
X1690256Y1174310D01*
G01X1692126Y1172440D02*
X1693996Y1170570D01*
G01X1684645Y1168700D02*
X1682775Y1166830D01*
G01D02*
X1680905Y1164960D01*
G01X1682775Y1166830D02*
X1680905Y1168700D01*
G01D02*
X1679035Y1170570D01*
G01D02*
X1680905Y1172440D01*
G01X1679035Y1170570D02*
X1677165Y1168700D01*
G01X1688385D02*
X1686515Y1166830D01*
G01X1688385Y1168700D02*
X1690256Y1170570D01*
G01X1688385Y1168700D02*
X1690256Y1166830D01*
G01X1686515Y1159350D02*
X1684645Y1161220D01*
G01X1690256Y1159350D02*
X1688385Y1161220D01*
G01X1677165D02*
X1679035Y1159350D01*
G01X1686515Y1166830D02*
X1684645Y1168700D01*
G01X1690256Y1170570D02*
X1692126Y1172440D01*
G01X1690256Y1166830D02*
X1692126Y1164960D01*
G01X1680905Y1176180D02*
X1679035Y1178051D01*
G01D02*
X1680905Y1179921D01*
G01X1679035Y1178051D02*
X1677165Y1176180D01*
G01X1680905Y1179921D02*
X1682775Y1181791D01*
G01D02*
X1684645Y1183661D01*
G01X1682775Y1181791D02*
X1680905Y1183661D01*
G01X1677165D02*
X1679035Y1185531D01*
G01D02*
X1680905Y1187401D01*
G01Y1183661D02*
X1679035Y1185531D01*
G01X1684645Y1191141D02*
X1682775Y1189271D01*
G01D02*
X1680905Y1187401D01*
G01Y1191141D02*
X1682775Y1189271D01*
G01X1684645Y1176180D02*
X1682775Y1174310D01*
G01X1692126Y1179921D02*
X1693996Y1178051D01*
G01X1688385Y1176180D02*
X1690256Y1178051D01*
G01X1688385Y1176180D02*
X1686515Y1174310D01*
G01X1684645Y1183661D02*
X1686515Y1181791D01*
G01X1684645Y1191141D02*
X1686515Y1189271D01*
G01X1692126Y1187401D02*
X1693996Y1185531D01*
G01X1692126Y1187401D02*
X1690256Y1189271D01*
G01X1688385Y1183661D02*
X1690256Y1185531D01*
G01X1692126Y1179921D02*
X1690256Y1181791D01*
G01X1682775Y1174310D02*
X1680905Y1176180D01*
G01X1690256Y1178051D02*
X1692126Y1179921D01*
G01X1686515Y1174310D02*
X1684645Y1176180D01*
G01X1690256Y1174310D02*
X1688385Y1176180D01*
G01X1686515Y1181791D02*
X1688385Y1183661D01*
G01X1686515Y1189271D02*
X1688385Y1191141D01*
G01X1690256Y1189271D02*
X1688385Y1191141D01*
G01X1690256Y1185531D02*
X1692126Y1187401D01*
G01X1690256Y1181791D02*
X1688385Y1183661D01*
G01X1677165Y1191141D02*
X1679035Y1193011D01*
G01D02*
X1680905Y1194881D01*
G01X1679035Y1193011D02*
X1680905Y1191141D01*
G01X1692126Y1194881D02*
X1693996Y1193011D01*
G01X1692126Y1194881D02*
X1690256Y1193011D01*
G01D02*
X1688385Y1191141D01*
G01X1684645Y1198621D02*
X1680905Y1194881D01*
G01D02*
Y1198621D01*
G01X1695866Y1149999D02*
X1697736Y1148129D01*
G01Y1140649D02*
X1695866Y1142519D01*
G01X1697736Y1155610D02*
X1695866Y1157480D01*
G01X1693996Y1140649D02*
X1695866Y1142519D01*
G01X1693996Y1148129D02*
X1695866Y1149999D01*
G01X1693996Y1155610D02*
X1695866Y1157480D01*
G01Y1164960D02*
X1697736Y1166830D01*
G01Y1170570D02*
X1695866Y1172440D01*
G01X1693996Y1170570D02*
X1695866Y1172440D01*
G01X1693996Y1166830D02*
X1695866Y1164960D01*
G01X1697736Y1178051D02*
X1695866Y1179921D01*
G01X1697736Y1185531D02*
X1695866Y1187401D01*
G01X1693996Y1178051D02*
X1695866Y1179921D01*
G01X1693996Y1185531D02*
X1695866Y1187401D01*
G01X1697676Y1193011D02*
Y1193071D01*
X1695866Y1194881D01*
G01X1693996Y1193011D02*
X1695866Y1194881D01*
G54D271*
G01X59324Y847718D02*
X62549D01*
X65549Y850718D01*
G54D16*
X8786Y82444D03*
X6298Y96682D03*
X18298D03*
X6499Y135880D03*
X15184Y147319D03*
X19184D03*
X8264Y156046D03*
X16709Y170318D03*
X17822Y209922D03*
X6811Y1002637D03*
X10701D03*
X14645D03*
X11768Y1522289D03*
X14375Y1547589D03*
X10367Y1547596D03*
X31971Y103502D03*
X23184Y147319D03*
X32201Y233075D03*
X26192Y613827D03*
X30192D03*
X33992D03*
X27556Y1002637D03*
X33659D03*
X21506D03*
X25674Y1488807D03*
X35850Y1550246D03*
X26231Y1548675D03*
X22381Y1548693D03*
X45643Y467435D03*
X49643D03*
X39549Y1002637D03*
X45858D03*
X51946D03*
X40951Y1550246D03*
X47074Y1550237D03*
X52048Y1550212D03*
X65759Y440010D03*
X61759D03*
X57759D03*
X54936Y451854D03*
X62224Y467575D03*
X66345Y487180D03*
X56514Y533924D03*
X64408Y575848D03*
X63684Y599741D03*
X61192Y636327D03*
X57692D03*
X64692D03*
X56149Y821324D03*
X65774Y1002637D03*
X61779D03*
X57834D03*
X57702Y1195761D03*
X61380Y1202487D03*
X53737Y1196921D03*
X54351Y1480899D03*
X56114Y1550211D03*
X64747Y1550204D03*
X63090Y1612093D03*
X70577Y98642D03*
X84808Y100544D03*
X80660Y98289D03*
X76660D03*
X76766Y259626D03*
X84766D03*
X78106Y659507D03*
X74910Y684528D03*
X84699Y1001482D03*
X87652Y575653D03*
X93456Y652341D03*
X95836Y983047D03*
X99836Y992047D03*
X95836D03*
X99836Y983047D03*
X97609Y1010913D03*
X104662Y113567D03*
X115582Y104840D03*
X111582D03*
X113607Y127839D03*
X106796Y154956D03*
X111836Y983047D03*
X103836D03*
X115836D03*
X107836D03*
X111836Y992047D03*
X103836D03*
X115836D03*
X107836D03*
X109601Y1223542D03*
X105601D03*
X119582Y104840D03*
X128251Y143853D03*
X120184Y209922D03*
X127235Y445597D03*
X119836Y983047D03*
X123836D03*
X127836D03*
X119836Y992047D03*
X123836D03*
X127836D03*
X131836Y983047D03*
Y992047D03*
X127604Y1102624D03*
Y1115224D03*
Y1140424D03*
Y1127824D03*
Y1153024D03*
Y1165624D03*
Y1178224D03*
X134333Y103502D03*
X134563Y233075D03*
X138971Y538907D03*
X142961Y538866D03*
X143836Y983047D03*
X147836D03*
X139836D03*
X143836Y992047D03*
X147836D03*
X139836D03*
X135836Y983047D03*
Y992047D03*
X139250Y1009887D03*
Y1022487D03*
X159836Y983047D03*
Y992047D03*
X155836D03*
X151836Y983047D03*
Y992047D03*
X172939Y98642D03*
X179022Y98289D03*
X179128Y259626D03*
X183022Y98289D03*
X188526Y97566D03*
Y105178D03*
X187128Y259626D03*
X201033Y88892D03*
X207024Y113567D03*
X213944Y104840D03*
X209158Y154956D03*
X221944Y104840D03*
X217944D03*
X215969Y127839D03*
X230613Y143853D03*
X222546Y209922D03*
X229942Y1546401D03*
X221942Y1534401D03*
X225753Y1534231D03*
X236695Y103502D03*
X236925Y233075D03*
X242102Y650762D03*
X246102D03*
X240842Y1527401D03*
X237942Y1546401D03*
X244942D03*
X233942D03*
X233753Y1534231D03*
X250102Y650762D03*
X248042Y1527401D03*
X275301Y98642D03*
X281384Y98289D03*
X290888Y97566D03*
X285384Y98289D03*
X290888Y105178D03*
X289490Y259626D03*
X281490D03*
X303395Y88892D03*
X309386Y113567D03*
X311520Y154956D03*
X312263Y318831D03*
X324306Y104840D03*
X320306D03*
X316306D03*
X318222Y127730D03*
X324908Y209922D03*
X317416Y342410D03*
X321416D03*
X323285Y550228D03*
X339057Y103502D03*
X332975Y143853D03*
X339287Y233075D03*
X342486Y379664D03*
X342285Y555228D03*
X336755Y1137220D03*
X337629Y1175841D03*
X342298Y1190932D03*
X346486Y379664D03*
X358486D03*
X350486D03*
X354486D03*
X353202Y409018D03*
X345748Y1137220D03*
X350414Y1175181D03*
X358443Y1174202D03*
X354414Y1175181D03*
X359761Y1182142D03*
X354442Y1182146D03*
X350442D03*
X346136Y1191067D03*
X370931Y364380D03*
X362486Y379664D03*
X374714Y790285D03*
X365748Y1137220D03*
X362282Y1174865D03*
X363729Y1182179D03*
X377663Y98642D03*
X393250Y97566D03*
X387746Y98289D03*
X383746D03*
X393250Y105178D03*
X383852Y259626D03*
X391852D03*
X389237Y373570D03*
X381237D03*
X385237D03*
X404686Y39989D03*
X400686D03*
X394237Y373572D03*
X403478Y872784D03*
X399369D03*
X399816Y953163D03*
X400043Y964420D03*
X404043D03*
X403263Y1155275D03*
X397461Y1563525D03*
X401461D03*
X420422Y362173D03*
X412318Y362165D03*
X411847Y429353D03*
X425673Y456117D03*
X426000Y786316D03*
X416200Y795616D03*
X417682Y1054729D03*
X410668Y1102646D03*
X414455D03*
X422532Y1098858D03*
X421461Y1563525D03*
X417461D03*
X431424Y362034D03*
X435024D03*
X427566Y880949D03*
X427913Y1098858D03*
X431285Y1110412D03*
X449745Y625576D03*
X445745D03*
X442796Y1102646D03*
X446583D03*
X454660Y1098858D03*
X456025Y1218004D03*
X459387Y113567D03*
X474307Y104840D03*
X470307D03*
X466307D03*
X468332Y127839D03*
X461521Y154956D03*
X474909Y209922D03*
X468836Y540113D03*
X460041Y1098858D03*
X463413Y1110412D03*
X468850Y1155275D03*
X462687D03*
X461319Y1218004D03*
X489058Y103502D03*
X482976Y143853D03*
X489288Y233075D03*
X485485Y434433D03*
X489485D03*
X491078Y613827D03*
X483278D03*
X487278D03*
X476255Y1102646D03*
X480042D03*
X488119Y1098858D03*
X500729Y464435D03*
X504729D03*
X501082Y989697D03*
X505958Y1055022D03*
X493500Y1098858D03*
X496872Y1110412D03*
X520845Y437010D03*
X516845D03*
X512845D03*
X510022Y448854D03*
X517310Y464575D03*
X523431Y487180D03*
X513600Y533924D03*
X521494Y575848D03*
X520770Y599741D03*
X516770D03*
X518278Y636327D03*
X514778D03*
X521778D03*
X519285Y725512D03*
X515285D03*
X511285D03*
X523285D03*
X509096Y755806D03*
X513504Y758923D03*
X508383Y1102646D03*
X512170D03*
X520247Y1098858D03*
X527664Y98642D03*
X537747Y98289D03*
X533747D03*
X533853Y259626D03*
X539285Y725512D03*
X535285D03*
X531285D03*
X527285D03*
X524319Y758897D03*
X536715Y1006337D03*
X529000Y1110412D03*
X528274Y1155275D03*
X555758Y88892D03*
X543251Y97566D03*
Y105178D03*
X541853Y259626D03*
X544738Y575653D03*
X552923Y983047D03*
Y992047D03*
X554696Y1010913D03*
X561749Y113567D03*
X568669Y104840D03*
X570694Y127839D03*
X563883Y154956D03*
X568464Y754990D03*
X560256Y776190D03*
X556923Y983047D03*
Y992047D03*
X568923Y983047D03*
X560923D03*
X564923D03*
X568923Y992047D03*
X560923D03*
X564923D03*
X562688Y1223542D03*
X566688D03*
X564242Y1525201D03*
X571942Y1544301D03*
X571809Y1535517D03*
X562786Y1534625D03*
X558786D03*
X576669Y104840D03*
X572669D03*
X585338Y143853D03*
X577271Y209922D03*
X584321Y445597D03*
X573203Y935413D03*
X576923Y983047D03*
X580923D03*
X584923D03*
X576923Y992047D03*
X580923D03*
X584923D03*
X572923Y983047D03*
Y992047D03*
X584691Y1102624D03*
Y1115224D03*
Y1140424D03*
Y1127824D03*
Y1153024D03*
Y1165624D03*
Y1178224D03*
X583742Y1544801D03*
X587809Y1535517D03*
X579809D03*
X591420Y103502D03*
X591650Y233075D03*
X600047Y538866D03*
X596057Y538907D03*
X600923Y983047D03*
X604923D03*
X592923D03*
X596923D03*
X600923Y992047D03*
X604923D03*
X592923D03*
X596923D03*
X588923Y983047D03*
Y992047D03*
X596337Y1009887D03*
Y1022487D03*
X600242Y1538601D03*
X591809Y1535517D03*
X608923Y992047D03*
X616923D03*
X612923D03*
X608923Y983047D03*
X616923D03*
X630026Y98642D03*
X636109Y98289D03*
X636215Y259626D03*
X645613Y97566D03*
X640109Y98289D03*
X645613Y105178D03*
X644215Y259626D03*
X658120Y88892D03*
X664111Y113567D03*
X666245Y154956D03*
X679031Y104840D03*
X671031D03*
X675031D03*
X673056Y127839D03*
X679633Y209922D03*
X693782Y103502D03*
X687700Y143853D03*
X694012Y233075D03*
X699188Y650762D03*
X688728Y700450D03*
X703188Y650762D03*
X707188D03*
X713382Y702253D03*
X732388Y98642D03*
X723811Y739072D03*
X742471Y98289D03*
X747975Y97566D03*
X738471Y98289D03*
X747975Y105178D03*
X738577Y259626D03*
X746577D03*
X747140Y1583826D03*
X748924Y1611884D03*
X748997Y1621426D03*
X747590Y1630725D03*
X760482Y88892D03*
X766473Y113567D03*
X763145Y1583804D03*
X759169Y1583851D03*
X763452Y1613858D03*
X752150Y1630750D03*
X781393Y104840D03*
X773393D03*
X777393D03*
X775418Y127839D03*
X768607Y154956D03*
X781995Y209922D03*
X769349Y318831D03*
X774502Y342410D03*
X778502D03*
X780371Y550228D03*
X767512Y1446718D03*
X783215Y1449666D03*
X777033Y1589513D03*
X781110D03*
X767452Y1613858D03*
X773822Y1630241D03*
X796144Y103502D03*
X790062Y143853D03*
X796374Y233075D03*
X799371Y555228D03*
X793842Y1137220D03*
X794716Y1175841D03*
X799230Y1203547D03*
X798324Y1195125D03*
X799901Y1469617D03*
X791610Y1596529D03*
X787447Y1596552D03*
X802835Y1137220D03*
X811529Y1182146D03*
X811501Y1175181D03*
X807501D03*
X807529Y1182146D03*
X814148Y1377699D03*
X832284Y713530D03*
X827284Y706580D03*
Y713530D03*
X828880Y867380D03*
X828643Y893105D03*
X826987Y926721D03*
X831409Y919309D03*
X827409D03*
X828423Y959210D03*
X822835Y1137220D03*
X816848Y1182142D03*
X820826Y1175229D03*
X820816Y1182179D03*
X816826Y1175229D03*
X834750Y98642D03*
X840833Y98289D03*
X844833D03*
X840939Y259626D03*
X848284Y713530D03*
X839290Y706560D03*
X843284Y706580D03*
X839290Y713510D03*
X843284Y713530D03*
X833112Y833606D03*
X836405Y860508D03*
X832880Y867380D03*
X832643Y893105D03*
X842000Y898516D03*
X848628Y909605D03*
X846000Y898516D03*
X841064Y919109D03*
X837235D03*
X840423Y959210D03*
X862844Y88892D03*
X850337Y97566D03*
Y105178D03*
X848939Y259626D03*
X858586Y377016D03*
X854086D03*
X858586Y387516D03*
X854086D03*
X863086D03*
X852284Y706580D03*
Y713530D03*
X856628Y909605D03*
X864628D03*
X849205Y926725D03*
X852488Y1014169D03*
X857884D03*
X864007D03*
X874531Y197441D03*
X880736Y385796D03*
X875916Y813556D03*
X872628Y909605D03*
X880628D03*
X879740Y941217D03*
X870401Y1014169D03*
X875954D03*
X893736Y385796D03*
X888736D03*
X884736D03*
X892931Y536584D03*
X885931D03*
X889431D03*
X895933Y612684D03*
X892728Y789792D03*
X895916Y813556D03*
X888628Y909605D03*
X892628D03*
X896628D03*
X881454Y1014169D03*
X885210D03*
X889089D03*
X893613Y1014312D03*
X904614Y340380D03*
X908114D03*
X911072Y381423D03*
X907173Y445694D03*
X899931Y536584D03*
X913208Y612535D03*
X909208D03*
X904376Y612455D03*
X900376D03*
X903916Y803406D03*
X899916Y813556D03*
Y803406D03*
X903916Y813556D03*
X909416D03*
X900200Y909616D03*
X907300D03*
X903700D03*
X912628Y922642D03*
X904057Y937629D03*
X906255Y1015797D03*
X898046Y1014256D03*
X902225Y1015744D03*
X901392Y1204764D03*
X897427Y1205924D03*
X905070Y1211490D03*
X916473Y113567D03*
X927393Y104840D03*
X923393D03*
X925418Y127839D03*
X918607Y154956D03*
X915072Y381423D03*
X920999Y472458D03*
X925418Y677886D03*
X921418D03*
X921061Y709861D03*
X925061D03*
X927916Y811556D03*
X921790Y813556D03*
X920628Y922642D03*
X924628D03*
X928628D03*
X916628D03*
X927984Y1014169D03*
X916465D03*
X921861D03*
X931393Y104840D03*
X940062Y143853D03*
X932661Y195093D03*
X938125Y233760D03*
X942757Y254705D03*
X941685Y357769D03*
X942437Y364721D03*
X931072Y381423D03*
X940365Y613827D03*
X944365D03*
X932412Y677886D03*
X938526Y727541D03*
X935916Y811556D03*
X939916D03*
X941535Y823573D03*
X937635D03*
X940516Y895121D03*
X944628Y922642D03*
X936628D03*
X940628D03*
X932628D03*
X945671Y985759D03*
X939931Y1014169D03*
X945431D03*
X934378D03*
X946144Y103502D03*
X947040Y218246D03*
X951278Y238064D03*
Y245043D03*
X959816Y467435D03*
X948165Y613827D03*
X961503Y701348D03*
X953551D03*
X957551D03*
X959950Y728554D03*
X952783Y830299D03*
X951100Y838616D03*
X947200D03*
X957900Y850516D03*
X958567Y930335D03*
X950567D03*
X953671Y985759D03*
X961671D03*
X949671D03*
X950987Y1014169D03*
X954866D03*
X961404Y1205924D03*
X975932Y440010D03*
X971932D03*
X969109Y451854D03*
X963816Y467435D03*
X976397Y467575D03*
X970687Y533924D03*
X978581Y575848D03*
X977857Y599741D03*
X973857D03*
X975365Y636327D03*
X971865D03*
X963950Y728554D03*
X966746Y930308D03*
X962567Y930335D03*
X965671Y985759D03*
X967625Y1014400D03*
X971760Y1014420D03*
X963823Y1014256D03*
X975659Y1014441D03*
X965369Y1204764D03*
X969047Y1211490D03*
X984750Y98642D03*
X990833Y98289D03*
X994833D03*
X990939Y259626D03*
X990405Y311033D03*
X988045Y361100D03*
X992045D03*
X979932Y440010D03*
X980518Y487180D03*
X978865Y636327D03*
X983712Y716605D03*
X994051Y813859D03*
X1000337Y97566D03*
Y105178D03*
X998939Y259626D03*
X1000698Y302767D03*
X996045Y361100D03*
X1001825Y575653D03*
X1007990Y768490D03*
X995990D03*
X1006699Y813916D03*
X1002699D03*
X1010699D03*
X1010009Y983047D03*
Y992047D03*
X998872Y1001482D03*
X1000248Y1021427D03*
X1012844Y88892D03*
X1018835Y113567D03*
X1025755Y104840D03*
X1020969Y154956D03*
X1016635Y302767D03*
X1020635D03*
X1025749D03*
X1012635D03*
X1018922Y802831D03*
X1014819Y932428D03*
X1026009Y983047D03*
X1018009D03*
X1022009D03*
X1014009D03*
X1026009Y992047D03*
X1018009D03*
X1022009D03*
X1014009D03*
X1011782Y1010913D03*
X1019774Y1223542D03*
X1023774D03*
X1017329Y1313528D03*
X1020049Y1330852D03*
X1019671Y1345015D03*
X1019257Y1363489D03*
X1033755Y104840D03*
X1029755D03*
X1027780Y127839D03*
X1042424Y143853D03*
X1034357Y209922D03*
X1029639Y302767D03*
X1041408Y445597D03*
X1030009Y983047D03*
X1038009D03*
X1042009D03*
X1034009Y992047D03*
X1030009D03*
X1038009D03*
X1042009D03*
X1034009Y983047D03*
X1041777Y1102624D03*
Y1115224D03*
Y1140424D03*
Y1127824D03*
Y1153024D03*
Y1165624D03*
Y1178224D03*
X1038996Y1368583D03*
X1048506Y103502D03*
X1048736Y233075D03*
X1045650Y302767D03*
X1057134Y538866D03*
X1053144Y538907D03*
X1046009Y983047D03*
X1050009D03*
X1054009D03*
X1046009Y992047D03*
X1050009D03*
X1054009D03*
X1058009D03*
Y983047D03*
X1053423Y1009887D03*
Y1022487D03*
X1074009Y992047D03*
Y983047D03*
X1066009Y992047D03*
X1062009D03*
X1070009D03*
X1066009Y983047D03*
X1062009D03*
X1087112Y98642D03*
X1086108Y1523524D03*
X1090904Y1593297D03*
X1086469Y1582501D03*
X1089474Y1631941D03*
X1093195Y98289D03*
X1097195D03*
X1102699Y97566D03*
Y105178D03*
X1093301Y259626D03*
X1101301D03*
X1096233Y1582524D03*
X1102904Y1593297D03*
X1104233Y1582524D03*
X1093474Y1631941D03*
X1101474D03*
X1105474D03*
X1115206Y88892D03*
X1121197Y113567D03*
X1123331Y154956D03*
X1136117Y104840D03*
X1132117D03*
X1128117D03*
X1130142Y127839D03*
X1136719Y209922D03*
X1150868Y103502D03*
X1144786Y143853D03*
X1151098Y233075D03*
X1156275Y650762D03*
X1156485Y767658D03*
X1155485Y839158D03*
X1160275Y650762D03*
X1164275D03*
X1167485Y825658D03*
X1159485D03*
X1171485Y839158D03*
X1163485D03*
X1167485D03*
X1159485D03*
X1189474Y98642D03*
X1183485Y825658D03*
X1175485D03*
X1183485Y839158D03*
X1179485D03*
X1175485D03*
X1195557Y98289D03*
X1199557D03*
X1205061Y97566D03*
Y105178D03*
X1195663Y259626D03*
X1203663D03*
X1217568Y88892D03*
X1238479Y104840D03*
X1223559Y113567D03*
X1234479Y104840D03*
X1230479D03*
X1232504Y127839D03*
X1225693Y154956D03*
X1226436Y318831D03*
X1231589Y342410D03*
X1235589D03*
X1237458Y550228D03*
X1253230Y103502D03*
X1247148Y143853D03*
X1239081Y209922D03*
X1253460Y233075D03*
X1250928Y1137220D03*
X1251802Y1175841D03*
X1249230Y1189437D03*
X1256659Y379664D03*
X1268659D03*
X1260659D03*
X1264659D03*
X1267375Y409018D03*
X1256458Y555228D03*
X1261622Y898533D03*
X1259921Y1137220D03*
X1264587Y1175181D03*
X1268587D03*
X1268615Y1182146D03*
X1264615D03*
X1255485Y1198941D03*
X1275660Y342726D03*
X1279655Y342667D03*
X1276659Y379664D03*
X1272659D03*
X1280042Y902164D03*
X1279921Y1137220D03*
X1277912Y1175229D03*
X1273912D03*
X1273934Y1182142D03*
X1277902Y1182179D03*
X1291836Y98642D03*
X1297919Y98289D03*
X1301919D03*
X1298025Y259626D03*
X1303410Y373570D03*
X1287437Y372695D03*
X1295410Y373570D03*
X1299410D03*
X1292566Y804337D03*
X1298909Y815608D03*
X1288155Y895016D03*
X1302000Y920016D03*
X1298000D03*
X1300882Y931080D03*
X1300500Y964016D03*
X1314859Y39989D03*
X1318859D03*
X1307423Y97566D03*
Y105178D03*
X1306025Y259626D03*
X1308410Y373572D03*
X1316903Y365257D03*
X1317000Y790516D03*
X1313000D03*
Y806516D03*
X1317000D03*
X1313152Y931080D03*
X1309103D03*
X1317000Y938016D03*
X1304949Y931080D03*
X1307000Y964016D03*
X1317437Y1155275D03*
X1325007Y365265D03*
X1334009Y365126D03*
X1326020Y429353D03*
X1333000Y790516D03*
X1329000D03*
X1325000D03*
X1321000D03*
X1333000Y806516D03*
X1325000D03*
X1329000D03*
X1321000D03*
X1322500Y920016D03*
X1326500D03*
Y938016D03*
X1327000Y964016D03*
X1332000D03*
X1331856Y1054729D03*
X1324842Y1102646D03*
X1328629D03*
X1337609Y365126D03*
X1339846Y456117D03*
X1341000Y790516D03*
X1337000D03*
X1341000Y806516D03*
X1345000D03*
X1349000D03*
X1337000D03*
X1350500Y920016D03*
X1336000Y938016D03*
X1337691Y948659D03*
X1342087Y1098858D03*
X1336706D03*
X1345459Y1110412D03*
X1353000Y806516D03*
X1354500Y920016D03*
X1358500D03*
X1362500D03*
X1366500D03*
X1361948Y946119D03*
X1356970Y1102646D03*
X1360757D03*
X1373560Y113567D03*
X1384480Y104840D03*
X1380480D03*
X1382505Y127839D03*
X1375694Y154956D03*
X1370500Y920016D03*
X1378500D03*
X1374500D03*
X1382500D03*
X1373948Y946119D03*
X1374215Y1098858D03*
X1368834D03*
X1377587Y1110412D03*
X1376861Y1155275D03*
X1383024D03*
X1388480Y104840D03*
X1397149Y143853D03*
X1389082Y209922D03*
X1397452Y613827D03*
X1390537Y806195D03*
X1386335Y806220D03*
X1388346Y924161D03*
X1390429Y1102646D03*
X1394216D03*
X1403231Y103502D03*
X1403461Y233075D03*
X1414903Y464435D03*
X1405252Y613827D03*
X1401452D03*
X1401000Y920016D03*
X1407674Y1098858D03*
X1402293D03*
X1411046Y1110412D03*
X1416684Y1511665D03*
X1411586Y1543470D03*
X1411094Y1566148D03*
X1431019Y437010D03*
X1427019D03*
X1424196Y448854D03*
X1431484Y464575D03*
X1418903Y464435D03*
X1427774Y533924D03*
X1430944Y599741D03*
X1432452Y636327D03*
X1428952D03*
X1420132Y1055022D03*
X1422557Y1102646D03*
X1426344D03*
X1426253Y1407793D03*
X1430374Y1495586D03*
X1433405Y1540508D03*
X1432913Y1563186D03*
X1441837Y98642D03*
X1447920Y98289D03*
X1448026Y259626D03*
X1435019Y437010D03*
X1437605Y487180D03*
X1435668Y575848D03*
X1434944Y599741D03*
X1435952Y636327D03*
X1443459Y1034427D03*
X1434421Y1098858D03*
X1443174Y1110412D03*
X1442448Y1155275D03*
X1436792Y1555457D03*
X1457424Y97566D03*
X1451920Y98289D03*
X1457424Y105178D03*
X1456026Y259626D03*
X1458912Y575653D03*
X1455959Y1001482D03*
X1469931Y88892D03*
X1475922Y113567D03*
X1478056Y154956D03*
X1475096Y983047D03*
X1479096D03*
X1471096D03*
X1475096Y992047D03*
X1479096D03*
X1471096D03*
X1467096Y983047D03*
Y992047D03*
X1468869Y1010913D03*
X1480861Y1223542D03*
X1476861D03*
X1490842Y104840D03*
X1482842D03*
X1486842D03*
X1484867Y127839D03*
X1491444Y209922D03*
X1491096Y983047D03*
X1487096D03*
X1495096D03*
X1491096Y992047D03*
X1487096D03*
X1495096D03*
X1483096Y983047D03*
Y992047D03*
X1505593Y103502D03*
X1499511Y143853D03*
X1505823Y233075D03*
X1498495Y445597D03*
X1514221Y538866D03*
X1510231Y538907D03*
X1503096Y983047D03*
X1507096D03*
X1511096D03*
X1503096Y992047D03*
X1507096D03*
X1511096D03*
X1499096D03*
Y983047D03*
X1510510Y1009887D03*
Y1022487D03*
X1498864Y1102624D03*
Y1115224D03*
Y1127824D03*
Y1140424D03*
Y1153024D03*
Y1165624D03*
Y1178224D03*
X1525015Y903541D03*
X1523096Y983047D03*
X1519096D03*
X1523096Y992047D03*
X1519096D03*
X1527096D03*
X1515096Y983047D03*
Y992047D03*
X1544199Y98642D03*
X1531096Y983047D03*
Y992047D03*
X1554282Y98289D03*
X1559786Y97566D03*
X1550282Y98289D03*
X1559786Y105178D03*
X1550388Y259626D03*
X1558388D03*
X1572293Y88892D03*
X1578284Y113567D03*
X1593204Y104840D03*
X1589204D03*
X1585204D03*
X1587229Y127839D03*
X1580418Y154956D03*
X1593806Y209922D03*
X1594307Y1502071D03*
X1594500Y1509016D03*
X1607955Y103502D03*
X1601873Y143853D03*
X1608185Y233075D03*
X1608483Y780418D03*
X1608383Y795218D03*
X1608283Y809218D03*
X1600333Y1443501D03*
X1605000Y1509016D03*
X1598142Y1527401D03*
X1613362Y650762D03*
X1617362D03*
X1621362D03*
X1616683Y747518D03*
X1616583Y761518D03*
X1634083Y774718D03*
X1632583Y787418D03*
X1631383Y801518D03*
X1646561Y98642D03*
X1652644Y98289D03*
X1656644D03*
X1652750Y259626D03*
X1660750D03*
X1674655Y88892D03*
X1662148Y97566D03*
Y105178D03*
X1680646Y113567D03*
X1691566Y104840D03*
X1687566D03*
X1689591Y127839D03*
X1682780Y154956D03*
X1683523Y318831D03*
X1688676Y342410D03*
X1692676D03*
X1695566Y104840D03*
X1704235Y143853D03*
X1696168Y209922D03*
X1694545Y550228D03*
X1708015Y1137220D03*
X1708889Y1175841D03*
X1708745Y1224216D03*
X1710317Y103502D03*
X1710547Y233075D03*
X1713746Y379664D03*
X1717746D03*
X1725746D03*
X1721746D03*
X1724462Y409018D03*
X1713545Y555228D03*
X1717008Y1137220D03*
X1725674Y1175181D03*
X1721674D03*
X1725702Y1182146D03*
X1721702D03*
X1713721Y1203402D03*
X1709827Y1203356D03*
X1712966Y1224207D03*
X1733746Y379664D03*
X1729746D03*
X1737008Y1137220D03*
X1734999Y1175229D03*
X1730999D03*
X1731021Y1182142D03*
X1734989Y1182179D03*
X1748923Y98642D03*
X1755006Y98289D03*
X1755112Y259626D03*
X1752497Y373570D03*
X1756497D03*
X1756297Y1015568D03*
X1753221Y1618595D03*
X1764510Y97566D03*
X1759006Y98289D03*
X1764510Y105178D03*
X1763112Y259626D03*
X1765497Y373572D03*
X1760497Y373570D03*
X1765131Y1015568D03*
X1760487D03*
X1771992D03*
X1774339Y1440626D03*
X1774216Y1472816D03*
X1763000Y1582016D03*
X1777017Y88892D03*
X1783107Y429353D03*
X1789463Y963266D03*
X1784145Y1015568D03*
X1790035D03*
X1778042D03*
X1796933Y456117D03*
X1793474Y924502D03*
X1796344Y1015568D03*
X1802432D03*
X1805384Y1206410D03*
X1803885Y1437656D03*
X1803762Y1469846D03*
X1808320Y1015568D03*
X1812265D03*
X1816260D03*
X1809349Y1205250D03*
X1813027Y1211976D03*
X1828272Y1106087D03*
Y1099048D03*
G54D61*
X42408Y511021D03*
X71691Y242569D03*
X61700Y511021D03*
X90983Y242569D03*
X174053D03*
X193345D03*
X276415D03*
X295707D03*
X378777D03*
X398069D03*
X411729Y414384D03*
X431021D03*
X499494Y511021D03*
X518786D03*
X528778Y242569D03*
X548070D03*
X631140D03*
X650432D03*
X733502D03*
X752794D03*
X835864D03*
X855156D03*
X905055Y430725D03*
X924347D03*
X956581Y511021D03*
X975873D03*
X985864Y242569D03*
X1005156D03*
X1088226D03*
X1107518D03*
X1190588D03*
X1209880D03*
X1292950D03*
X1312242D03*
X1325902Y414384D03*
X1345194D03*
X1413668Y511021D03*
X1432960D03*
X1442951Y242569D03*
X1462243D03*
X1545313D03*
X1564605D03*
X1647675D03*
X1666967D03*
X1750037D03*
X1769329D03*
X1782989Y414384D03*
X1802281D03*
G54D154*
X420656Y1116630D03*
X452784D03*
X486243D03*
X518371D03*
X1334830D03*
X1366958D03*
X1400417D03*
X1432545D03*
G54D43*
X29212Y81575D03*
X72914Y61614D03*
X131574Y81575D03*
X175276Y61614D03*
X233936Y81575D03*
X277639Y61614D03*
X336299Y81575D03*
X380001Y61614D03*
X486279Y81595D03*
X530001Y61614D03*
X588641Y81594D03*
X632363Y61614D03*
X691004Y81595D03*
X734725Y61614D03*
X793366Y81595D03*
X837087Y61614D03*
X943366Y81595D03*
X987087Y61614D03*
X1045728Y81595D03*
X1089450Y61614D03*
X1148090Y81595D03*
X1191812Y61614D03*
X1250453Y81595D03*
X1294174Y61614D03*
X1400453Y81595D03*
X1444174Y61614D03*
X1502834Y81575D03*
X1546536Y61614D03*
X1605177Y81595D03*
X1648898Y61614D03*
X1707539Y81595D03*
X1751261Y61614D03*
G54D136*
X410968Y1064305D03*
Y1078675D03*
X434336Y691514D03*
Y705884D03*
X499098Y1064305D03*
Y1078675D03*
X1325142Y1064305D03*
Y1078675D03*
X1413272Y1064305D03*
Y1078675D03*
G54D145*
X422988Y326886D03*
X424563D03*
X421413D03*
X419839D03*
X437161D03*
X435587D03*
X427713D03*
X429287D03*
X430862D03*
X434012D03*
X432437D03*
X426138D03*
X1330298Y329978D03*
X1331872D03*
X1325573D03*
X1333447D03*
X1335022D03*
X1328723D03*
X1327148D03*
X1323998D03*
X1322424D03*
X1339746D03*
X1338172D03*
X1336597D03*
G54D253*
X1150912Y324148D03*
Y329148D03*
Y334148D03*
Y339148D03*
X1171712Y324148D03*
Y334148D03*
Y339148D03*
Y329148D03*
G54D190*
X770472Y1490945D03*
X820079Y388583D03*
X1020866D03*
X1070472Y1490945D03*
G54D34*
X8788Y992319D03*
Y986519D03*
X14513Y992319D03*
Y986519D03*
X20006Y992319D03*
Y986519D03*
X30903Y992319D03*
Y986519D03*
X36293Y992319D03*
Y986519D03*
X25462Y992319D03*
Y986519D03*
X41792Y992319D03*
Y986519D03*
X47234Y992319D03*
Y986519D03*
X47425Y1242619D03*
Y1248419D03*
X117670Y1011465D03*
X110258Y1014862D03*
Y1020662D03*
X117670Y1017265D03*
Y1024065D03*
Y1029865D03*
X106024Y1104202D03*
Y1110002D03*
Y1116802D03*
Y1122602D03*
Y1129402D03*
Y1135202D03*
Y1142002D03*
Y1147802D03*
Y1154602D03*
Y1160402D03*
Y1167202D03*
Y1173002D03*
Y1179802D03*
Y1185602D03*
X374800Y770700D03*
Y776500D03*
X389627Y881760D03*
X406173Y455001D03*
Y449201D03*
X400711Y1217592D03*
Y1211792D03*
X411673Y449201D03*
Y455001D03*
X412040Y840629D03*
Y834829D03*
X426822Y1217735D03*
Y1211935D03*
X456091Y1029816D03*
X455968Y1206277D03*
Y1212077D03*
X455592Y1260171D03*
Y1265971D03*
X461319Y1206276D03*
Y1212076D03*
X461101Y1260171D03*
Y1265971D03*
X499598Y1217351D03*
Y1211551D03*
X526120Y1218053D03*
Y1212253D03*
X567345Y1014862D03*
Y1020662D03*
X563111Y1104202D03*
Y1110002D03*
Y1116802D03*
Y1122602D03*
Y1129402D03*
Y1135202D03*
Y1142002D03*
Y1147802D03*
Y1154602D03*
Y1160402D03*
Y1167202D03*
Y1173002D03*
Y1179802D03*
Y1185602D03*
X574757Y1011465D03*
Y1024065D03*
Y1017265D03*
Y1029865D03*
X866448Y1003630D03*
Y997830D03*
X871389Y1003630D03*
Y997830D03*
X876279Y1003630D03*
Y997830D03*
X881278Y1003630D03*
Y997830D03*
X886220Y1003630D03*
Y997830D03*
X891068Y1003630D03*
Y997830D03*
X895989Y1003630D03*
Y997830D03*
X891115Y1251622D03*
Y1257422D03*
X901499Y471342D03*
Y465542D03*
X906999D03*
Y471342D03*
X900721Y1003630D03*
Y997830D03*
X913751Y1004630D03*
Y998830D03*
X925969Y1003630D03*
Y997830D03*
X920476Y1003630D03*
Y997830D03*
X936866Y1003630D03*
Y997830D03*
X942256Y1003630D03*
Y997830D03*
X931425Y1003630D03*
Y997830D03*
X961110Y1003283D03*
Y997483D03*
X955092Y1251622D03*
Y1257422D03*
X973080Y1003456D03*
Y997656D03*
X1002052Y1397662D03*
Y1403462D03*
X1024431Y1014862D03*
Y1020662D03*
X1020197Y1104202D03*
Y1116802D03*
Y1122602D03*
Y1110002D03*
Y1129402D03*
Y1135202D03*
Y1142002D03*
Y1147802D03*
Y1154602D03*
Y1160402D03*
Y1167202D03*
Y1173002D03*
Y1179802D03*
Y1185602D03*
X1031843Y1011465D03*
Y1017265D03*
Y1024065D03*
Y1029865D03*
X1053227Y811659D03*
Y817459D03*
X1314823Y1217928D03*
Y1212128D03*
X1320346Y455001D03*
Y449201D03*
X1325846D03*
Y455001D03*
X1341454Y1217562D03*
Y1211762D03*
X1370265Y1029816D03*
X1414947Y1217224D03*
Y1211424D03*
X1440660Y1217062D03*
Y1211262D03*
X1481518Y1014862D03*
Y1020662D03*
X1477284Y1104202D03*
Y1116802D03*
Y1122602D03*
Y1110002D03*
Y1129402D03*
Y1135202D03*
Y1142002D03*
Y1147802D03*
Y1154602D03*
Y1167202D03*
Y1173002D03*
Y1160402D03*
Y1179802D03*
Y1185602D03*
X1488930Y1011465D03*
Y1024065D03*
Y1017265D03*
Y1029865D03*
X1746267Y903414D03*
Y909214D03*
X1770492Y1005250D03*
Y999450D03*
X1759274Y1005250D03*
Y999450D03*
X1764999Y1005250D03*
Y999450D03*
X1777433Y455001D03*
Y449201D03*
X1782933D03*
Y455001D03*
X1786779Y1005250D03*
Y999450D03*
X1775948Y1005250D03*
Y999450D03*
X1781389Y1005250D03*
Y999450D03*
X1792278Y1005250D03*
Y999450D03*
X1797720Y1005250D03*
Y999450D03*
X1799072Y1252108D03*
Y1257908D03*
G54D127*
X392821Y34022D03*
Y25754D03*
X409947Y34022D03*
Y25754D03*
X1268294Y327801D03*
Y336069D03*
X1285420Y327801D03*
Y336069D03*
X1306994Y34022D03*
Y25754D03*
X1324120Y34022D03*
Y25754D03*
X1582437Y335455D03*
Y343723D03*
X1599563Y335455D03*
Y343723D03*
G54D118*
X307313Y316731D03*
Y319290D03*
X299833Y316731D03*
Y321849D03*
Y319290D03*
X307313Y321849D03*
X764399Y316731D03*
Y319290D03*
X756919Y316731D03*
Y321849D03*
Y319290D03*
X764399Y321849D03*
X877801Y710611D03*
Y713170D03*
X870321Y710611D03*
Y715729D03*
Y713170D03*
X877801Y715729D03*
X1221486Y316731D03*
Y319290D03*
X1214006Y316731D03*
Y321849D03*
Y319290D03*
X1221486Y321849D03*
X1671093Y316731D03*
Y321849D03*
Y319290D03*
X1678573Y316731D03*
Y319290D03*
Y321849D03*
G54D181*
X687146Y759581D03*
Y762140D03*
Y764699D03*
Y774936D03*
Y777495D03*
Y767258D03*
Y769818D03*
Y772377D03*
X709194Y759581D03*
Y762140D03*
Y764699D03*
Y774936D03*
Y777495D03*
Y767258D03*
Y769818D03*
Y772377D03*
G54D217*
X903297Y245669D03*
Y243307D03*
Y240945D03*
Y238583D03*
Y236221D03*
Y233858D03*
Y231496D03*
Y262205D03*
Y259843D03*
Y257480D03*
Y255118D03*
Y252756D03*
Y250394D03*
Y248032D03*
Y274016D03*
Y271654D03*
Y269291D03*
Y266929D03*
Y264567D03*
X915423Y245669D03*
Y243307D03*
Y240945D03*
Y238583D03*
Y236221D03*
Y233858D03*
Y231496D03*
Y262205D03*
Y259843D03*
Y257480D03*
Y255118D03*
Y252756D03*
Y250394D03*
Y248032D03*
Y274016D03*
Y271654D03*
Y269291D03*
Y266929D03*
Y264567D03*
G54D262*
X1817323Y1567323D03*
G54D25*
X18887Y156163D03*
X16919D03*
X14951D03*
X18887Y164037D03*
X16919D03*
X14951D03*
X65122Y451557D03*
X63154D03*
X61186D03*
X65122Y459431D03*
X63154D03*
X61186D03*
X79038Y277477D03*
X81006D03*
X82974D03*
X79038Y269603D03*
X81006D03*
X82974D03*
X115285Y113684D03*
X113317D03*
X111349D03*
Y121558D03*
X113317D03*
X115285D03*
X181400Y277477D03*
Y269603D03*
X183368Y277477D03*
X185336D03*
X183368Y269603D03*
X185336D03*
X213711Y113684D03*
Y121558D03*
X217647Y113684D03*
X215679D03*
X217647Y121558D03*
X215679D03*
X283762Y277477D03*
X285730D03*
X287698D03*
X283762Y269603D03*
X285730D03*
X287698D03*
X320009Y113684D03*
X318041D03*
X316073D03*
X320009Y121558D03*
X318041D03*
X316073D03*
X386124Y277477D03*
X388092D03*
X390060D03*
X386124Y269603D03*
X388092D03*
X390060D03*
X470010Y113684D03*
X468042D03*
X466074D03*
X470010Y121558D03*
X468042D03*
X466074D03*
X520208Y448557D03*
X518240D03*
X516272D03*
X520208Y456431D03*
X518240D03*
X516272D03*
X536125Y277477D03*
X538093D03*
X536125Y269603D03*
X538093D03*
X540061Y277477D03*
Y269603D03*
X570404Y113684D03*
X568436D03*
X570404Y121558D03*
X568436D03*
X572372Y113684D03*
Y121558D03*
X638487Y277477D03*
X640455D03*
X642423D03*
X638487Y269603D03*
X640455D03*
X642423D03*
X674734Y113684D03*
X672766D03*
X670798D03*
X674734Y121558D03*
X672766D03*
X670798D03*
X740849Y277477D03*
X742817D03*
X744785D03*
X740849Y269603D03*
X742817D03*
X744785D03*
X777096Y113684D03*
X775128D03*
X773160D03*
X777096Y121558D03*
X775128D03*
X773160D03*
X843211Y277477D03*
X845179D03*
X847147D03*
X843211Y269603D03*
X845179D03*
X847147D03*
X927096Y113684D03*
X925128D03*
X923160D03*
X927096Y121558D03*
X925128D03*
X923160D03*
X977327Y451557D03*
X975359D03*
X977327Y459431D03*
X975359D03*
X993211Y277477D03*
Y269603D03*
X979295Y451557D03*
Y459431D03*
X995179Y277477D03*
X997147D03*
X995179Y269603D03*
X997147D03*
X1025522Y113684D03*
Y121558D03*
X1029458Y113684D03*
X1027490D03*
X1029458Y121558D03*
X1027490D03*
X1095573Y277477D03*
X1097541D03*
X1099509D03*
X1095573Y269603D03*
X1097541D03*
X1099509D03*
X1131820Y113684D03*
X1129852D03*
X1127884D03*
X1131820Y121558D03*
X1129852D03*
X1127884D03*
X1197935Y277477D03*
X1199903D03*
X1201871D03*
X1197935Y269603D03*
X1199903D03*
X1201871D03*
X1234182Y113684D03*
X1232214D03*
X1230246D03*
X1234182Y121558D03*
X1232214D03*
X1230246D03*
X1300297Y277477D03*
X1302265D03*
X1300297Y269603D03*
X1302265D03*
X1304233Y277477D03*
Y269603D03*
X1384183Y113684D03*
X1382215D03*
X1380247D03*
X1384183Y121558D03*
X1382215D03*
X1380247D03*
X1432414Y448557D03*
X1430446D03*
X1432414Y456431D03*
X1430446D03*
X1434382Y448557D03*
Y456431D03*
X1450298Y277477D03*
X1452266D03*
X1454234D03*
X1450298Y269603D03*
X1452266D03*
X1454234D03*
X1486545Y113684D03*
X1484577D03*
X1482609D03*
X1486545Y121558D03*
X1484577D03*
X1482609D03*
X1552660Y277477D03*
X1554628D03*
X1556596D03*
X1552660Y269603D03*
X1554628D03*
X1556596D03*
X1588907Y113684D03*
X1586939D03*
X1584971D03*
X1588907Y121558D03*
X1586939D03*
X1584971D03*
X1655022Y277477D03*
X1656990D03*
X1658958D03*
X1655022Y269603D03*
X1656990D03*
X1658958D03*
X1691269Y113684D03*
X1689301D03*
X1687333D03*
X1691269Y121558D03*
X1689301D03*
X1687333D03*
X1757384Y277477D03*
Y269603D03*
X1759352Y277477D03*
X1761320D03*
X1759352Y269603D03*
X1761320D03*
G54D172*
X501821Y359214D03*
Y356655D03*
Y361773D03*
Y366891D03*
Y372010D03*
Y377128D03*
Y364332D03*
Y369450D03*
Y374569D03*
Y379687D03*
Y382246D03*
Y384805D03*
X523869Y356655D03*
Y359214D03*
Y372010D03*
Y366891D03*
Y361773D03*
Y374569D03*
Y369450D03*
Y364332D03*
Y377128D03*
Y384805D03*
Y382246D03*
Y379687D03*
X1404362Y326437D03*
Y331555D03*
Y336673D03*
Y341792D03*
Y328996D03*
Y334114D03*
Y339232D03*
Y344351D03*
Y346910D03*
Y349469D03*
Y352028D03*
Y354587D03*
X1426410Y326437D03*
Y341792D03*
Y336673D03*
Y331555D03*
Y344351D03*
Y339232D03*
Y334114D03*
Y328996D03*
Y354587D03*
Y352028D03*
Y349469D03*
Y346910D03*
X1506457Y326325D03*
Y323766D03*
Y328884D03*
Y334002D03*
Y339121D03*
Y344239D03*
Y331443D03*
Y336561D03*
Y341680D03*
Y346798D03*
Y349357D03*
Y351916D03*
X1528505Y323766D03*
Y326325D03*
Y339121D03*
Y334002D03*
Y328884D03*
Y341680D03*
Y336561D03*
Y331443D03*
Y344239D03*
Y351916D03*
Y349357D03*
Y346798D03*
G54D52*
X22756Y1506877D03*
Y1508846D03*
Y1510814D03*
Y1512783D03*
Y1514751D03*
Y1516720D03*
Y1518688D03*
Y1520657D03*
Y1522625D03*
Y1524594D03*
Y1526562D03*
Y1528531D03*
Y1530499D03*
Y1532468D03*
Y1534436D03*
Y1536405D03*
X57402Y1512783D03*
Y1510814D03*
Y1508846D03*
Y1506877D03*
Y1528531D03*
Y1526562D03*
Y1524594D03*
Y1522625D03*
Y1520657D03*
Y1518688D03*
Y1516720D03*
Y1514751D03*
Y1536405D03*
Y1534436D03*
Y1532468D03*
Y1530499D03*
G54D226*
X943716Y861015D03*
Y857865D03*
G54D109*
X109882Y1453504D03*
Y1468859D03*
Y1484213D03*
Y1499567D03*
Y1514922D03*
Y1555867D03*
Y1571221D03*
Y1586575D03*
Y1601930D03*
Y1617284D03*
X127205Y1453504D03*
X118543Y1457835D03*
X127205Y1468859D03*
X118543Y1473189D03*
X127205Y1484213D03*
X118543Y1488544D03*
X127205Y1499567D03*
Y1514922D03*
X118543Y1503898D03*
Y1519252D03*
X127205Y1555867D03*
X118543Y1560197D03*
X127205Y1571221D03*
X118543Y1575552D03*
X127205Y1586575D03*
X118543Y1590906D03*
X127205Y1601930D03*
X118543Y1606260D03*
X127205Y1617284D03*
X118543Y1621615D03*
X144528Y1453504D03*
X135866Y1457835D03*
X144528Y1468859D03*
X135866Y1473189D03*
X144528Y1484213D03*
X135866Y1488544D03*
X144528Y1499567D03*
Y1514922D03*
X135866Y1503898D03*
Y1519252D03*
X144528Y1555867D03*
X135866Y1560197D03*
X144528Y1571221D03*
X135866Y1575552D03*
X144528Y1586575D03*
X135866Y1590906D03*
X144528Y1601930D03*
X135866Y1606260D03*
X144528Y1617284D03*
X135866Y1621615D03*
X161850Y1453504D03*
X153189Y1457835D03*
X161850Y1468859D03*
X153189Y1473189D03*
X161850Y1484213D03*
X153189Y1488544D03*
X161850Y1499567D03*
Y1514922D03*
X153189Y1503898D03*
Y1519252D03*
X161850Y1555867D03*
X153189Y1560197D03*
X161850Y1571221D03*
X153189Y1575552D03*
X161850Y1586575D03*
X153189Y1590906D03*
X161850Y1601930D03*
X153189Y1606260D03*
X161850Y1617284D03*
X153189Y1621615D03*
X179173Y1453504D03*
X170512Y1457835D03*
X179173Y1468859D03*
X170512Y1473189D03*
X179173Y1484213D03*
X170512Y1488544D03*
X179173Y1499567D03*
Y1514922D03*
X170512Y1503898D03*
Y1519252D03*
X179173Y1555867D03*
X170512Y1560197D03*
X179173Y1571221D03*
X170512Y1575552D03*
X179173Y1586575D03*
X170512Y1590906D03*
X179173Y1601930D03*
X170512Y1606260D03*
X179173Y1617284D03*
X170512Y1621615D03*
X187835Y1457835D03*
Y1473189D03*
Y1488544D03*
Y1503898D03*
Y1519252D03*
Y1560197D03*
Y1575552D03*
Y1590906D03*
Y1606260D03*
Y1621615D03*
X283110Y1453504D03*
X291771Y1457835D03*
X283110Y1468859D03*
X291771Y1473189D03*
X283110Y1484213D03*
X291771Y1488544D03*
X283110Y1499567D03*
X291771Y1503898D03*
X283110Y1514922D03*
X291771Y1519252D03*
X283110Y1555867D03*
X291771Y1560197D03*
X283110Y1571221D03*
X291771Y1575552D03*
X283110Y1586575D03*
X291771Y1590906D03*
X283110Y1601930D03*
X291771Y1606260D03*
X283110Y1617284D03*
X291771Y1621615D03*
X300433Y1453504D03*
X309094Y1457835D03*
X300433Y1468859D03*
X309094Y1473189D03*
X300433Y1484213D03*
X309094Y1488544D03*
X300433Y1499567D03*
X309094Y1503898D03*
X300433Y1514922D03*
X309094Y1519252D03*
X300433Y1555867D03*
X309094Y1560197D03*
X300433Y1571221D03*
X309094Y1575552D03*
X300433Y1586575D03*
X309094Y1590906D03*
X300433Y1601930D03*
X309094Y1606260D03*
X300433Y1617284D03*
X309094Y1621615D03*
X317756Y1453504D03*
X326417Y1457835D03*
X317756Y1468859D03*
X326417Y1473189D03*
X317756Y1484213D03*
X326417Y1488544D03*
X317756Y1499567D03*
X326417Y1503898D03*
X317756Y1514922D03*
X326417Y1519252D03*
X317756Y1555867D03*
X326417Y1560197D03*
X317756Y1571221D03*
X326417Y1575552D03*
X317756Y1586575D03*
X326417Y1590906D03*
X317756Y1601930D03*
X326417Y1606260D03*
X317756Y1617284D03*
X326417Y1621615D03*
X335078Y1453504D03*
X343740Y1457835D03*
X335078Y1468859D03*
X343740Y1473189D03*
X335078Y1484213D03*
X343740Y1488544D03*
X335078Y1499567D03*
X343740Y1503898D03*
X335078Y1514922D03*
X343740Y1519252D03*
X335078Y1555867D03*
X343740Y1560197D03*
X335078Y1571221D03*
X343740Y1575552D03*
X335078Y1586575D03*
X343740Y1590906D03*
X335078Y1601930D03*
X343740Y1606260D03*
X335078Y1617284D03*
X343740Y1621615D03*
X352401Y1453504D03*
X361063Y1457835D03*
X352401Y1468859D03*
X361063Y1473189D03*
X352401Y1484213D03*
X361063Y1488544D03*
X352401Y1499567D03*
X361063Y1503898D03*
X352401Y1514922D03*
X361063Y1519252D03*
X352401Y1555867D03*
X361063Y1560197D03*
X352401Y1571221D03*
X361063Y1575552D03*
X352401Y1586575D03*
X361063Y1590906D03*
X352401Y1601930D03*
X361063Y1606260D03*
X352401Y1617284D03*
X361063Y1621615D03*
X456339Y1453504D03*
Y1468859D03*
Y1484213D03*
Y1499567D03*
Y1514922D03*
Y1555867D03*
Y1571221D03*
Y1586575D03*
Y1601930D03*
Y1617284D03*
X473662Y1453504D03*
X465000Y1457835D03*
X473662Y1468859D03*
X465000Y1473189D03*
X473662Y1484213D03*
X465000Y1488544D03*
X473662Y1499567D03*
Y1514922D03*
X465000Y1503898D03*
Y1519252D03*
X473662Y1555867D03*
X465000Y1560197D03*
X473662Y1571221D03*
X465000Y1575552D03*
X473662Y1586575D03*
X465000Y1590906D03*
X473662Y1601930D03*
X465000Y1606260D03*
X473662Y1617284D03*
X465000Y1621615D03*
X490985Y1453504D03*
X482323Y1457835D03*
X490985Y1468859D03*
X482323Y1473189D03*
X490985Y1484213D03*
X482323Y1488544D03*
X490985Y1499567D03*
Y1514922D03*
X482323Y1503898D03*
Y1519252D03*
X490985Y1555867D03*
X482323Y1560197D03*
X490985Y1571221D03*
X482323Y1575552D03*
X490985Y1586575D03*
X482323Y1590906D03*
X490985Y1601930D03*
X482323Y1606260D03*
X490985Y1617284D03*
X482323Y1621615D03*
X508307Y1453504D03*
X499646Y1457835D03*
X508307Y1468859D03*
X499646Y1473189D03*
X508307Y1484213D03*
X499646Y1488544D03*
X508307Y1499567D03*
Y1514922D03*
X499646Y1503898D03*
Y1519252D03*
X508307Y1555867D03*
X499646Y1560197D03*
X508307Y1571221D03*
X499646Y1575552D03*
X508307Y1586575D03*
X499646Y1590906D03*
X508307Y1601930D03*
X499646Y1606260D03*
X508307Y1617284D03*
X499646Y1621615D03*
X516969Y1457835D03*
Y1473189D03*
Y1488544D03*
Y1503898D03*
Y1519252D03*
Y1560197D03*
Y1575552D03*
Y1590906D03*
Y1606260D03*
Y1621615D03*
X525630Y1453504D03*
X534292Y1457835D03*
X525630Y1468859D03*
X534292Y1473189D03*
X525630Y1484213D03*
X534292Y1488544D03*
X525630Y1499567D03*
X534292Y1503898D03*
X525630Y1514922D03*
X534292Y1519252D03*
X525630Y1555867D03*
X534292Y1560197D03*
X525630Y1571221D03*
X534292Y1575552D03*
X525630Y1586575D03*
X534292Y1590906D03*
X525630Y1601930D03*
X534292Y1606260D03*
X525630Y1617284D03*
X534292Y1621615D03*
X629567Y1453504D03*
X638228Y1457835D03*
X629567Y1468859D03*
X638228Y1473189D03*
X629567Y1484213D03*
X638228Y1488544D03*
X629567Y1499567D03*
X638228Y1503898D03*
X629567Y1514922D03*
X638228Y1519252D03*
X629567Y1555867D03*
X638228Y1560197D03*
X629567Y1571221D03*
X638228Y1575552D03*
X629567Y1586575D03*
X638228Y1590906D03*
X629567Y1601930D03*
X638228Y1606260D03*
X629567Y1617284D03*
X638228Y1621615D03*
X646890Y1453504D03*
Y1468859D03*
Y1484213D03*
Y1499567D03*
Y1514922D03*
Y1555867D03*
Y1571221D03*
Y1586575D03*
Y1601930D03*
Y1617284D03*
X664213Y1453504D03*
X655551Y1457835D03*
X664213Y1468859D03*
X655551Y1473189D03*
X664213Y1484213D03*
X655551Y1488544D03*
X664213Y1499567D03*
Y1514922D03*
X655551Y1503898D03*
Y1519252D03*
X664213Y1555867D03*
X655551Y1560197D03*
X664213Y1571221D03*
X655551Y1575552D03*
X664213Y1586575D03*
X655551Y1590906D03*
X664213Y1601930D03*
X655551Y1606260D03*
X664213Y1617284D03*
X655551Y1621615D03*
X681535Y1453504D03*
X672874Y1457835D03*
X681535Y1468859D03*
X672874Y1473189D03*
X681535Y1484213D03*
X672874Y1488544D03*
X681535Y1499567D03*
Y1514922D03*
X672874Y1503898D03*
Y1519252D03*
X681535Y1555867D03*
X672874Y1560197D03*
X681535Y1571221D03*
X672874Y1575552D03*
X681535Y1586575D03*
X672874Y1590906D03*
X681535Y1601930D03*
X672874Y1606260D03*
X681535Y1617284D03*
X672874Y1621615D03*
X698858Y1453504D03*
X690197Y1457835D03*
X698858Y1468859D03*
X690197Y1473189D03*
X698858Y1484213D03*
X690197Y1488544D03*
X698858Y1499567D03*
Y1514922D03*
X690197Y1503898D03*
Y1519252D03*
X698858Y1555867D03*
X690197Y1560197D03*
X698858Y1571221D03*
X690197Y1575552D03*
X698858Y1586575D03*
X690197Y1590906D03*
X698858Y1601930D03*
X690197Y1606260D03*
X698858Y1617284D03*
X690197Y1621615D03*
X707520Y1457835D03*
Y1473189D03*
Y1488544D03*
Y1503898D03*
Y1519252D03*
Y1560197D03*
Y1575552D03*
Y1590906D03*
Y1606260D03*
Y1621615D03*
X1131850Y1453504D03*
X1140511Y1457835D03*
X1131850Y1468859D03*
X1140511Y1473189D03*
X1131850Y1484213D03*
X1140511Y1488544D03*
X1131850Y1499567D03*
X1140511Y1503898D03*
X1131850Y1514922D03*
X1140511Y1519252D03*
X1131850Y1555867D03*
X1140511Y1560197D03*
X1131850Y1571221D03*
X1140511Y1575552D03*
X1131850Y1586575D03*
X1140511Y1590906D03*
X1131850Y1601930D03*
X1140511Y1606260D03*
X1131850Y1617284D03*
X1140511Y1621615D03*
X1149173Y1453504D03*
X1157834Y1457835D03*
X1149173Y1468859D03*
X1157834Y1473189D03*
X1149173Y1484213D03*
X1157834Y1488544D03*
X1149173Y1499567D03*
X1157834Y1503898D03*
X1149173Y1514922D03*
X1157834Y1519252D03*
X1149173Y1555867D03*
X1157834Y1560197D03*
X1149173Y1571221D03*
X1157834Y1575552D03*
X1149173Y1586575D03*
X1157834Y1590906D03*
X1149173Y1601930D03*
X1157834Y1606260D03*
X1149173Y1617284D03*
X1157834Y1621615D03*
X1166496Y1453504D03*
Y1468859D03*
Y1484213D03*
Y1499567D03*
Y1514922D03*
Y1555867D03*
Y1571221D03*
Y1586575D03*
Y1601930D03*
Y1617284D03*
X1183818Y1453504D03*
X1175157Y1457835D03*
X1183818Y1468859D03*
X1175157Y1473189D03*
X1183818Y1484213D03*
X1175157Y1488544D03*
X1183818Y1499567D03*
Y1514922D03*
X1175157Y1503898D03*
Y1519252D03*
X1183818Y1555867D03*
X1175157Y1560197D03*
X1183818Y1571221D03*
X1175157Y1575552D03*
X1183818Y1586575D03*
X1175157Y1590906D03*
X1183818Y1601930D03*
X1175157Y1606260D03*
X1183818Y1617284D03*
X1175157Y1621615D03*
X1201141Y1453504D03*
X1192480Y1457835D03*
X1201141Y1468859D03*
X1192480Y1473189D03*
X1201141Y1484213D03*
X1192480Y1488544D03*
X1201141Y1499567D03*
Y1514922D03*
X1192480Y1503898D03*
Y1519252D03*
X1201141Y1555867D03*
X1192480Y1560197D03*
X1201141Y1571221D03*
X1192480Y1575552D03*
X1201141Y1586575D03*
X1192480Y1590906D03*
X1201141Y1601930D03*
X1192480Y1606260D03*
X1201141Y1617284D03*
X1192480Y1621615D03*
X1209803Y1457835D03*
Y1473189D03*
Y1488544D03*
Y1503898D03*
Y1519252D03*
Y1560197D03*
Y1575552D03*
Y1590906D03*
Y1606260D03*
Y1621615D03*
X1305079Y1453504D03*
X1313740Y1457835D03*
X1305079Y1468859D03*
X1313740Y1473189D03*
X1305079Y1484213D03*
X1313740Y1488544D03*
X1305079Y1499567D03*
X1313740Y1503898D03*
X1305079Y1514922D03*
X1313740Y1519252D03*
X1305079Y1555867D03*
X1313740Y1560197D03*
X1305079Y1571221D03*
X1313740Y1575552D03*
X1305079Y1586575D03*
X1313740Y1590906D03*
X1305079Y1601930D03*
X1313740Y1606260D03*
X1305079Y1617284D03*
X1313740Y1621615D03*
X1322402Y1453504D03*
X1331063Y1457835D03*
X1322402Y1468859D03*
X1331063Y1473189D03*
X1322402Y1484213D03*
X1331063Y1488544D03*
X1322402Y1499567D03*
X1331063Y1503898D03*
X1322402Y1514922D03*
X1331063Y1519252D03*
X1322402Y1555867D03*
X1331063Y1560197D03*
X1322402Y1571221D03*
X1331063Y1575552D03*
X1322402Y1586575D03*
X1331063Y1590906D03*
X1322402Y1601930D03*
X1331063Y1606260D03*
X1322402Y1617284D03*
X1331063Y1621615D03*
X1339725Y1453504D03*
X1348386Y1457835D03*
X1339725Y1468859D03*
X1348386Y1473189D03*
X1339725Y1484213D03*
X1348386Y1488544D03*
X1339725Y1499567D03*
X1348386Y1503898D03*
X1339725Y1514922D03*
X1348386Y1519252D03*
X1339725Y1555867D03*
X1348386Y1560197D03*
X1339725Y1571221D03*
X1348386Y1575552D03*
X1339725Y1586575D03*
X1348386Y1590906D03*
X1339725Y1601930D03*
X1348386Y1606260D03*
X1339725Y1617284D03*
X1348386Y1621615D03*
X1357047Y1453504D03*
X1365709Y1457835D03*
X1357047Y1468859D03*
X1365709Y1473189D03*
X1357047Y1484213D03*
X1365709Y1488544D03*
X1357047Y1499567D03*
X1365709Y1503898D03*
X1357047Y1514922D03*
X1365709Y1519252D03*
X1357047Y1555867D03*
X1365709Y1560197D03*
X1357047Y1571221D03*
X1365709Y1575552D03*
X1357047Y1586575D03*
X1365709Y1590906D03*
X1357047Y1601930D03*
X1365709Y1606260D03*
X1357047Y1617284D03*
X1365709Y1621615D03*
X1374370Y1453504D03*
X1383032Y1457835D03*
X1374370Y1468859D03*
X1383032Y1473189D03*
X1374370Y1484213D03*
X1383032Y1488544D03*
X1374370Y1499567D03*
X1383032Y1503898D03*
X1374370Y1514922D03*
X1383032Y1519252D03*
X1374370Y1555867D03*
X1383032Y1560197D03*
X1374370Y1571221D03*
X1383032Y1575552D03*
X1374370Y1586575D03*
X1383032Y1590906D03*
X1374370Y1601930D03*
X1383032Y1606260D03*
X1374370Y1617284D03*
X1383032Y1621615D03*
X1478307Y1453504D03*
Y1468859D03*
Y1484213D03*
Y1499567D03*
Y1514922D03*
Y1555867D03*
Y1571221D03*
Y1586575D03*
Y1601930D03*
Y1617284D03*
X1495630Y1453504D03*
X1486968Y1457835D03*
X1495630Y1468859D03*
X1486968Y1473189D03*
X1495630Y1484213D03*
X1486968Y1488544D03*
X1495630Y1499567D03*
Y1514922D03*
X1486968Y1503898D03*
Y1519252D03*
X1495630Y1555867D03*
X1486968Y1560197D03*
X1495630Y1571221D03*
X1486968Y1575552D03*
X1495630Y1586575D03*
X1486968Y1590906D03*
X1495630Y1601930D03*
X1486968Y1606260D03*
X1495630Y1617284D03*
X1486968Y1621615D03*
X1512953Y1453504D03*
X1504291Y1457835D03*
X1512953Y1468859D03*
X1504291Y1473189D03*
X1512953Y1484213D03*
X1504291Y1488544D03*
X1512953Y1499567D03*
Y1514922D03*
X1504291Y1503898D03*
Y1519252D03*
X1512953Y1555867D03*
X1504291Y1560197D03*
X1512953Y1571221D03*
X1504291Y1575552D03*
X1512953Y1586575D03*
X1504291Y1590906D03*
X1512953Y1601930D03*
X1504291Y1606260D03*
X1512953Y1617284D03*
X1504291Y1621615D03*
X1530275Y1453504D03*
X1521614Y1457835D03*
X1530275Y1468859D03*
X1521614Y1473189D03*
X1530275Y1484213D03*
X1521614Y1488544D03*
X1530275Y1499567D03*
Y1514922D03*
X1521614Y1503898D03*
Y1519252D03*
X1530275Y1555867D03*
X1521614Y1560197D03*
X1530275Y1571221D03*
X1521614Y1575552D03*
X1530275Y1586575D03*
X1521614Y1590906D03*
X1530275Y1601930D03*
X1521614Y1606260D03*
X1530275Y1617284D03*
X1521614Y1621615D03*
X1547598Y1453504D03*
X1538937Y1457835D03*
X1547598Y1468859D03*
X1538937Y1473189D03*
X1547598Y1484213D03*
X1538937Y1488544D03*
X1547598Y1499567D03*
Y1514922D03*
X1538937Y1503898D03*
Y1519252D03*
X1547598Y1555867D03*
X1538937Y1560197D03*
X1547598Y1571221D03*
X1538937Y1575552D03*
X1547598Y1586575D03*
X1538937Y1590906D03*
X1547598Y1601930D03*
X1538937Y1606260D03*
X1547598Y1617284D03*
X1538937Y1621615D03*
X1556260Y1457835D03*
Y1473189D03*
Y1488544D03*
Y1503898D03*
Y1519252D03*
Y1560197D03*
Y1575552D03*
Y1590906D03*
Y1606260D03*
Y1621615D03*
X1651535Y1453504D03*
X1660196Y1457835D03*
X1651535Y1468859D03*
X1660196Y1473189D03*
X1651535Y1484213D03*
X1660196Y1488544D03*
X1651535Y1499567D03*
X1660196Y1503898D03*
X1651535Y1514922D03*
X1660196Y1519252D03*
X1651535Y1555867D03*
X1660196Y1560197D03*
X1651535Y1571221D03*
X1660196Y1575552D03*
X1651535Y1586575D03*
X1660196Y1590906D03*
X1651535Y1601930D03*
X1660196Y1606260D03*
X1651535Y1617284D03*
X1660196Y1621615D03*
X1668858Y1453504D03*
X1677519Y1457835D03*
X1668858Y1468859D03*
X1677519Y1473189D03*
X1668858Y1484213D03*
X1677519Y1488544D03*
X1668858Y1499567D03*
X1677519Y1503898D03*
X1668858Y1514922D03*
X1677519Y1519252D03*
X1668858Y1555867D03*
X1677519Y1560197D03*
X1668858Y1571221D03*
X1677519Y1575552D03*
X1668858Y1586575D03*
X1677519Y1590906D03*
X1668858Y1601930D03*
X1677519Y1606260D03*
X1668858Y1617284D03*
X1677519Y1621615D03*
X1686181Y1453504D03*
Y1468859D03*
Y1484213D03*
Y1499567D03*
Y1514922D03*
Y1555867D03*
Y1571221D03*
Y1586575D03*
Y1601930D03*
Y1617284D03*
X1703503Y1453504D03*
X1694842Y1457835D03*
X1703503Y1468859D03*
X1694842Y1473189D03*
X1703503Y1484213D03*
X1694842Y1488544D03*
X1703503Y1499567D03*
Y1514922D03*
X1694842Y1503898D03*
Y1519252D03*
X1703503Y1555867D03*
X1694842Y1560197D03*
X1703503Y1571221D03*
X1694842Y1575552D03*
X1703503Y1586575D03*
X1694842Y1590906D03*
X1703503Y1601930D03*
X1694842Y1606260D03*
X1703503Y1617284D03*
X1694842Y1621615D03*
X1720826Y1453504D03*
X1712165Y1457835D03*
X1720826Y1468859D03*
X1712165Y1473189D03*
X1720826Y1484213D03*
X1712165Y1488544D03*
X1720826Y1499567D03*
Y1514922D03*
X1712165Y1503898D03*
Y1519252D03*
X1720826Y1555867D03*
X1712165Y1560197D03*
X1720826Y1571221D03*
X1712165Y1575552D03*
X1720826Y1586575D03*
X1712165Y1590906D03*
X1720826Y1601930D03*
X1712165Y1606260D03*
X1720826Y1617284D03*
X1712165Y1621615D03*
X1729488Y1457835D03*
Y1473189D03*
Y1488544D03*
Y1503898D03*
Y1519252D03*
Y1560197D03*
Y1575552D03*
Y1590906D03*
Y1606260D03*
Y1621615D03*
G54D70*
X52707Y1084666D03*
X73499Y587848D03*
X89945Y182850D03*
X192307D03*
X294669D03*
X359496Y394525D03*
X387809Y957627D03*
X397031Y182850D03*
X530585Y587848D03*
X547032Y182850D03*
X649394D03*
X751756D03*
X854118D03*
X860251Y402526D03*
X899397Y1093669D03*
X963374D03*
X987672Y587848D03*
X1004118Y182850D03*
X1106480D03*
X1208842D03*
X1273669Y394525D03*
X1311204Y182850D03*
X1444759Y587848D03*
X1461205Y182850D03*
X1563567D03*
X1665929D03*
X1730756Y394525D03*
X1768291Y182850D03*
X1807354Y1094155D03*
G54D235*
X953192Y-31798D03*
X978036Y-70978D03*
X1231336D03*
X1236692Y-31928D03*
X1487836Y-70978D03*
X1523192Y-32058D03*
X1742336Y-70978D03*
X1807692Y-32188D03*
G54D208*
X895384Y228740D03*
Y276772D03*
X923336Y226772D03*
Y278740D03*
G54D163*
X438244Y1059069D03*
Y1080329D03*
X471246Y1059069D03*
Y1080329D03*
X1352418Y1059069D03*
Y1080329D03*
X1385420Y1059069D03*
Y1080329D03*
G54D244*
X1022350Y331915D03*
G54D272*
G01X45755Y1201110D02*
X47456D01*
X49500Y1199066D01*
G01X45755Y1204259D02*
X48274D01*
X49180Y1203884D01*
X49638D01*
G01X45755Y1205834D02*
X50028D01*
X50741Y1205539D01*
X51617Y1204663D01*
G01X45755Y1202684D02*
X47440D01*
X50499Y1201416D01*
X51023D01*
G01X45755Y1208984D02*
X48190D01*
G01X45755Y1207409D02*
X49589D01*
G01X410938Y875223D02*
X408522D01*
X407597Y874840D01*
X406415D01*
G01X410938Y878373D02*
X408933D01*
X406967Y878764D01*
G01X410938Y879948D02*
X408613D01*
X407262Y881299D01*
X405466D01*
G01X410938Y873648D02*
X408212D01*
X407257Y872693D01*
G01X410938Y876798D02*
X406593D01*
X405808Y877123D01*
X404444Y878487D01*
G01X410938Y881522D02*
X409237D01*
X407193Y883566D01*
G01X422988Y326886D02*
Y323627D01*
G01X410688Y344736D02*
X412983D01*
X413707Y344012D01*
X416886D01*
G01Y332988D02*
X414409D01*
X413979Y333418D01*
X412671D01*
G01X416886Y331413D02*
X413608D01*
X412812Y330617D01*
G01X416886Y345587D02*
X414642D01*
X413432Y346797D01*
G01X430361Y323187D02*
Y323451D01*
X429287Y324525D01*
Y326886D01*
G01X440114Y332988D02*
X443424D01*
G01X426138Y350114D02*
Y355079D01*
G01X429287Y350114D02*
Y352711D01*
X428420Y353578D01*
G01X435587Y350114D02*
Y353568D01*
X435886Y353867D01*
G01X438087Y628237D02*
X439788D01*
X441832Y626193D01*
G01X438087Y631386D02*
X440068D01*
X440973Y631011D01*
X441612D01*
G01X438087Y634536D02*
X441921D01*
G01X438087Y629811D02*
X440054D01*
X441212Y628653D01*
X443143D01*
X443144Y628654D01*
Y628667D01*
G01X438087Y636111D02*
X440813D01*
X440868Y636166D01*
G01X438087Y632961D02*
X442420D01*
X444482Y630899D01*
X444954D01*
G01X459360Y1007180D02*
Y1008504D01*
X462647Y1011791D01*
X466046D01*
G01Y1022815D02*
X464542D01*
X462666Y1024691D01*
X461091D01*
G01Y1027841D02*
X463151D01*
X463853Y1027139D01*
Y1025504D01*
X464967Y1024390D01*
X466046D01*
G01X470978Y1046591D02*
X476630D01*
X479432Y1043789D01*
Y1026752D01*
G01X477857D02*
Y1027956D01*
X478000Y1028099D01*
Y1040643D01*
X475588Y1043055D01*
G01X889445Y1210113D02*
X891146D01*
X893190Y1208069D01*
G01X889445Y1213262D02*
X891964D01*
X892870Y1212887D01*
X893328D01*
G01X889445Y1211687D02*
X891130D01*
X894189Y1210419D01*
X894713D01*
G01X889445Y1216412D02*
X893279D01*
G01X889445Y1217987D02*
X891880D01*
G01X889445Y1214837D02*
X893718D01*
X894431Y1214542D01*
X895307Y1213666D01*
G01X910492Y311046D02*
X913057D01*
G01X908846Y564037D02*
Y560124D01*
G01X953422Y1210113D02*
X955123D01*
X957167Y1208069D01*
G01X953422Y1213262D02*
X955941D01*
X956847Y1212887D01*
X957305D01*
G01X953422Y1211687D02*
X955107D01*
X958166Y1210419D01*
X958690D01*
G01X953422Y1217987D02*
X955857D01*
G01X953422Y1214837D02*
X957695D01*
X958408Y1214542D01*
X959284Y1213666D01*
G01X953422Y1216412D02*
X957256D01*
G01X1007094Y323057D02*
X1006142D01*
X1005899Y323300D01*
X1003424D01*
X1003181Y323057D01*
G01X1319471Y336080D02*
X1317073D01*
X1316643Y336510D01*
X1315256D01*
G01X1319471Y334505D02*
X1316193D01*
X1315397Y333709D01*
G01X1319471Y348679D02*
X1317227D01*
X1316017Y349889D01*
G01X1312731Y348041D02*
X1313668Y347104D01*
G01D02*
X1319471D01*
G01X1331872Y329978D02*
Y327446D01*
X1332563Y326755D01*
Y326356D01*
G01X1325573Y329978D02*
Y326719D01*
G01X1328723Y353206D02*
Y355841D01*
X1327619Y356945D01*
X1326489D01*
G01X1331872Y353206D02*
Y355803D01*
X1331005Y356670D01*
G01X1342699Y336080D02*
X1346009D01*
G01X1338172Y353206D02*
Y356660D01*
X1338471Y356959D01*
G01X1380220Y1011791D02*
X1376821D01*
X1373534Y1008504D01*
Y1007180D01*
G01X1380220Y1022815D02*
X1378482D01*
X1376606Y1024691D01*
X1375265D01*
G01Y1027841D02*
X1376784D01*
X1377422Y1027203D01*
Y1025807D01*
X1378839Y1024390D01*
X1380220D01*
G01X1393606Y1026752D02*
Y1043789D01*
X1390804Y1046591D01*
X1385152D01*
G01X1392031Y1026752D02*
Y1027732D01*
X1392200Y1027901D01*
Y1040617D01*
X1389762Y1043055D01*
G01X1797402Y1210599D02*
X1799103D01*
X1801147Y1208555D01*
G01X1797402Y1213748D02*
X1799921D01*
X1800827Y1213373D01*
X1801285D01*
G01X1797402Y1216898D02*
X1801236D01*
G01X1797402Y1215323D02*
X1801675D01*
X1802388Y1215028D01*
X1803264Y1214152D01*
G01X1797402Y1218473D02*
X1799837D01*
G01X1797402Y1212173D02*
X1799087D01*
X1802146Y1210905D01*
X1802670D01*
G54D263*
G01X14951Y156163D02*
Y154599D01*
X13615Y153263D01*
G01X32051Y213243D02*
X34224D01*
X34520Y213539D01*
G01X26146Y225055D02*
Y227215D01*
X24559Y231047D01*
X24091Y231515D01*
Y232971D01*
G01X34845Y289272D02*
Y291756D01*
G01X38323Y538456D02*
X34735D01*
X33005Y536726D01*
X31549D01*
G01X30177Y534211D02*
X31548D01*
X31549Y534212D01*
Y536726D01*
G01X44976Y593689D02*
X27553D01*
X26192Y595050D01*
Y613736D01*
G01X33267Y629311D02*
X34977D01*
X36575Y627713D01*
G01X48154Y491712D02*
X46868D01*
X45787Y490631D01*
Y490479D01*
X43600Y488292D01*
Y486769D01*
X41380Y484549D01*
Y483982D01*
G01X50135Y544361D02*
Y546534D01*
X49839Y546830D01*
G01X45057Y593770D02*
X44976Y593689D01*
G01X45255Y624823D02*
Y627033D01*
X39583Y632705D01*
Y640441D01*
G01X43286Y624823D02*
Y626662D01*
X36692Y633256D01*
Y633724D01*
G01D02*
Y636236D01*
G01X42192D02*
Y633736D01*
X42172Y633716D01*
G01D02*
X42192Y633696D01*
Y632620D01*
X46832Y627980D01*
X47224Y627034D01*
Y624823D01*
G01X49192D02*
Y628078D01*
G01X50329Y631212D02*
Y636099D01*
X50192Y636236D01*
G01X49192Y628078D02*
Y629479D01*
X49909Y631211D01*
X49910Y631212D01*
X50329D01*
G01X47179D02*
Y633736D01*
G01D02*
X46192Y634723D01*
Y636236D01*
G01X36575Y627713D02*
X39446D01*
X41318Y625841D01*
Y624823D01*
G01X49449Y688473D02*
Y690226D01*
X50034Y690811D01*
G01D02*
X52182D01*
X53861Y692490D01*
X86031D01*
X91838Y686683D01*
Y682577D01*
G01X44365Y1086404D02*
X46186Y1085650D01*
X47195D01*
G01X43766Y1093757D02*
Y1089973D01*
X46120Y1087619D01*
X47195D01*
G01X53737Y1196830D02*
X51736D01*
X49500Y1199066D01*
G01X51617Y1204663D02*
X53620Y1202660D01*
X57553D01*
G01X53737Y1199980D02*
X52459D01*
X51023Y1201416D01*
G01X48190Y1208984D02*
X48215Y1209009D01*
X49398D01*
X51644Y1209939D01*
X53056D01*
G01X49589Y1207409D02*
X50275D01*
X51772Y1206789D01*
X53056D01*
G01X61186Y451557D02*
Y450538D01*
X59522Y448874D01*
G01X64408Y578907D02*
X66062D01*
X69491Y582336D01*
X70546D01*
G01X55098Y624823D02*
Y627308D01*
X55318Y627528D01*
Y629362D01*
G01X53129Y624823D02*
Y627948D01*
G01X57702Y1195670D02*
X54897D01*
X53737Y1196830D01*
G01X57553Y1202660D02*
X57702Y1202511D01*
Y1198820D01*
G01X65379Y1205835D02*
X64057Y1204542D01*
X62380D01*
X61380Y1205542D01*
Y1205546D01*
G01Y1202396D02*
X60210D01*
X59817Y1202789D01*
X59632Y1203236D01*
Y1203979D01*
X57801Y1205810D01*
X57553D01*
G01X61380Y1202396D02*
X62612D01*
X63156Y1202940D01*
X64275D01*
X65350Y1201865D01*
X65379Y1201565D01*
G01X57553Y1205810D02*
X57190Y1206173D01*
X56182D01*
X55188Y1205179D01*
G01D02*
X53578Y1206789D01*
X53056D01*
G01X61360Y1209720D02*
Y1213720D01*
G01X61380Y1205546D02*
Y1205890D01*
X63094Y1207604D01*
G01D02*
X61360Y1209338D01*
Y1209720D01*
G01X58210Y1213720D02*
Y1209720D01*
G01X53056Y1209939D02*
X54378D01*
X54905Y1210466D01*
X55596D01*
G01D02*
X56171D01*
X56917Y1209720D01*
X58210D01*
G01X84433Y179897D02*
X82783D01*
X80502Y177616D01*
G01X73711Y176148D02*
X77711D01*
G01X80502Y177616D02*
X79034Y176148D01*
X77711D01*
G01Y172998D02*
X77659Y172946D01*
Y168697D01*
G01X86992Y177338D02*
Y175335D01*
X83847Y172190D01*
X81083D01*
G01D02*
X80275Y172998D01*
X77711D01*
G01X77854Y191941D02*
X75072D01*
G01X84433Y183834D02*
X82357D01*
X81572Y184619D01*
G01X74939Y188727D02*
X76261Y187405D01*
X77938D01*
G01X81004Y191941D02*
X84844D01*
G01X84433Y185803D02*
X83358D01*
X81004Y188157D01*
Y191941D01*
G01X83256Y209229D02*
Y207056D01*
X83552Y206760D01*
G01X80201Y571614D02*
Y575614D01*
G01X72515Y582336D02*
Y580260D01*
X71730Y579475D01*
G01X76452Y582336D02*
Y580686D01*
X78733Y578405D01*
G01D02*
X80201Y576937D01*
Y575614D01*
G01X83351D02*
X83403Y575562D01*
X87652D01*
G01X83351Y575614D02*
Y578178D01*
X84159Y578986D01*
G01D02*
Y581614D01*
X80878Y584895D01*
X79011D01*
G01X77688Y847363D02*
X78533Y846518D01*
Y836380D01*
X77710Y835557D01*
X75049D01*
G01X69309Y1055646D02*
Y1060748D01*
X69373Y1060812D01*
G01X69291Y1046138D02*
Y1050756D01*
X69263Y1050784D01*
G01D02*
Y1053152D01*
G01X69373Y1060812D02*
Y1063389D01*
G01X68529Y1201565D02*
X70947D01*
G01X68529Y1205835D02*
X70947D01*
G01X101747Y188665D02*
X100434D01*
X99639Y187870D01*
Y186629D01*
G01X95068Y215134D02*
X98656D01*
X100386Y216864D01*
X101842D01*
G01X104897Y172665D02*
X107540D01*
G01X104897Y180665D02*
X107540D01*
G01X104897Y176665D02*
X107540D01*
G01X104897Y168665D02*
X107540D01*
G01X104992Y200864D02*
X107572D01*
G01X104992Y212864D02*
X107572D01*
G01X104992Y204864D02*
X107572D01*
G01X104992Y216864D02*
X107572D01*
G01X104992Y221864D02*
X107572D01*
G01X103213Y219379D02*
X103090D01*
X101842Y218131D01*
Y216864D01*
G01X128508Y225055D02*
Y227215D01*
X126921Y231047D01*
X126453Y231515D01*
Y232971D01*
G01X134413Y213243D02*
X136586D01*
X136882Y213539D01*
G01X145078Y1176180D02*
Y1176179D01*
X146947Y1174310D01*
G01X156299Y1138779D02*
X154429Y1140649D01*
G01X160039Y1138779D02*
X158169Y1140649D01*
G01X163779Y1138779D02*
X161909Y1140649D01*
G01X180073Y176148D02*
X181396D01*
X182864Y177616D01*
G01X176073Y176148D02*
X180073D01*
G01Y172998D02*
X182637D01*
X183445Y172190D01*
G01X180073Y172998D02*
X180021Y172946D01*
Y168697D01*
G01X180216Y191941D02*
X177434D01*
G01X177301Y188727D02*
X178623Y187405D01*
X180300D01*
G01X174999Y1183661D02*
X175000D01*
X176870Y1185531D01*
G01X174999Y1187401D02*
X175000D01*
X176870Y1185531D01*
G01X174999Y1183661D02*
X173129Y1185531D01*
G01X174999Y1183661D02*
X173129Y1181791D01*
G01X182864Y177616D02*
X185145Y179897D01*
X186795D01*
G01X183445Y172190D02*
X186209D01*
X189354Y175335D01*
Y177338D01*
G01X186795Y183834D02*
X184719D01*
X183934Y184619D01*
G01X183366Y191941D02*
Y188157D01*
X185720Y185803D01*
X186795D01*
G01X187206Y191941D02*
X183366D01*
G01X185618Y209229D02*
Y207056D01*
X185914Y206760D01*
G01X197430Y215134D02*
X201018D01*
X202748Y216864D01*
X204204D01*
G01X186220Y1138779D02*
X184350Y1136909D01*
G01X186220Y1149999D02*
Y1150000D01*
X188090Y1151870D01*
G01X189960Y1157480D02*
X188090Y1155610D01*
G01X186220Y1164960D02*
X182480D01*
G01X186220Y1157480D02*
X188090Y1159350D01*
G01X186220Y1202362D02*
Y1202361D01*
X188090Y1200491D01*
G01X213711Y113684D02*
Y112120D01*
X212375Y110784D01*
G01X207259Y172665D02*
X209902D01*
G01X207259Y180665D02*
X209902D01*
G01X207259Y176665D02*
X209902D01*
G01X207259Y168665D02*
X209902D01*
G01X204109Y188665D02*
X202796D01*
X202001Y187870D01*
Y186629D01*
G01X207354Y200864D02*
X209934D01*
G01X207354Y212864D02*
X209934D01*
G01X207354Y204864D02*
X209934D01*
G01X207354Y216864D02*
X209934D01*
G01X207354Y221864D02*
X209934D01*
G01X205575Y219379D02*
X205452D01*
X204204Y218131D01*
Y216864D01*
G01X230870Y225055D02*
Y227215D01*
X229283Y231047D01*
X228815Y231515D01*
Y232971D01*
G01X219881Y1213582D02*
X218011Y1211712D01*
G01X236775Y213243D02*
X238948D01*
X239244Y213539D01*
G01X238582Y1123818D02*
X236712Y1121948D01*
G01D02*
X234842Y1120078D01*
G01X278435Y176148D02*
X282435D01*
G01X279663Y188727D02*
X280985Y187405D01*
X282662D01*
G01X291716Y177338D02*
Y175335D01*
X288571Y172190D01*
X285807D01*
G01X282435Y172998D02*
X282383Y172946D01*
Y168697D01*
G01X285807Y172190D02*
X284999Y172998D01*
X282435D01*
G01X289157Y179897D02*
X287507D01*
X285226Y177616D01*
G01D02*
X283758Y176148D01*
X282435D01*
G01X282578Y191941D02*
X279796D01*
G01X289157Y183834D02*
X287081D01*
X286296Y184619D01*
G01X285728Y191941D02*
X289568D01*
G01X289157Y185803D02*
X288082D01*
X285728Y188157D01*
Y191941D01*
G01X287980Y209229D02*
Y207056D01*
X288276Y206760D01*
G01X287204Y1179921D02*
X285334Y1178051D01*
G01X287204Y1183661D02*
X289074Y1181791D01*
G01X309621Y172665D02*
X312264D01*
G01X309621Y180665D02*
X312264D01*
G01X309621Y176665D02*
X312264D01*
G01X309621Y168665D02*
X312264D01*
G01X306471Y188665D02*
X305158D01*
X304363Y187870D01*
Y186629D01*
G01X309716Y212864D02*
X312296D01*
G01X309716Y200864D02*
X312296D01*
G01X309716Y204864D02*
X312296D01*
G01X309716Y221864D02*
X312296D01*
G01X309716Y216864D02*
X312296D01*
G01X299792Y215134D02*
X303380D01*
X305110Y216864D01*
X306566D01*
G01X307313Y316731D02*
X310013D01*
G01X316073Y113684D02*
Y112120D01*
X314737Y110784D01*
G01X339137Y213243D02*
X341310D01*
X341606Y213539D01*
G01X333232Y225055D02*
Y227215D01*
X331645Y231047D01*
X331177Y231515D01*
Y232971D01*
G01X361234Y402867D02*
X360480Y401046D01*
Y400037D01*
G01X379461Y395544D02*
X377288D01*
X376992Y395248D01*
G01X368587Y403466D02*
X364803D01*
X362449Y401112D01*
Y400037D01*
G01X369178Y472606D02*
X366860D01*
X366443Y472189D01*
G01X372857Y959812D02*
X370214D01*
G01X376007Y951812D02*
Y951888D01*
X377815Y953696D01*
X378119D01*
G01X372857Y967812D02*
X370214D01*
G01X372857Y963812D02*
X370214D01*
G01X372857Y971812D02*
X370214D01*
G01X380797Y176148D02*
X384797D01*
G01D02*
X386120D01*
X387588Y177616D01*
G01D02*
X389869Y179897D01*
X391519D01*
G01X394078Y177338D02*
Y175335D01*
X390933Y172190D01*
X388169D01*
G01X384797Y172998D02*
X384745Y172946D01*
Y168697D01*
G01X388169Y172190D02*
X387361Y172998D01*
X384797D01*
G01X384940Y191941D02*
X382158D01*
G01X391519Y183834D02*
X389443D01*
X388658Y184619D01*
G01X382025Y188727D02*
X383347Y187405D01*
X385024D01*
G01X388090Y191941D02*
X391930D01*
G01X391519Y185803D02*
X390444D01*
X388090Y188157D01*
Y191941D01*
G01X390342Y209229D02*
Y207056D01*
X390638Y206760D01*
G01X385366Y383732D02*
Y382312D01*
X387493Y380185D01*
G01X380990Y478511D02*
X382410D01*
X384537Y480638D01*
G01X395390Y875845D02*
X392584D01*
G01D02*
X392569Y875860D01*
X389627D01*
G01X391410Y930472D02*
X388388D01*
X387525Y929609D01*
Y886958D01*
X389627Y884856D01*
Y881760D01*
G01X391410Y930472D02*
X391614Y930676D01*
G01X396750Y948536D02*
Y950386D01*
X393321Y953815D01*
Y954674D01*
G01X392910Y948536D02*
X396750D01*
G01X390762Y963139D02*
X393443D01*
X394556Y964252D01*
Y966172D01*
X396671Y968287D01*
G01X408833Y188665D02*
X407520D01*
X406725Y187870D01*
Y186629D01*
G01X410299Y219379D02*
X410176D01*
X408928Y218131D01*
Y216864D01*
G01X402154Y215134D02*
X405742D01*
X407472Y216864D01*
X408928D01*
G01X406528Y349939D02*
Y344439D01*
G01D02*
X408550D01*
X408847Y344736D01*
X410688D01*
G01X398132Y444236D02*
X398051Y444317D01*
G01D02*
Y461740D01*
X399412Y463101D01*
X418098D01*
G01X399369Y875843D02*
X395392D01*
X395390Y875845D01*
G01X399369Y872693D02*
X403478D01*
G01X399369D02*
X395392D01*
G01X407257D02*
X403478D01*
G01X395392D02*
X395390Y872695D01*
G01X399052Y881198D02*
X399516Y880079D01*
X401108Y878487D01*
G01X404444D02*
X401108D01*
G01X399052Y884348D02*
X402865D01*
X402966Y884449D01*
G01D02*
X406310D01*
X407193Y883566D01*
G01X402966Y881299D02*
X405466D01*
G01X393321Y956643D02*
X395397D01*
X396182Y955858D01*
G01X399900Y948536D02*
X402682D01*
G01X399816Y953072D02*
X401493D01*
X402815Y951750D01*
G01X397252Y962861D02*
X394971Y960580D01*
X393321D01*
G01X400095Y971780D02*
Y967531D01*
X400043Y967479D01*
G01X396671Y968287D02*
X397479Y967479D01*
X400043D01*
G01X404043Y964329D02*
X400043D01*
G01D02*
X398720D01*
X397252Y962861D01*
G01X408964Y1534417D02*
Y1531149D01*
G01X399373Y1555855D02*
X401090Y1554138D01*
Y1553413D01*
G01X411983Y180665D02*
X414626D01*
G01X411983Y172665D02*
X414626D01*
G01X411983Y176665D02*
X414626D01*
G01X411983Y168665D02*
X414626D01*
G01X412078Y212864D02*
X414658D01*
G01X412078Y200864D02*
X414658D01*
G01X412078Y204864D02*
X414658D01*
G01X412078Y216864D02*
X414658D01*
G01X412078Y221864D02*
X414658D01*
G01X425060Y1101917D02*
X427913D01*
G01X414455Y1102555D02*
X410668D01*
G01X416494Y1539978D02*
X419619D01*
G01X416494Y1549821D02*
X417632D01*
X418132Y1550321D01*
Y1552451D01*
X418151Y1552470D01*
G01X429185Y434195D02*
X431670D01*
X431890Y433975D01*
X433724D01*
G01X429185Y436164D02*
X432310D01*
G01X429185Y440101D02*
X432440D01*
G01X440598Y439101D02*
X440461Y438964D01*
X435574D01*
G01X432440Y440101D02*
X433087D01*
X434224Y438964D01*
X435574D01*
G01X444803Y449710D02*
X437067D01*
X431395Y444038D01*
X429185D01*
G01Y447975D02*
X430203D01*
X432075Y449847D01*
Y452718D01*
G01D02*
X433673Y454316D01*
Y456026D01*
G01X435574Y442114D02*
X438098D01*
G01D02*
X439085Y443101D01*
X440598D01*
G01X429185Y446007D02*
X431024D01*
X437618Y452601D01*
X438086D01*
G01D02*
X440598D01*
G01X429185Y442069D02*
X431396D01*
X432342Y442461D01*
X436982Y447101D01*
X438058D01*
X438078Y447121D01*
G01D02*
X438098Y447101D01*
X440598D01*
G01X441921Y634536D02*
X442896D01*
X443551Y633881D01*
X444779D01*
G01X440868Y636166D02*
X442318D01*
X443183Y637031D01*
X444779D01*
G01X444954Y630899D02*
X447811D01*
X447921Y630789D01*
G01X431285Y1110321D02*
X431041D01*
X429526Y1111836D01*
G01X431285Y1113471D02*
X431476Y1113662D01*
Y1115896D01*
G01Y1118396D02*
Y1120630D01*
X431285Y1120821D01*
G01X442798Y493720D02*
Y491547D01*
X443094Y491251D01*
G01X454610Y499625D02*
X456058D01*
X458244Y501811D01*
Y503085D01*
X462828Y507669D01*
G01X454290Y625894D02*
X470170D01*
X474428Y621636D01*
Y544680D01*
X473030Y543282D01*
X468946D01*
G01X443144Y628667D02*
X443149Y628662D01*
X445718D01*
X445745Y628635D01*
G01X450402Y634279D02*
Y638279D01*
G01X447921Y630789D02*
X449745Y628965D01*
Y628635D01*
G01X453552Y638279D02*
Y634279D01*
G01X454290Y629044D02*
X453552Y629782D01*
Y631779D01*
G01D02*
Y634279D01*
G01X450402Y638279D02*
X448583D01*
X447335Y637031D01*
X447279D01*
G01D02*
X444779D01*
G01X451140Y1021793D02*
X452167Y1020766D01*
X452591D01*
G01X451140Y1021793D02*
X450167Y1022766D01*
X448666D01*
G01D02*
Y1026266D01*
G01X457166Y1024766D02*
X461016D01*
X461091Y1024691D01*
G01X454016Y1024766D02*
Y1027741D01*
X456091Y1029816D01*
G01X456860Y1012325D02*
X459360D01*
G01X451904Y1023811D02*
Y1027387D01*
X450875Y1028416D01*
G01X456860Y1016325D02*
X457360Y1015825D01*
X459860D01*
G01X450875Y1028416D02*
X449025Y1030266D01*
X448666D01*
G01D02*
Y1034266D01*
G01X456091Y1035716D02*
X459700D01*
G01X446583Y1102555D02*
X442796D01*
G01X457188Y1101917D02*
X460041D01*
G01X466074Y113684D02*
Y112120D01*
X464738Y110784D01*
G01X470758Y468551D02*
X472322D01*
X473658Y467215D01*
G01X464199Y510184D02*
X463738Y509723D01*
X463328D01*
X462828Y509223D01*
Y507669D01*
G01X468946Y543282D02*
X468836Y543172D01*
G01X459360Y1004680D02*
Y1007180D01*
G01X459700Y1032266D02*
Y1029232D01*
X461091Y1027841D01*
G01X463413Y1110321D02*
X463169D01*
X461654Y1111836D01*
G01X463413Y1113471D02*
X463604Y1113662D01*
Y1115896D01*
G01Y1118396D02*
Y1120630D01*
X463413Y1120821D01*
G01X462239Y1247517D02*
Y1245032D01*
X463216Y1244055D01*
G01X489138Y213243D02*
X491311D01*
X491607Y213539D01*
G01X483233Y225055D02*
Y227215D01*
X481646Y231047D01*
X481178Y231515D01*
Y232971D01*
G01X495409Y538456D02*
X491821D01*
X490091Y536726D01*
X488635D01*
G01X482836Y534249D02*
X487302D01*
X488303Y535250D01*
Y536394D01*
X488635Y536726D01*
G01X483278Y613736D02*
Y595050D01*
X484639Y593689D01*
X502062D01*
G01X490353Y629311D02*
X492063D01*
X493661Y627713D01*
G01X491210Y1032180D02*
X485860D01*
X485360Y1031680D01*
G01X485678Y1039880D02*
X487878Y1037680D01*
X489835D01*
G01X485633Y1036155D02*
X484325D01*
X482210Y1034040D01*
Y1031680D01*
G01X480042Y1102555D02*
X476255D01*
G01X497424Y354559D02*
Y355101D01*
X498978Y356655D01*
X501821D01*
G01X498466Y483982D02*
X498755D01*
X500824Y486051D01*
Y488599D01*
X503722Y491497D01*
X504240Y491712D01*
X505240D01*
G01X507221Y544361D02*
Y546534D01*
X506925Y546830D01*
G01X502062Y593689D02*
X502143Y593770D01*
G01X502341Y624823D02*
Y627033D01*
X496669Y632705D01*
Y640441D01*
G01X493661Y627713D02*
X496532D01*
X498404Y625841D01*
Y624823D01*
G01X503278Y636236D02*
Y634723D01*
X504265Y633736D01*
G01D02*
Y631212D01*
G01X499278Y636236D02*
Y633736D01*
X499258Y633716D01*
G01D02*
X499278Y633696D01*
Y632620D01*
X503918Y627980D01*
X504310Y627034D01*
Y624823D01*
G01X500372D02*
Y626662D01*
X493778Y633256D01*
Y633724D01*
G01D02*
Y636236D01*
G01X507415Y631212D02*
Y629792D01*
X506278Y628655D01*
Y628078D01*
G01D02*
Y624823D01*
G01X494360Y1032180D02*
Y1034255D01*
X495735Y1035630D01*
Y1037680D01*
G01D02*
X501422D01*
G01X491210Y1027453D02*
Y1032180D01*
G01X490647Y1101917D02*
X493500D01*
G01X496872Y1110321D02*
X496628D01*
X495113Y1111836D01*
G01X496872Y1113471D02*
X497063Y1113662D01*
Y1115896D01*
G01Y1118396D02*
Y1120630D01*
X496872Y1120821D01*
G01X516272Y448557D02*
Y447538D01*
X514608Y445874D01*
G01X521494Y578907D02*
X523148D01*
X526577Y582336D01*
X527632D01*
G01X512184Y624823D02*
Y627308D01*
X512404Y627528D01*
Y629362D01*
G01X510215Y624823D02*
Y627948D01*
G01X507415Y631212D02*
Y636099D01*
X507278Y636236D01*
G01X522775Y1101917D02*
X523305D01*
X525105Y1103717D01*
G01X512170Y1102555D02*
X508383D01*
G01X544079Y177338D02*
Y175335D01*
X540934Y172190D01*
X538170D01*
G01X534798Y172998D02*
X534746Y172946D01*
Y168697D01*
G01X538170Y172190D02*
X537362Y172998D01*
X534798D01*
G01Y176148D02*
X536121D01*
X537589Y177616D01*
G01X530798Y176148D02*
X534798D01*
G01X537589Y177616D02*
X539870Y179897D01*
X541520D01*
G01Y183834D02*
X539444D01*
X538659Y184619D01*
G01X534941Y191941D02*
X532159D01*
G01X532026Y188727D02*
X533348Y187405D01*
X535025D01*
G01X538091Y191941D02*
X541931D01*
G01X541520Y185803D02*
X540447D01*
X538091Y188159D01*
Y191941D01*
G01X537287Y571614D02*
Y575614D01*
G01X529601Y582336D02*
Y580260D01*
X528816Y579475D01*
G01X533538Y582336D02*
Y580686D01*
X535819Y578405D01*
G01D02*
X537287Y576937D01*
Y575614D01*
G01X536097Y584895D02*
X537964D01*
X541245Y581614D01*
Y578986D01*
G01X529000Y1110321D02*
X528756D01*
X527241Y1111836D01*
G01X529000Y1113471D02*
X529191Y1113662D01*
Y1115896D01*
G01Y1118396D02*
Y1120630D01*
X529000Y1120821D01*
G01X540343Y209229D02*
Y207056D01*
X540639Y206760D01*
G01X552155Y215134D02*
X555743D01*
X557473Y216864D01*
X558929D01*
G01X544738Y575562D02*
X540489D01*
X540437Y575614D01*
G01X541245Y578986D02*
X540437Y578178D01*
Y575614D01*
G01X568436Y113684D02*
Y112120D01*
X567100Y110784D01*
G01X561984Y180665D02*
X564627D01*
G01X561984Y172665D02*
X564627D01*
G01X561984Y176665D02*
X564627D01*
G01X561984Y168665D02*
X564627D01*
G01X558834Y188665D02*
X557521D01*
X556726Y187870D01*
Y186629D01*
G01X562079Y212864D02*
X564659D01*
G01X562079Y200864D02*
X564659D01*
G01X562079Y204864D02*
X564659D01*
G01X562079Y221864D02*
X564659D01*
G01X562079Y216864D02*
X564659D01*
G01X560300Y219379D02*
X560177D01*
X558929Y218131D01*
Y216864D01*
G01X585595Y225055D02*
Y227215D01*
X584008Y231047D01*
X583540Y231515D01*
Y232971D01*
G01X591500Y213243D02*
X593673D01*
X593969Y213539D01*
G01X613386Y1138779D02*
X611516Y1140649D01*
G01X617126Y1138779D02*
X615256Y1140649D01*
G01X620866Y1138779D02*
X618996Y1140649D01*
G01X633160Y176148D02*
X637160D01*
G01X637303Y191941D02*
X634521D01*
G01X634388Y188727D02*
X635710Y187405D01*
X637387D01*
G01X624606Y1138779D02*
X622736Y1140649D01*
G01X624606Y1179921D02*
Y1179920D01*
X622736Y1178050D01*
G01X637160Y176148D02*
X638483D01*
X639951Y177616D01*
G01D02*
X642232Y179897D01*
X643882D01*
G01X646441Y177338D02*
Y175335D01*
X643296Y172190D01*
X640532D01*
G01X637160Y172998D02*
X637108Y172946D01*
Y168697D01*
G01X640532Y172190D02*
X639724Y172998D01*
X637160D01*
G01X643882Y183834D02*
X641806D01*
X641021Y184619D01*
G01X640453Y191941D02*
X644293D01*
G01X643882Y185803D02*
X642807D01*
X640453Y188157D01*
Y191941D01*
G01X642705Y209229D02*
Y207056D01*
X643001Y206760D01*
G01X643307Y1138779D02*
X641437Y1136909D01*
G01X643307Y1149999D02*
Y1150000D01*
X645177Y1151870D01*
G01X647047Y1157480D02*
X645177Y1155610D01*
G01X643307Y1157480D02*
X645177Y1159350D01*
G01X670798Y113684D02*
Y112120D01*
X669462Y110784D01*
G01X664346Y172665D02*
X666989D01*
G01X664346Y180665D02*
X666989D01*
G01X664346Y176665D02*
X666989D01*
G01X664346Y168665D02*
X666989D01*
G01X661196Y188665D02*
X659883D01*
X659088Y187870D01*
Y186629D01*
G01X664441Y200864D02*
X667021D01*
G01X664441Y212864D02*
X667021D01*
G01X664441Y204864D02*
X667021D01*
G01X664441Y221864D02*
X667021D01*
G01X664441Y216864D02*
X667021D01*
G01X662662Y219379D02*
X662539D01*
X661291Y218131D01*
Y216864D01*
G01X654517Y215134D02*
X658105D01*
X659835Y216864D01*
X661291D01*
G01X673228Y1112598D02*
X671358Y1114468D01*
G01X693862Y213243D02*
X696035D01*
X696331Y213539D01*
G01X687957Y225055D02*
Y227215D01*
X686370Y231047D01*
X685902Y231515D01*
Y232971D01*
G01X695669Y1123818D02*
X693799Y1121948D01*
G01D02*
X691929Y1120078D01*
G01X739522Y172998D02*
X742086D01*
X742894Y172190D01*
G01X739522Y172998D02*
X739470Y172946D01*
Y168697D01*
G01X742894Y172190D02*
X745658D01*
X748803Y175335D01*
Y177338D01*
G01X739522Y176148D02*
X740845D01*
X742313Y177616D01*
G01X735522Y176148D02*
X739522D01*
G01X742313Y177616D02*
X744594Y179897D01*
X746244D01*
G01Y183834D02*
X744168D01*
X743383Y184619D01*
G01X739665Y191941D02*
X736883D01*
G01X736750Y188727D02*
X738072Y187405D01*
X739749D01*
G01X746244Y185803D02*
X745169D01*
X742815Y188157D01*
Y191941D01*
G01D02*
X746655D01*
G01X745067Y209229D02*
Y207056D01*
X745363Y206760D01*
G01X744291Y1183661D02*
X746161Y1181791D01*
G01X744291Y1179921D02*
X742421Y1178051D01*
G01X766708Y172665D02*
X769351D01*
G01X766708Y180665D02*
X769351D01*
G01X766708Y176665D02*
X769351D01*
G01X766708Y168665D02*
X769351D01*
G01X763558Y188665D02*
X762245D01*
X761450Y187870D01*
Y186629D01*
G01X765024Y219379D02*
X764901D01*
X763653Y218131D01*
Y216864D01*
G01X756879Y215134D02*
X760467D01*
X762197Y216864D01*
X763653D01*
G01X764399Y316731D02*
X767099D01*
G01X755512Y1112598D02*
X751772D01*
G01X773160Y113684D02*
Y112120D01*
X771824Y110784D01*
G01X766803Y200864D02*
X769383D01*
G01X766803Y212864D02*
X769383D01*
G01X766803Y204864D02*
X769383D01*
G01X766803Y221864D02*
X769383D01*
G01X766803Y216864D02*
X769383D01*
G01X777114Y1442270D02*
X779011D01*
X780186Y1443445D01*
G01X778428Y1455156D02*
Y1458066D01*
G01X774785Y1454305D02*
X777577D01*
X778428Y1455156D01*
G01X786591Y1452803D02*
X786522Y1452734D01*
X783224D01*
X783215Y1452725D01*
G01X796224Y213243D02*
X798397D01*
X798693Y213539D01*
G01X790319Y225055D02*
Y227215D01*
X788732Y231047D01*
X788264Y231515D01*
Y232971D01*
G01X794071Y1451701D02*
X793288Y1450918D01*
G01X793882Y1453473D02*
X792680Y1452975D01*
X786763D01*
X786591Y1452803D01*
G01X819134Y863607D02*
X816904D01*
X814069Y860772D01*
Y859199D01*
G01X807054Y1404769D02*
X804654D01*
G01X821750Y448076D02*
X823314D01*
X824650Y446740D01*
G01X826264Y467606D02*
X823946D01*
X823529Y467189D01*
G01X841884Y176148D02*
X843207D01*
X844675Y177616D01*
G01X837884Y176148D02*
X841884D01*
G01X844675Y177616D02*
X846956Y179897D01*
X848606D01*
G01X851165Y177338D02*
Y175335D01*
X848020Y172190D01*
X845256D01*
G01X841884Y172998D02*
X841832Y172946D01*
Y168697D01*
G01X845256Y172190D02*
X844448Y172998D01*
X841884D01*
G01X839112Y188727D02*
X840434Y187405D01*
X842111D01*
G01X842027Y191941D02*
X839245D01*
G01X848606Y183834D02*
X846530D01*
X845745Y184619D01*
G01X845177Y191941D02*
Y188157D01*
X847531Y185803D01*
X848606D01*
G01X849017Y191941D02*
X845177D01*
G01X847429Y209229D02*
Y207056D01*
X847725Y206760D01*
G01X850399Y418760D02*
X839629D01*
X839129Y419260D01*
Y429363D01*
G01X850399Y414760D02*
X846150D01*
X846098Y414812D01*
G01X838076Y473511D02*
X839496D01*
X841623Y475638D01*
G01X832284Y735051D02*
Y731216D01*
G01X846065Y827686D02*
Y826708D01*
X847152Y825621D01*
X849396D01*
X851297Y823720D01*
X851782D01*
G01X832726Y843629D02*
X832071Y844284D01*
Y848651D01*
G01X842169Y1444959D02*
X839744D01*
G01X842156Y1440859D02*
X839744D01*
G01X842169Y1448959D02*
X839744D01*
G01X842169Y1457959D02*
X839744D01*
G01X846044Y1451459D02*
X846319Y1451184D01*
X849544D01*
G01X865920Y188665D02*
X864607D01*
X863812Y187870D01*
Y186629D01*
G01X859241Y215134D02*
X862829D01*
X864559Y216864D01*
X866015D01*
G01X861235Y408038D02*
Y410114D01*
X862020Y410899D01*
G01X869342Y411467D02*
X865804D01*
X863204Y408867D01*
Y408038D01*
G01X848284Y735051D02*
Y731181D01*
G01X975402Y948782D02*
Y929255D01*
G01X849544Y1454334D02*
X850305Y1453573D01*
X855862D01*
G01X849544Y1451184D02*
X849965Y1451605D01*
X855862D01*
G01X871713Y172665D02*
X869070D01*
G01X871713Y180665D02*
X869070D01*
G01X871713Y168665D02*
X869070D01*
G01X871713Y176665D02*
X869070D01*
G01X871745Y200864D02*
X869165D01*
G01X871745Y212864D02*
X869165D01*
G01X871745Y216864D02*
X869165D01*
G01X871745Y221864D02*
X869165D01*
G01X866015Y216864D02*
Y218131D01*
X867263Y219379D01*
X867386D01*
G01X874787Y408885D02*
X872614D01*
X872318Y408589D01*
G01X899185Y358369D02*
X896592D01*
G01X899185Y354369D02*
X896592D01*
G01X899185Y362369D02*
X896592D01*
G01X899185Y366369D02*
X896592D01*
G01X899185Y370369D02*
X896592D01*
G01X899185Y374369D02*
X896592D01*
G01X880692Y397073D02*
Y395625D01*
X882842Y393475D01*
X886131Y392113D01*
G01X893458Y460577D02*
X893377Y460658D01*
G01D02*
Y478081D01*
X894738Y479442D01*
X913424D01*
G01X893885Y1094653D02*
X892876D01*
X891055Y1095407D01*
G01X893885Y1096622D02*
X892810D01*
X890456Y1098976D01*
Y1102760D01*
G01X897427Y1208983D02*
X896149D01*
X894713Y1210419D01*
G01X893279Y1216412D02*
X893965D01*
X895462Y1215792D01*
X896746D01*
G01X891880Y1217987D02*
X891905Y1218012D01*
X893088D01*
X895334Y1218942D01*
X896746D01*
G01X895307Y1213666D02*
X897310Y1211663D01*
X901243D01*
G01X883669Y1440859D02*
X881244D01*
G01X883669Y1464859D02*
X881244D01*
G01X883644Y1452663D02*
X883448Y1452859D01*
X881444D01*
X881244Y1453059D01*
G01X897862Y1453573D02*
X893952D01*
X892382Y1455143D01*
X891935D01*
X891844Y1455234D01*
G01X886819Y1460859D02*
X889244D01*
G01X897862Y1451605D02*
X893555D01*
X892984Y1452176D01*
X891936D01*
X891844Y1452084D01*
G01X889336Y1452554D02*
X889725Y1452165D01*
X891763D01*
X891844Y1452084D01*
G01X886819Y1472859D02*
X889244D01*
G01X911845Y357348D02*
X910284D01*
X909644Y356708D01*
X908521D01*
G01X911845Y359317D02*
X908625D01*
G01X911072Y384482D02*
Y386992D01*
G01X911841Y1028101D02*
Y1022941D01*
X911893Y1022889D01*
G01D02*
Y1022821D01*
X909296Y1020224D01*
G01X912220Y1210568D02*
X914637D01*
G01X905070Y1211399D02*
X903900D01*
X903507Y1211792D01*
X903322Y1212239D01*
Y1212982D01*
X901491Y1214813D01*
X901243D01*
G01X896746Y1215792D02*
X897268D01*
X898878Y1214182D01*
G01D02*
X899872Y1215176D01*
X900880D01*
X901243Y1214813D01*
G01X905070Y1211399D02*
X906302D01*
X906846Y1211943D01*
X907965D01*
X909040Y1210868D01*
X909070Y1210568D01*
G01X901900Y1218723D02*
X900607D01*
X899861Y1219469D01*
X899286D01*
G01X901900Y1222723D02*
Y1218723D01*
G01X899286Y1219469D02*
X898595D01*
X898068Y1218942D01*
X896746D01*
G01X912220Y1214838D02*
X914637D01*
G01X905070Y1214549D02*
Y1214893D01*
X906784Y1216607D01*
G01X905050Y1218723D02*
Y1222723D01*
G01X906784Y1216607D02*
X905050Y1218341D01*
Y1218723D01*
G01X909070Y1214838D02*
X907747Y1213545D01*
X906070D01*
X905070Y1214545D01*
Y1214549D01*
G01X901243Y1211663D02*
X901392Y1211514D01*
Y1207823D01*
G01X923160Y113684D02*
Y112120D01*
X921824Y110784D01*
G01X923311Y353756D02*
Y349959D01*
G01X927072Y384482D02*
Y386992D01*
G01X919072Y384482D02*
Y386992D01*
G01X923072Y384482D02*
Y386992D01*
G01X915072Y384482D02*
Y386992D01*
G01X924511Y452505D02*
X927636D01*
G01X924511Y450536D02*
X926996D01*
X927216Y450316D01*
X929050D01*
G01X930900Y455305D02*
X929550D01*
X928413Y456442D01*
X927766D01*
G01D02*
X924511D01*
G01Y460379D02*
X926721D01*
X932393Y466051D01*
X940129D01*
G01X924511Y464316D02*
X925529D01*
X927401Y466188D01*
Y469059D01*
G01D02*
X928999Y470657D01*
Y472367D01*
G01X924511Y458410D02*
X926722D01*
X927668Y458802D01*
X932308Y463442D01*
X933384D01*
X933404Y463462D01*
G01X924511Y462348D02*
X926350D01*
X932944Y468942D01*
X933412D01*
G01X923888Y850016D02*
X925463Y848441D01*
X926066D01*
G01X928123D02*
X929079Y849397D01*
X933601D01*
X933604Y849400D01*
X938496D01*
X938984Y849888D01*
G01X939042Y854928D02*
X935800Y851686D01*
X933935D01*
X933246Y850997D01*
X928019D01*
X927038Y850016D01*
G01X919304Y1080832D02*
X916922D01*
X916749Y1080659D01*
G01X919276Y1088717D02*
X916807D01*
X916749Y1088659D01*
G01X925697Y1457401D02*
Y1460109D01*
G01X924803Y1472100D02*
Y1474743D01*
G01X940985Y210226D02*
Y212386D01*
X939398Y216218D01*
X938930Y216686D01*
Y218142D01*
G01X934464Y358618D02*
X932775Y359317D01*
X930841D01*
G01X931072Y384482D02*
Y386992D01*
G01X930900Y455305D02*
X935787D01*
X935924Y455442D01*
G01X930900Y458455D02*
X933424D01*
G01D02*
X934411Y459442D01*
X935924D01*
G01X933404Y463462D02*
X933424Y463442D01*
X935924D01*
G01X933412Y468942D02*
X935924D01*
G01X944351Y534211D02*
X945221Y535081D01*
Y536225D01*
X945722Y536726D01*
G01X940365Y613736D02*
Y595050D01*
X941726Y593689D01*
X959149D01*
G01X947541Y857440D02*
X947116Y857865D01*
X943716D01*
G01D02*
Y854788D01*
X939810Y850882D01*
Y850714D01*
X938984Y849888D01*
G01X947541Y861440D02*
X947116Y861015D01*
X943716D01*
G01D02*
X942956D01*
X941661Y859720D01*
Y857547D01*
X939042Y854928D01*
G01X944235Y1406262D02*
X945485Y1405012D01*
Y1402856D01*
X947885Y1400456D01*
X953761D01*
X955004Y1399213D01*
X958968D01*
G01X937671Y1488139D02*
X938921Y1489389D01*
X941240D01*
X942586Y1488043D01*
Y1477022D01*
G01Y1498282D02*
Y1492185D01*
X941290Y1490889D01*
X938921D01*
X937671Y1492139D01*
G01X946890Y198414D02*
X949063D01*
X949359Y198710D01*
G01X962327Y491712D02*
X961338D01*
X960250Y491261D01*
X957589Y488600D01*
Y486585D01*
X955553Y484549D01*
Y483982D01*
G01X952496Y538456D02*
X948908D01*
X947178Y536726D01*
X945722D01*
G01X959149Y593689D02*
X959230Y593770D01*
G01X959428Y624823D02*
Y627033D01*
X953756Y632705D01*
Y640441D01*
G01X960365Y636236D02*
Y634723D01*
X961352Y633736D01*
G01D02*
Y631212D01*
G01X957459Y624823D02*
Y626662D01*
X950865Y633256D01*
Y633724D01*
G01D02*
Y636236D01*
G01X955491Y624823D02*
Y625841D01*
X953619Y627713D01*
X950748D01*
G01D02*
X949150Y629311D01*
X947440D01*
G01X961397Y624823D02*
Y627034D01*
X961005Y627980D01*
X956365Y632620D01*
Y633696D01*
X956345Y633716D01*
G01D02*
X956365Y633736D01*
Y636236D01*
G01X957862Y1094653D02*
X956853D01*
X955032Y1095407D01*
G01X957862Y1096622D02*
X956787D01*
X954433Y1098976D01*
Y1102760D01*
G01X958690Y1210419D02*
X960126Y1208983D01*
X961404D01*
G01X960723Y1218942D02*
X962045D01*
X962572Y1219469D01*
X963263D01*
G01X955857Y1217987D02*
X955882Y1218012D01*
X957065D01*
X959311Y1218942D01*
X960723D01*
G01X959284Y1213666D02*
X961287Y1211663D01*
X965220D01*
G01X957256Y1216412D02*
X957942D01*
X959439Y1215792D01*
X960723D01*
G01D02*
X961245D01*
X962855Y1214182D01*
G01X958968Y1383465D02*
X952561D01*
G01X958968Y1379528D02*
X952417D01*
G01X958968Y1375591D02*
X952385D01*
G01X958968Y1391339D02*
X952514D01*
G01X958968Y1395276D02*
X952395D01*
G01X958968Y1387402D02*
X952716D01*
G01X958968Y1403150D02*
X954737D01*
X953538Y1401956D01*
X948507D01*
X946985Y1403478D01*
Y1405012D01*
X948235Y1406262D01*
G01X975359Y451557D02*
Y450538D01*
X973695Y448874D01*
G01X974139Y497617D02*
Y499790D01*
X973843Y500086D01*
G01X964308Y544361D02*
Y546534D01*
X964012Y546830D01*
G01X967302Y624823D02*
Y627948D01*
G01X969271Y624823D02*
Y627308D01*
X969491Y627528D01*
Y629362D01*
G01X963365Y624823D02*
Y628078D01*
G01X964502Y631212D02*
Y636099D01*
X964365Y636236D01*
G01X963365Y628078D02*
Y628639D01*
X964502Y629776D01*
Y631212D01*
G01X976197Y1210568D02*
X978614D01*
G01X965877Y1222723D02*
Y1218723D01*
G01X963263Y1219469D02*
X963838D01*
X964584Y1218723D01*
X965877D01*
G01X965220Y1211663D02*
X965369Y1211514D01*
Y1207823D01*
G01X969047Y1211399D02*
X967877D01*
X967484Y1211792D01*
X967299Y1212239D01*
Y1212982D01*
X965468Y1214813D01*
X965220D01*
G01X962855Y1214182D02*
X963849Y1215176D01*
X964857D01*
X965220Y1214813D01*
G01X969047Y1211399D02*
X970279D01*
X970823Y1211943D01*
X971942D01*
X973017Y1210868D01*
X973047Y1210568D01*
G01X969047Y1214549D02*
Y1214893D01*
X970761Y1216607D01*
G01X969027Y1218723D02*
Y1222723D01*
G01X970761Y1216607D02*
X969027Y1218341D01*
Y1218723D01*
G01X973047Y1214838D02*
X971724Y1213545D01*
X970047D01*
X969047Y1214545D01*
Y1214549D01*
G01X976197Y1214838D02*
X978614D01*
G01X991884Y172998D02*
X991832Y172946D01*
Y168697D01*
G01X991884Y172998D02*
X994448D01*
X995256Y172190D01*
G01X991884Y176148D02*
X993207D01*
X994675Y177616D01*
G01X987884Y176148D02*
X991884D01*
G01X992027Y191941D02*
X989245D01*
G01X989112Y188727D02*
X990434Y187405D01*
X992111D01*
G01X986688Y582336D02*
Y580260D01*
X985903Y579475D01*
G01X978581Y578907D02*
X980235D01*
X983664Y582336D01*
X984719D01*
G01X990625D02*
Y580686D01*
X992906Y578405D01*
G01D02*
X994374Y576937D01*
Y575614D01*
G01X993184Y584895D02*
X995051D01*
X998332Y581614D01*
Y578986D01*
G01X980085Y1492797D02*
Y1490832D01*
X979085Y1489832D01*
X978987D01*
G01X980085Y1486681D02*
Y1487481D01*
X982241Y1489637D01*
G01X995256Y172190D02*
X998020D01*
X1001165Y175335D01*
Y177338D01*
G01X994675Y177616D02*
X996956Y179897D01*
X998606D01*
G01Y183834D02*
X996530D01*
X995745Y184619D01*
G01X995177Y191941D02*
X999017D01*
G01X998606Y185803D02*
X997531D01*
X995177Y188157D01*
Y191941D01*
G01X997429Y209229D02*
Y207056D01*
X997725Y206760D01*
G01X1009241Y215134D02*
X1012829D01*
X1014559Y216864D01*
X1016015D01*
G01X994374Y571614D02*
Y575614D01*
G01X1001825Y575562D02*
X997576D01*
X997524Y575614D01*
G01X998332Y578986D02*
X997524Y578178D01*
Y575614D01*
G01X1025522Y113684D02*
Y112120D01*
X1024186Y110784D01*
G01X1019070Y180665D02*
X1021713D01*
G01X1019070Y172665D02*
X1021713D01*
G01X1019070Y176665D02*
X1021713D01*
G01X1019070Y168665D02*
X1021713D01*
G01X1015920Y188665D02*
X1014607D01*
X1013812Y187870D01*
Y186629D01*
G01X1019165Y212864D02*
X1021745D01*
G01X1019165Y200864D02*
X1021745D01*
G01X1019165Y204864D02*
X1021745D01*
G01X1019165Y221864D02*
X1021745D01*
G01X1019165Y216864D02*
X1021745D01*
G01X1017386Y219379D02*
X1017263D01*
X1016015Y218131D01*
Y216864D01*
G01X1020286Y1035102D02*
X1020298Y1035114D01*
X1022594D01*
G01X1020023Y1489637D02*
X1017867Y1487481D01*
Y1486681D01*
G01X1016769Y1489832D02*
X1017867Y1490930D01*
Y1492797D01*
G01X1042681Y225055D02*
Y227215D01*
X1041094Y231047D01*
X1040626Y231515D01*
Y232971D01*
G01X1048586Y213243D02*
X1050759D01*
X1051055Y213539D01*
G01X1074212Y1138779D02*
X1076082Y1140649D01*
G01X1070472Y1138779D02*
X1072342Y1140649D01*
G01X1066260Y1445541D02*
X1069642D01*
G01X1068861Y1451311D02*
X1063686Y1456486D01*
X1061410D01*
G01X1090246Y176148D02*
X1094246D01*
G01X1094389Y191941D02*
X1091607D01*
G01X1091474Y188727D02*
X1092796Y187405D01*
X1094473D01*
G01X1081692Y1138779D02*
X1083562Y1140649D01*
G01X1077952Y1138779D02*
X1079822Y1140649D01*
G01X1089172Y1183661D02*
X1087302Y1181791D01*
G01X1091043Y1185531D02*
X1091042D01*
X1089172Y1183661D01*
G01X1091529Y1528718D02*
Y1528491D01*
X1094220Y1525800D01*
Y1521648D01*
G01X1094246Y172998D02*
X1096810D01*
X1097618Y172190D01*
G01X1094194Y168697D02*
Y172946D01*
X1094246Y172998D01*
G01X1097618Y172190D02*
X1100382D01*
X1103527Y175335D01*
Y177338D01*
G01X1094246Y176148D02*
X1095569D01*
X1097037Y177616D01*
G01D02*
X1099318Y179897D01*
X1100968D01*
G01Y183834D02*
X1098892D01*
X1098107Y184619D01*
G01X1097539Y191941D02*
X1101379D01*
G01X1100968Y185803D02*
X1099893D01*
X1097539Y188157D01*
Y191941D01*
G01X1099791Y209229D02*
Y207056D01*
X1100087Y206760D01*
G01X1100393Y1138779D02*
X1098523Y1136909D01*
G01Y1148129D02*
X1096653Y1146259D01*
G01X1098523Y1155610D02*
X1096653Y1153740D01*
G01X1104133Y1157480D02*
X1102263Y1155610D01*
G01X1092913Y1183661D02*
X1094783Y1181791D01*
G01X1096780Y1521648D02*
Y1526700D01*
G01X1121432Y180665D02*
X1124075D01*
G01X1121432Y172665D02*
X1124075D01*
G01X1121432Y168665D02*
X1124075D01*
G01X1121432Y176665D02*
X1124075D01*
G01X1118282Y188665D02*
X1116969D01*
X1116174Y187870D01*
Y186629D01*
G01X1121527Y200864D02*
X1124107D01*
G01X1121527Y212864D02*
X1124107D01*
G01X1121527Y204864D02*
X1124107D01*
G01X1121527Y216864D02*
X1124107D01*
G01X1121527Y221864D02*
X1124107D01*
G01X1119748Y219379D02*
X1119625D01*
X1118377Y218131D01*
Y216864D01*
G01X1111603Y215134D02*
X1115191D01*
X1116921Y216864D01*
X1118377D01*
G01X1127884Y113684D02*
Y112120D01*
X1126548Y110784D01*
G01X1150948Y213243D02*
X1153121D01*
X1153417Y213539D01*
G01X1145043Y225055D02*
Y227215D01*
X1143456Y231047D01*
X1142988Y231515D01*
Y232971D01*
G01X1152755Y1123818D02*
X1150885Y1121948D01*
G01D02*
X1149015Y1120078D01*
G01X1205889Y177338D02*
X1203208D01*
X1202095Y176225D01*
Y174305D01*
X1199980Y172190D01*
G01X1196556Y168697D02*
Y172946D01*
X1196608Y172998D01*
G01X1199980Y172190D02*
X1199172Y172998D01*
X1196608D01*
G01Y176148D02*
X1197931D01*
X1199399Y177616D01*
G01X1192608Y176148D02*
X1196608D01*
G01X1199399Y177616D02*
X1201680Y179897D01*
X1203330D01*
G01Y183834D02*
X1201254D01*
X1200469Y184619D01*
G01X1196751Y191941D02*
X1193969D01*
G01X1193836Y188727D02*
X1195158Y187405D01*
X1196835D01*
G01X1199901Y191941D02*
X1203741D01*
G01X1203330Y185803D02*
X1202255D01*
X1199901Y188157D01*
Y191941D01*
G01X1202153Y209229D02*
Y207056D01*
X1202449Y206760D01*
G01X1205117Y1112598D02*
X1208857D01*
G01X1201377Y1179921D02*
X1199507Y1178051D01*
G01X1201377Y1183661D02*
X1203247Y1181791D01*
G01X1220644Y188665D02*
X1219331D01*
X1218536Y187870D01*
Y186629D01*
G01X1222110Y219379D02*
X1221987D01*
X1220739Y218131D01*
Y216864D01*
G01X1213965Y215134D02*
X1217553D01*
X1219283Y216864D01*
X1220739D01*
G01X1221486Y316731D02*
X1224186D01*
G01X1212598Y1112598D02*
X1208858D01*
G01X1208857D02*
X1208858D01*
G01X1230246Y113684D02*
Y112120D01*
X1228910Y110784D01*
G01X1223794Y180665D02*
X1226437D01*
G01X1223794Y172665D02*
X1226437D01*
G01X1223794Y176665D02*
X1226437D01*
G01X1223794Y168665D02*
X1226437D01*
G01X1223889Y200864D02*
X1226469D01*
G01X1223889Y212864D02*
X1226469D01*
G01X1223889Y204864D02*
X1226469D01*
G01X1223889Y216864D02*
X1226469D01*
G01X1223889Y221864D02*
X1226469D01*
G01X1235039Y1194881D02*
X1236909Y1193011D01*
G01X1253310Y213243D02*
X1255483D01*
X1255779Y213539D01*
G01X1247405Y225055D02*
Y227215D01*
X1245818Y231047D01*
X1245350Y231515D01*
Y232971D01*
G01X1238779Y1194881D02*
Y1194821D01*
X1240589Y1193011D01*
G01X1275407Y402867D02*
X1274653Y401046D01*
Y400037D01*
G01X1282760Y403466D02*
X1278976D01*
X1276622Y401112D01*
Y400037D01*
G01X1278837Y454076D02*
X1280401D01*
X1281737Y452740D01*
G01X1283351Y472606D02*
X1281033D01*
X1280616Y472189D01*
G01X1298970Y176148D02*
X1300293D01*
X1301761Y177616D01*
G01X1294970Y176148D02*
X1298970D01*
G01X1301761Y177616D02*
X1304042Y179897D01*
X1305692D01*
G01X1308251Y177338D02*
X1305570D01*
X1304457Y176225D01*
Y174305D01*
X1302342Y172190D01*
G01X1298918Y168697D02*
Y172946D01*
X1298970Y172998D01*
G01X1302342Y172190D02*
X1301534Y172998D01*
X1298970D01*
G01X1299113Y191941D02*
X1296331D01*
G01X1305692Y183834D02*
X1303616D01*
X1302831Y184619D01*
G01X1296198Y188727D02*
X1297520Y187405D01*
X1299197D01*
G01X1305692Y185803D02*
X1304617D01*
X1302263Y188157D01*
Y191941D01*
G01D02*
X1306103D01*
G01X1299539Y383732D02*
Y382312D01*
X1301666Y380185D01*
G01X1293634Y395544D02*
X1291461D01*
X1291165Y395248D01*
G01X1295163Y478511D02*
X1296583D01*
X1298710Y480638D01*
G01X1304515Y209229D02*
Y207056D01*
X1304811Y206760D01*
G01X1316327Y215134D02*
X1319915D01*
X1321645Y216864D01*
X1323101D01*
G01X1312224Y444317D02*
Y461740D01*
X1313585Y463101D01*
X1332271D01*
G01X1312305Y444236D02*
X1312224Y444317D01*
G01X1315330Y831445D02*
X1313756Y829871D01*
G01X1318480Y844044D02*
X1316906Y842470D01*
G01X1326156Y172665D02*
X1328799D01*
G01X1326156Y180665D02*
X1328799D01*
G01X1326156Y168665D02*
X1328799D01*
G01X1326156Y176665D02*
X1328799D01*
G01X1323006Y188665D02*
X1321693D01*
X1320898Y187870D01*
Y186629D01*
G01X1326251Y212864D02*
X1328831D01*
G01X1326251Y200864D02*
X1328831D01*
G01X1326251Y204864D02*
X1328831D01*
G01X1326251Y221864D02*
X1328831D01*
G01X1326251Y216864D02*
X1328831D01*
G01X1323101D02*
Y218131D01*
X1324349Y219379D01*
X1324472D01*
G01X1328629Y1102555D02*
X1324842D01*
G01X1343358Y434195D02*
X1345843D01*
X1346063Y433975D01*
X1347897D01*
G01X1343358Y436164D02*
X1346483D01*
G01X1343358Y440101D02*
X1346613D01*
G01X1354771Y439101D02*
X1354634Y438964D01*
X1349747D01*
G01X1346613Y440101D02*
X1347260D01*
X1348397Y438964D01*
X1349747D01*
G01X1358976Y449710D02*
X1351240D01*
X1345568Y444038D01*
X1343358D01*
G01Y442069D02*
X1345569D01*
X1346515Y442461D01*
X1351155Y447101D01*
X1352231D01*
X1352251Y447121D01*
G01X1343358Y447975D02*
X1344376D01*
X1346248Y449847D01*
Y452718D01*
G01D02*
X1347846Y454316D01*
Y456026D01*
G01X1349747Y442114D02*
X1352271D01*
G01X1343358Y446007D02*
X1345197D01*
X1351791Y452601D01*
X1352259D01*
G01X1340527Y856642D02*
X1338952Y855067D01*
G01X1342087Y1101917D02*
X1339234D01*
G01X1345459Y1110321D02*
X1345215D01*
X1343700Y1111836D01*
G01X1345459Y1113471D02*
X1345650Y1113662D01*
Y1115896D01*
G01Y1118396D02*
Y1120630D01*
X1345459Y1120821D01*
G01X1352251Y447121D02*
X1352271Y447101D01*
X1354771D01*
G01X1352271Y442114D02*
X1353258Y443101D01*
X1354771D01*
G01X1352259Y452601D02*
X1354771D01*
G01X1365049Y1028416D02*
X1366078Y1027387D01*
Y1023811D01*
G01X1362840Y1026266D02*
Y1022766D01*
G01D02*
X1364341D01*
X1365314Y1021793D01*
G01D02*
X1366341Y1020766D01*
X1366765D01*
G01X1362840Y1034266D02*
Y1030266D01*
G01D02*
X1363199D01*
X1365049Y1028416D01*
G01X1360757Y1102555D02*
X1356970D01*
G01X1380247Y113684D02*
Y112120D01*
X1378911Y110784D01*
G01X1373534Y1007180D02*
Y1004680D01*
G01X1371034Y1012325D02*
X1373534D01*
G01X1371034Y1016325D02*
X1371534Y1015825D01*
X1374034D01*
G01X1368190Y1024766D02*
Y1027741D01*
X1370265Y1029816D01*
G01X1371340Y1024766D02*
X1375190D01*
X1375265Y1024691D01*
G01X1373874Y1032266D02*
Y1029232D01*
X1375265Y1027841D01*
G01X1370265Y1035716D02*
X1373874D01*
G01X1371362Y1101917D02*
X1374215D01*
G01X1377587Y1110321D02*
X1377343D01*
X1375828Y1111836D01*
G01X1377587Y1113471D02*
X1377778Y1113662D01*
Y1115896D01*
G01Y1118396D02*
Y1120630D01*
X1377587Y1120821D01*
G01X1397406Y225055D02*
Y227215D01*
X1395819Y231047D01*
X1395351Y231515D01*
Y232971D01*
G01X1397452Y613736D02*
Y595050D01*
X1398813Y593689D01*
X1416236D01*
G01X1399534Y1031680D02*
X1400034Y1032180D01*
X1405384D01*
G01X1396384Y1031680D02*
Y1034282D01*
X1398257Y1036155D01*
X1399807D01*
G01X1399852Y1039779D02*
X1399953D01*
X1402052Y1037680D01*
X1404009D01*
G01X1394216Y1102555D02*
X1390429D01*
G01X1403311Y213243D02*
X1405484D01*
X1405780Y213539D01*
G01X1419414Y491712D02*
X1418190D01*
X1414676Y488198D01*
Y486585D01*
X1412640Y484549D01*
Y483982D01*
G01X1409583Y538456D02*
X1405995D01*
X1404265Y536726D01*
X1402809D01*
G01X1401438Y534211D02*
X1402410Y535183D01*
Y536327D01*
X1402809Y536726D01*
G01X1416236Y593689D02*
X1416317Y593770D01*
G01X1416515Y624823D02*
Y627033D01*
X1410843Y632705D01*
Y640441D01*
G01X1407952Y636236D02*
Y633724D01*
G01D02*
Y633256D01*
X1414546Y626662D01*
Y624823D01*
G01X1418484D02*
Y627034D01*
X1418092Y627980D01*
X1413452Y632620D01*
Y633696D01*
X1413432Y633716D01*
G01D02*
X1413452Y633736D01*
Y636236D01*
G01X1412578Y624823D02*
Y625841D01*
X1410706Y627713D01*
X1407835D01*
G01D02*
X1406237Y629311D01*
X1404527D01*
G01X1405384Y1032180D02*
Y1027452D01*
G01X1408534Y1032180D02*
Y1034255D01*
X1409909Y1035630D01*
Y1037680D01*
G01D02*
X1415596D01*
G01X1404821Y1101917D02*
X1407674D01*
G01X1411046Y1110321D02*
X1410802D01*
X1409287Y1111836D01*
G01X1411046Y1113471D02*
X1411237Y1113662D01*
Y1115896D01*
G01Y1118396D02*
Y1120630D01*
X1411046Y1120821D01*
G01X1430446Y448557D02*
Y447538D01*
X1428782Y445874D01*
G01X1421395Y544361D02*
Y546534D01*
X1421099Y546830D01*
G01X1427233Y628183D02*
X1426358Y627308D01*
Y624823D01*
G01X1424389D02*
Y627948D01*
G01X1420452Y624823D02*
Y628078D01*
G01X1421589Y631212D02*
Y636099D01*
X1421452Y636236D01*
G01X1420452Y628078D02*
Y630075D01*
X1421589Y631212D01*
G01X1417452Y636236D02*
Y634723D01*
X1418439Y633736D01*
G01D02*
Y631212D01*
G01X1426344Y1102555D02*
X1422557D01*
G01X1444971Y176148D02*
X1448971D01*
G01Y172998D02*
X1448919Y172946D01*
Y168697D01*
G01X1449114Y191941D02*
X1446332D01*
G01X1446199Y188727D02*
X1447521Y187405D01*
X1449198D01*
G01X1443775Y582336D02*
Y580260D01*
X1442990Y579475D01*
G01X1435668Y578907D02*
X1437322D01*
X1440751Y582336D01*
X1441806D01*
G01X1447712D02*
Y580686D01*
X1449993Y578405D01*
G01X1436949Y1101917D02*
X1437479D01*
X1439279Y1103717D01*
G01X1443174Y1110321D02*
X1442930D01*
X1441415Y1111836D01*
G01X1443174Y1113471D02*
X1443365Y1113662D01*
Y1115896D01*
G01Y1118396D02*
Y1120630D01*
X1443174Y1120821D01*
G01X1455693Y179897D02*
X1454043D01*
X1451762Y177616D01*
G01D02*
X1450294Y176148D01*
X1448971D01*
G01Y172998D02*
X1451535D01*
X1452343Y172190D01*
G01D02*
X1454458Y174305D01*
Y176225D01*
X1455571Y177338D01*
X1458252D01*
G01X1455693Y183834D02*
X1453617D01*
X1452832Y184619D01*
G01X1455693Y185803D02*
X1454618D01*
X1452264Y188157D01*
Y191941D01*
G01D02*
X1456104D01*
G01X1454516Y209229D02*
Y207056D01*
X1454812Y206760D01*
G01X1451461Y571614D02*
Y575614D01*
G01X1454611D02*
X1454663Y575562D01*
X1458912D01*
G01X1454611Y575614D02*
Y578178D01*
X1455419Y578986D01*
G01D02*
Y581614D01*
X1452138Y584895D01*
X1450271D01*
G01X1449993Y578405D02*
X1451461Y576937D01*
Y575614D01*
G01X1482609Y113684D02*
Y112120D01*
X1481273Y110784D01*
G01X1476157Y180665D02*
X1478800D01*
G01X1476157Y172665D02*
X1478800D01*
G01X1476157Y168665D02*
X1478800D01*
G01X1476157Y176665D02*
X1478800D01*
G01X1473007Y188665D02*
X1471694D01*
X1470899Y187870D01*
Y186629D01*
G01X1476252Y200864D02*
X1478832D01*
G01X1476252Y212864D02*
X1478832D01*
G01X1476252Y204864D02*
X1478832D01*
G01X1476252Y216864D02*
X1478832D01*
G01X1476252Y221864D02*
X1478832D01*
G01X1474473Y219379D02*
X1474350D01*
X1473102Y218131D01*
Y216864D01*
G01X1466328Y215134D02*
X1469916D01*
X1471646Y216864D01*
X1473102D01*
G01X1499768Y225055D02*
Y227215D01*
X1498181Y231047D01*
X1497713Y231515D01*
Y232971D01*
G01X1505673Y213243D02*
X1507846D01*
X1508142Y213539D01*
G01X1526611Y921442D02*
X1526990Y921063D01*
Y916678D01*
G01X1527559Y1138779D02*
X1529429Y1140649D01*
G01X1531299Y1138779D02*
X1533169Y1140649D01*
G01X1535039Y1138779D02*
X1536909Y1140649D01*
G01X1538779Y1138779D02*
X1540649Y1140649D01*
G01X1546259Y1183661D02*
X1546260D01*
X1548130Y1185531D01*
G01X1551333Y172998D02*
X1553897D01*
X1554705Y172190D01*
G01X1551333Y172998D02*
X1551281Y172946D01*
Y168697D01*
G01X1554705Y172190D02*
X1556820Y174305D01*
Y176225D01*
X1557933Y177338D01*
X1560614D01*
G01X1551333Y176148D02*
X1552656D01*
X1554124Y177616D01*
G01X1547333Y176148D02*
X1551333D01*
G01X1554124Y177616D02*
X1556405Y179897D01*
X1558055D01*
G01X1551476Y191941D02*
X1548694D01*
G01X1558055Y183834D02*
X1555979D01*
X1555194Y184619D01*
G01X1548561Y188727D02*
X1549883Y187405D01*
X1551560D01*
G01X1558055Y185803D02*
X1556980D01*
X1554626Y188157D01*
Y191941D01*
G01D02*
X1558466D01*
G01X1556878Y209229D02*
Y207056D01*
X1557174Y206760D01*
G01X1557480Y1138779D02*
X1555610Y1136909D01*
G01X1557480Y1149999D02*
Y1150000D01*
X1559350Y1151870D01*
G01X1561220Y1157480D02*
X1559350Y1155610D01*
G01X1557480Y1157480D02*
X1559350Y1159350D01*
G01X1551870Y1185531D02*
X1550000Y1183661D01*
G01X1551870Y1181791D02*
X1550000Y1183661D01*
G01X1578519Y172665D02*
X1581162D01*
G01X1578519Y168665D02*
X1581162D01*
G01X1578519Y176665D02*
X1581162D01*
G01X1575369Y188665D02*
X1574056D01*
X1573261Y187870D01*
Y186629D01*
G01X1578614Y212864D02*
X1581194D01*
G01X1578614Y200864D02*
X1581194D01*
G01X1578614Y204864D02*
X1581194D01*
G01X1578614Y221864D02*
X1581194D01*
G01X1578614Y216864D02*
X1581194D01*
G01X1576835Y219379D02*
X1576712D01*
X1575464Y218131D01*
Y216864D01*
G01X1568690Y215134D02*
X1572278D01*
X1574008Y216864D01*
X1575464D01*
G01X1584971Y113684D02*
Y112120D01*
X1583635Y110784D01*
G01X1608035Y213243D02*
X1610208D01*
X1610504Y213539D01*
G01X1602130Y225055D02*
Y227215D01*
X1600543Y231047D01*
X1600075Y231515D01*
Y232971D01*
G01X1609842Y1123818D02*
X1607972Y1121948D01*
G01D02*
X1606102Y1120078D01*
G01X1619950Y675889D02*
Y678519D01*
G01X1653695Y176148D02*
X1655018D01*
X1656486Y177616D01*
G01X1649695Y176148D02*
X1653695D01*
G01X1656486Y177616D02*
X1658767Y179897D01*
X1660417D01*
G01X1653695Y172998D02*
X1656259D01*
X1657067Y172190D01*
G01X1653695Y172998D02*
X1653643Y172946D01*
Y168697D01*
G01X1657067Y172190D02*
X1659182Y174305D01*
Y176225D01*
X1660295Y177338D01*
X1662976D01*
G01X1653838Y191941D02*
X1651056D01*
G01X1660417Y183834D02*
X1658341D01*
X1657556Y184619D01*
G01X1650923Y188727D02*
X1652245Y187405D01*
X1653922D01*
G01X1660417Y185803D02*
X1659342D01*
X1656988Y188157D01*
Y191941D01*
G01D02*
X1660828D01*
G01X1659240Y209229D02*
Y207056D01*
X1659536Y206760D01*
G01X1658464Y1183661D02*
X1660334Y1181791D01*
G01X1658464Y1179921D02*
X1656594Y1178051D01*
G01X1677731Y188665D02*
X1676418D01*
X1675623Y187870D01*
Y186629D01*
G01X1671052Y215134D02*
X1674640D01*
X1676370Y216864D01*
X1677826D01*
G01X1662204Y1112598D02*
X1665944D01*
G01D02*
X1665945D01*
G01X1687333Y113684D02*
Y112120D01*
X1685997Y110784D01*
G01X1680881Y172665D02*
X1683524D01*
G01X1680881Y180665D02*
X1683524D01*
G01X1680881Y168665D02*
X1683524D01*
G01X1680881Y176665D02*
X1683524D01*
G01X1680976Y200864D02*
X1683556D01*
G01X1680976Y212864D02*
X1683556D01*
G01X1680976Y204864D02*
X1683556D01*
G01X1680976Y221864D02*
X1683556D01*
G01X1680976Y216864D02*
X1683556D01*
G01X1679197Y219379D02*
X1679074D01*
X1677826Y218131D01*
Y216864D01*
G01X1678573Y316731D02*
X1681273D01*
G01X1704492Y225055D02*
Y227215D01*
X1702905Y231047D01*
X1702437Y231515D01*
Y232971D01*
G01X1710397Y213243D02*
X1712570D01*
X1712866Y213539D01*
G01X1732494Y402867D02*
X1731740Y401046D01*
Y400037D01*
G01X1739847Y403466D02*
X1736063D01*
X1733709Y401112D01*
Y400037D01*
G01X1735924Y454076D02*
X1737488D01*
X1738824Y452740D01*
G01X1740438Y472606D02*
X1738120D01*
X1737703Y472189D01*
G01X1756057Y176148D02*
X1757380D01*
X1758848Y177616D01*
G01X1752057Y176148D02*
X1756057D01*
G01Y172998D02*
X1758621D01*
X1759429Y172190D01*
G01X1756057Y172998D02*
X1756005Y172946D01*
Y168697D01*
G01X1756200Y191941D02*
X1753418D01*
G01X1753285Y188727D02*
X1754607Y187405D01*
X1756284D01*
G01X1756626Y383732D02*
Y382312D01*
X1758753Y380185D01*
G01X1750721Y395544D02*
X1748548D01*
X1748252Y395248D01*
G01X1752250Y478511D02*
X1753670D01*
X1755797Y480638D01*
G01X1758848Y177616D02*
X1761129Y179897D01*
X1762779D01*
G01X1759429Y172190D02*
X1761544Y174305D01*
Y176225D01*
X1762657Y177338D01*
X1765338D01*
G01X1762779Y183834D02*
X1760703D01*
X1759918Y184619D01*
G01X1762779Y185803D02*
X1761704D01*
X1759350Y188157D01*
Y191941D01*
G01D02*
X1763190D01*
G01X1761602Y209229D02*
Y207056D01*
X1761898Y206760D01*
G01X1773414Y215134D02*
X1777002D01*
X1778732Y216864D01*
X1780188D01*
G01X1769392Y444236D02*
X1769311Y444317D01*
G01D02*
Y461740D01*
X1770672Y463101D01*
X1789358D01*
G01X1783243Y172665D02*
X1785886D01*
G01X1783243Y180665D02*
X1785886D01*
G01X1783243Y168665D02*
X1785886D01*
G01X1783243Y176665D02*
X1785886D01*
G01X1780093Y188665D02*
X1778780D01*
X1777985Y187870D01*
Y186629D01*
G01X1783338Y200864D02*
X1785918D01*
G01X1783338Y212864D02*
X1785918D01*
G01X1783338Y216864D02*
X1785918D01*
G01X1783338Y221864D02*
X1785918D01*
G01X1781559Y219379D02*
X1781436D01*
X1780188Y218131D01*
Y216864D01*
G01X1800445Y434195D02*
X1802930D01*
X1803150Y433975D01*
X1804984D01*
G01X1800445Y436164D02*
X1803570D01*
G01X1800445Y440101D02*
X1803700D01*
G01D02*
X1804347D01*
X1805484Y438964D01*
X1806834D01*
G01X1816063Y449710D02*
X1808327D01*
X1802655Y444038D01*
X1800445D01*
G01Y447975D02*
X1801463D01*
X1803335Y449847D01*
Y452718D01*
G01D02*
X1804933Y454316D01*
Y456026D01*
G01X1800445Y446007D02*
X1802284D01*
X1808878Y452601D01*
X1809346D01*
G01X1800445Y442069D02*
X1802656D01*
X1803602Y442461D01*
X1808242Y447101D01*
X1809318D01*
X1809338Y447121D01*
G01X1799012Y1095893D02*
X1800833Y1095139D01*
X1801842D01*
G01X1798413Y1103246D02*
Y1099462D01*
X1800767Y1097108D01*
X1801842D01*
G01X1801236Y1216898D02*
X1801922D01*
X1803419Y1216278D01*
X1804703D01*
G01D02*
X1805225D01*
X1806835Y1214668D01*
G01X1803264Y1214152D02*
X1805267Y1212149D01*
X1809200D01*
G01X1804703Y1219428D02*
X1806025D01*
X1806552Y1219955D01*
X1807243D01*
G01X1799837Y1218473D02*
X1799862Y1218498D01*
X1801045D01*
X1803291Y1219428D01*
X1804703D01*
G01X1805384Y1209469D02*
X1804106D01*
X1802670Y1210905D01*
G01X1806834Y438964D02*
X1811721D01*
X1811858Y439101D01*
G01X1809346Y452601D02*
X1811858D01*
G01X1809338Y447121D02*
X1809358Y447101D01*
X1811858D01*
G01X1806834Y442114D02*
X1809358D01*
G01D02*
X1810345Y443101D01*
X1811858D01*
G01X1820177Y1211054D02*
X1822594D01*
G01X1820177Y1215324D02*
X1822594D01*
G01X1813007Y1219209D02*
Y1223209D01*
G01X1813027Y1215035D02*
Y1215379D01*
X1814741Y1217093D01*
G01D02*
X1813007Y1218827D01*
Y1219209D01*
G01X1817027Y1215324D02*
X1815704Y1214031D01*
X1814027D01*
X1813027Y1215031D01*
Y1215035D01*
G01Y1211885D02*
X1811857D01*
X1811464Y1212278D01*
X1811279Y1212725D01*
Y1213468D01*
X1809448Y1215299D01*
X1809200D01*
G01X1806835Y1214668D02*
X1807829Y1215662D01*
X1808837D01*
X1809200Y1215299D01*
G01X1813027Y1211885D02*
X1814259D01*
X1814803Y1212429D01*
X1815922D01*
X1816997Y1211354D01*
X1817027Y1211054D01*
G01X1809200Y1212149D02*
X1809349Y1212000D01*
Y1208309D01*
G01X1809857Y1223209D02*
Y1219209D01*
G01X1807243Y1219955D02*
X1807818D01*
X1808564Y1219209D01*
X1809857D01*
G54D236*
X965740Y1360945D03*
G54D71*
X43350Y1077095D03*
X344530Y1220701D03*
X354057Y1217750D03*
X356886Y1220579D03*
X351229Y1214922D03*
X347359Y1223528D03*
X350188Y1226357D03*
X353017Y1229186D03*
X362543Y1226236D03*
X808316Y1214922D03*
X813973Y1220579D03*
X811144Y1217750D03*
X801617Y1220701D03*
X807275Y1226357D03*
X804446Y1223528D03*
X810104Y1229186D03*
X819630Y1226236D03*
X890040Y1086098D03*
X954017D03*
X1258703Y1220701D03*
X1268230Y1217750D03*
X1271059Y1220579D03*
X1265402Y1214922D03*
X1261532Y1223528D03*
X1264361Y1226357D03*
X1267190Y1229186D03*
X1276716Y1226236D03*
X1715790Y1220701D03*
X1725317Y1217750D03*
X1722489Y1214922D03*
X1718619Y1223528D03*
X1721448Y1226357D03*
X1724277Y1229186D03*
X1728146Y1220579D03*
X1733803Y1226236D03*
X1797997Y1086584D03*
G54D26*
X14781Y189835D03*
X30529D03*
X32086Y586113D03*
X47834D03*
X117143Y189835D03*
X132891D03*
X235253D03*
X219505D03*
X321867D03*
X337615D03*
X381983Y418952D03*
X397731D03*
X471868Y189835D03*
X487616D03*
X489172Y586113D03*
X504920D03*
X574230Y189835D03*
X589978D03*
X676592D03*
X692340D03*
X778954D03*
X794702D03*
X877309Y432293D03*
X893057D03*
X929620Y175006D03*
X945368D03*
X946259Y586113D03*
X962007D03*
X1047064Y189835D03*
X1031316D03*
X1133678D03*
X1149426D03*
X1236040D03*
X1251788D03*
X1296156Y418952D03*
X1311904D03*
X1386041Y189835D03*
X1401789D03*
X1403346Y586113D03*
X1419094D03*
X1488403Y189835D03*
X1504151D03*
X1590765D03*
X1606513D03*
X1693127D03*
X1708875D03*
X1753243Y418952D03*
X1768991D03*
G54D173*
G01X414455Y1105705D02*
Y1110194D01*
X414416Y1110233D01*
G01X419731D02*
Y1108532D01*
X420510Y1107753D01*
X420782Y1106780D01*
Y1105552D01*
G01X410668Y1105705D02*
X412644Y1107681D01*
Y1110233D01*
G01X423274D02*
Y1108875D01*
X424995Y1107154D01*
Y1106897D01*
G01X418495Y1106867D02*
X417959Y1107403D01*
Y1110233D01*
G01X427913Y1101917D02*
X428025Y1102029D01*
Y1104941D01*
X426684Y1108179D01*
X425046Y1109817D01*
Y1110233D01*
G01X431285Y1123971D02*
X430059D01*
X428922Y1122834D01*
Y1120596D01*
X428106Y1119780D01*
X426660D01*
G01X429526Y1111836D02*
X428816Y1113550D01*
X427901Y1114465D01*
X426660D01*
G01Y1116237D02*
X428376D01*
X431142Y1113471D01*
X431285D01*
G01X427810Y1110092D02*
Y1111391D01*
X427509Y1112117D01*
X426933Y1112693D01*
X426660D01*
G01Y1118008D02*
X428315D01*
X431128Y1120821D01*
X431285D01*
G01X446583Y1105705D02*
Y1110194D01*
X446544Y1110233D01*
G01X451859D02*
Y1108532D01*
X452638Y1107753D01*
X452910Y1106780D01*
Y1105552D01*
G01X442796Y1105705D02*
X444772Y1107681D01*
Y1110233D01*
G01X455402D02*
Y1108875D01*
X457123Y1107154D01*
Y1106897D01*
G01X450623Y1106867D02*
X450087Y1107403D01*
Y1110233D01*
G01X460041Y1101917D02*
X460153Y1102029D01*
Y1104941D01*
X458812Y1108179D01*
X457174Y1109817D01*
Y1110233D01*
G01X461654Y1111836D02*
X460944Y1113550D01*
X460029Y1114465D01*
X458788D01*
G01X460080Y1119780D02*
X458788D01*
G01X460080D02*
X461300Y1121000D01*
Y1123084D01*
X462187Y1123971D01*
X463413D01*
G01X459938Y1110092D02*
Y1111391D01*
X459637Y1112117D01*
X459061Y1112693D01*
X458788D01*
G01Y1116237D02*
X460504D01*
X463270Y1113471D01*
X463413D01*
G01X458788Y1118008D02*
X460408D01*
X463221Y1120821D01*
X463413D01*
G01X485318Y1110233D02*
Y1108532D01*
X486097Y1107753D01*
X486369Y1106780D01*
Y1105552D01*
G01X480042Y1105705D02*
Y1110194D01*
X480003Y1110233D01*
G01X476255Y1105705D02*
X478231Y1107681D01*
Y1110233D01*
G01X488861D02*
Y1108875D01*
X490582Y1107154D01*
Y1106897D01*
G01X484082Y1106867D02*
X483546Y1107403D01*
Y1110233D01*
G01X493500Y1101917D02*
X493612Y1102029D01*
Y1104941D01*
X492271Y1108179D01*
X490633Y1109817D01*
Y1110233D01*
G01X496872Y1123971D02*
X495646D01*
X494509Y1122834D01*
Y1120596D01*
X493693Y1119780D01*
X492247D01*
G01X495113Y1111836D02*
X494403Y1113550D01*
X493488Y1114465D01*
X492247D01*
G01Y1116237D02*
X493963D01*
X496729Y1113471D01*
X496872D01*
G01X493397Y1110092D02*
Y1111391D01*
X493096Y1112117D01*
X492520Y1112693D01*
X492247D01*
G01Y1118008D02*
X493902D01*
X496715Y1120821D01*
X496872D01*
G01X517446Y1110233D02*
Y1108532D01*
X518225Y1107753D01*
X518497Y1106780D01*
Y1105552D01*
G01X512170Y1105705D02*
Y1110194D01*
X512131Y1110233D01*
G01X508383Y1105705D02*
X510359Y1107681D01*
Y1110233D01*
G01X520989D02*
Y1108875D01*
X522710Y1107154D01*
Y1106897D01*
G01X516210Y1106867D02*
X515674Y1108070D01*
Y1110233D01*
G01X525105Y1103717D02*
Y1106475D01*
X524399Y1108179D01*
X522761Y1109817D01*
Y1110233D01*
G01X529000Y1123971D02*
X527774D01*
X526637Y1122834D01*
Y1120596D01*
X525821Y1119780D01*
X524375D01*
G01X527241Y1111836D02*
X526531Y1113550D01*
X525616Y1114465D01*
X524375D01*
G01Y1116237D02*
X526091D01*
X528857Y1113471D01*
X529000D01*
G01X525525Y1110092D02*
Y1111391D01*
X525224Y1112117D01*
X524648Y1112693D01*
X524375D01*
G01Y1118008D02*
X526030D01*
X528843Y1120821D01*
X529000D01*
G01X796269Y1436559D02*
Y1439498D01*
X799679Y1442908D01*
Y1443778D01*
G01X1324842Y1105705D02*
X1326818Y1107681D01*
Y1110233D01*
G01X1328629Y1105705D02*
Y1110194D01*
X1328590Y1110233D01*
G01X1333905D02*
Y1108532D01*
X1334684Y1107753D01*
X1334956Y1106780D01*
Y1105552D01*
G01X1332669Y1106867D02*
X1332133Y1108070D01*
Y1110233D01*
G01X1339220D02*
Y1109817D01*
X1340858Y1108179D01*
X1342199Y1104941D01*
Y1102029D01*
X1342087Y1101917D01*
G01X1337448Y1110233D02*
Y1108875D01*
X1339169Y1107154D01*
Y1106897D01*
G01X1345459Y1123971D02*
X1344233D01*
X1343096Y1122834D01*
Y1120596D01*
X1342280Y1119780D01*
X1340834D01*
G01X1343700Y1111836D02*
X1342990Y1113550D01*
X1342075Y1114465D01*
X1340834D01*
G01X1341984Y1110092D02*
Y1111391D01*
X1341683Y1112117D01*
X1341107Y1112693D01*
X1340834D01*
G01Y1116237D02*
X1342550D01*
X1345316Y1113471D01*
X1345459D01*
G01X1340834Y1118008D02*
X1342489D01*
X1345302Y1120821D01*
X1345459D01*
G01X1360757Y1105705D02*
Y1110194D01*
X1360718Y1110233D01*
G01X1356970Y1105705D02*
X1358946Y1107681D01*
Y1110233D01*
G01X1366033D02*
Y1108532D01*
X1366812Y1107753D01*
X1367084Y1106780D01*
Y1105552D01*
G01X1364797Y1106867D02*
X1364261Y1108070D01*
Y1110233D01*
G01X1374215Y1101917D02*
X1374327Y1102029D01*
Y1104941D01*
X1372986Y1108179D01*
X1371348Y1109817D01*
Y1110233D01*
G01X1369576D02*
Y1108875D01*
X1371297Y1107154D01*
Y1106897D01*
G01X1377587Y1123971D02*
X1376361D01*
X1375224Y1122834D01*
Y1120596D01*
X1374408Y1119780D01*
X1372962D01*
G01X1375828Y1111836D02*
X1375118Y1113550D01*
X1374203Y1114465D01*
X1372962D01*
G01X1374112Y1110092D02*
Y1111391D01*
X1373811Y1112117D01*
X1373235Y1112693D01*
X1372962D01*
G01Y1116237D02*
X1374678D01*
X1377444Y1113471D01*
X1377587D01*
G01X1372962Y1118008D02*
X1374631D01*
X1377444Y1120821D01*
X1377587D01*
G01X1394216Y1105705D02*
Y1110194D01*
X1394177Y1110233D01*
G01X1390429Y1105705D02*
X1392405Y1107681D01*
Y1110233D01*
G01X1398256Y1106867D02*
X1397720Y1108070D01*
Y1110233D01*
G01X1399492D02*
Y1108532D01*
X1400271Y1107753D01*
X1400543Y1106780D01*
Y1105552D01*
G01X1407674Y1101917D02*
X1407786Y1102029D01*
Y1104941D01*
X1406445Y1108179D01*
X1404807Y1109817D01*
Y1110233D01*
G01X1403035D02*
Y1108875D01*
X1404756Y1107154D01*
Y1106897D01*
G01X1411046Y1123971D02*
X1409820D01*
X1408683Y1122834D01*
Y1120596D01*
X1407867Y1119780D01*
X1406421D01*
G01X1409287Y1111836D02*
X1408577Y1113550D01*
X1407662Y1114465D01*
X1406421D01*
G01Y1116237D02*
X1408137D01*
X1410903Y1113471D01*
X1411046D01*
G01X1407571Y1110092D02*
Y1111391D01*
X1407270Y1112117D01*
X1406694Y1112693D01*
X1406421D01*
G01Y1118008D02*
X1408076D01*
X1410889Y1120821D01*
X1411046D01*
G01X1422557Y1105705D02*
X1424533Y1107681D01*
Y1110233D01*
G01X1426344Y1105705D02*
Y1110194D01*
X1426305Y1110233D01*
G01X1431620D02*
Y1108532D01*
X1432399Y1107753D01*
X1432671Y1106780D01*
Y1105552D01*
G01X1430384Y1106867D02*
X1429848Y1108070D01*
Y1110233D01*
G01X1439279Y1103717D02*
Y1106475D01*
X1438573Y1108179D01*
X1436935Y1109817D01*
Y1110233D01*
G01X1435163D02*
Y1108875D01*
X1436884Y1107154D01*
Y1106897D01*
G01X1443174Y1123971D02*
X1441948D01*
X1440811Y1122834D01*
Y1120596D01*
X1439995Y1119780D01*
X1438549D01*
G01X1441415Y1111836D02*
X1440705Y1113550D01*
X1439790Y1114465D01*
X1438549D01*
G01X1439699Y1110092D02*
Y1111391D01*
X1439398Y1112117D01*
X1438822Y1112693D01*
X1438549D01*
G01Y1116237D02*
X1440265D01*
X1443031Y1113471D01*
X1443174D01*
G01X1438549Y1118008D02*
X1440204D01*
X1443017Y1120821D01*
X1443174D01*
X513666Y696458D03*
Y690553D03*
X521540Y688584D03*
X517603Y690553D03*
X519571D03*
X513666Y700395D03*
X515634Y690553D03*
X521540D03*
X513666Y692521D03*
Y694490D03*
Y698427D03*
X511697Y696458D03*
Y698427D03*
X519571Y688584D03*
X517603D03*
X515634D03*
X513666D03*
X511697Y700395D03*
Y688584D03*
Y690553D03*
Y692521D03*
Y694490D03*
X517603Y708269D03*
X513666Y702364D03*
Y708269D03*
X521540D03*
X513666Y704332D03*
Y706301D03*
X519571Y708269D03*
X515634D03*
X511697Y702364D03*
Y704332D03*
Y706301D03*
Y708269D03*
Y710238D03*
X513666D03*
X515634D03*
X517603D03*
X519571D03*
X521540D03*
X531382Y696458D03*
Y692521D03*
X529414Y690553D03*
X525477D03*
X531382D03*
Y700395D03*
X527445Y690553D03*
X523508D03*
X531382Y694490D03*
Y698427D03*
X533351Y700395D03*
Y698427D03*
Y696458D03*
Y694490D03*
Y692521D03*
Y690553D03*
Y688584D03*
X531382D03*
X529414D03*
X527445D03*
X525477D03*
X523508D03*
X525477Y708269D03*
X533351Y702364D03*
X529414Y708269D03*
X531382Y706301D03*
Y702364D03*
Y708269D03*
Y704332D03*
X527445Y708269D03*
X523508D03*
Y710238D03*
X525477D03*
X527445D03*
X529414D03*
X531382D03*
X533351D03*
Y708269D03*
Y706301D03*
Y704332D03*
G54D137*
X411109Y1116611D03*
X443237D03*
X476696D03*
X508824D03*
X1325283D03*
X1357411D03*
X1390870D03*
X1422998D03*
G54D245*
X1027569Y1344460D03*
Y1348200D03*
Y1351940D03*
X1037883D03*
Y1348200D03*
Y1344460D03*
G54D128*
X392821Y28608D03*
Y31168D03*
X409947Y28608D03*
Y31168D03*
X1268294Y333215D03*
Y330655D03*
X1285420Y333215D03*
Y330655D03*
X1306994Y28608D03*
Y31168D03*
X1324120Y28608D03*
Y31168D03*
X1582437Y340869D03*
Y338309D03*
X1599563Y340869D03*
Y338309D03*
G54D254*
X1155929Y786294D03*
Y808342D03*
X1171284Y786294D03*
X1158488D03*
X1161047D03*
X1163606D03*
X1166166D03*
X1168725D03*
X1158488Y808342D03*
X1171284D03*
X1161047D03*
X1163606D03*
X1166166D03*
X1168725D03*
X1173843Y786294D03*
Y808342D03*
G54D164*
X427378Y1555499D03*
X434070Y1560617D03*
Y1555499D03*
X427378Y1560617D03*
X948452Y360607D03*
X955144D03*
Y365725D03*
X948452D03*
G54D191*
X766516Y1622460D03*
X759036D03*
Y1633090D03*
X762776D03*
X766516D03*
X782289Y1623876D03*
X786029Y1614546D03*
X789769Y1623876D03*
G54D119*
X310628Y328844D03*
Y336324D03*
X320274Y328844D03*
Y336324D03*
Y332584D03*
X767714Y328844D03*
Y336324D03*
X777360Y328844D03*
Y336324D03*
Y332584D03*
X859838Y685230D03*
Y692710D03*
Y688970D03*
X869484Y685230D03*
Y692710D03*
X896074Y940895D03*
X886428D03*
Y944635D03*
X896074Y948375D03*
X886428D03*
X1224801Y328844D03*
X1234447D03*
X1224801Y336324D03*
X1234447D03*
Y332584D03*
X1681888Y328844D03*
X1691534D03*
X1681888Y336324D03*
X1691534D03*
Y332584D03*
G54D155*
X423215Y1122634D03*
X455343D03*
X488802D03*
X520930D03*
X1337389D03*
X1369517D03*
X1402976D03*
X1435104D03*
G54D209*
X887685Y569450D03*
Y571419D03*
Y575356D03*
Y579293D03*
Y583230D03*
Y585199D03*
Y577325D03*
Y587167D03*
Y573387D03*
Y581261D03*
Y589136D03*
X912291Y571419D03*
Y569450D03*
Y585199D03*
Y581261D03*
Y577325D03*
Y579293D03*
Y587167D03*
Y573387D03*
Y575356D03*
Y583230D03*
Y589136D03*
X1010047Y322072D03*
Y326009D03*
Y327978D03*
Y324041D03*
Y329947D03*
Y333883D03*
Y337821D03*
Y339789D03*
Y331915D03*
Y341758D03*
Y335852D03*
X1034653Y327978D03*
Y326009D03*
Y324041D03*
Y322072D03*
Y341758D03*
Y337821D03*
Y335852D03*
Y331915D03*
Y339789D03*
Y333883D03*
Y329947D03*
G54D44*
X32051Y213243D03*
X30083D03*
X28114D03*
X26146D03*
X24177D03*
X22209D03*
Y225055D03*
X24177D03*
X26146D03*
X28114D03*
X30083D03*
X32051D03*
X132445Y213243D03*
X130476D03*
X128508D03*
X126539D03*
X124571D03*
Y225055D03*
X126539D03*
X128508D03*
X130476D03*
X132445D03*
X134413Y213243D03*
Y225055D03*
X230870Y213243D03*
X228901D03*
X226933D03*
Y225055D03*
X228901D03*
X230870D03*
X236775Y213243D03*
X234807D03*
X232838D03*
Y225055D03*
X234807D03*
X236775D03*
X339137Y213243D03*
X337169D03*
X335200D03*
X333232D03*
X331263D03*
X329295D03*
Y225055D03*
X331263D03*
X333232D03*
X335200D03*
X337169D03*
X339137D03*
X389303Y383732D03*
X387335D03*
X385366D03*
X383398D03*
X381429D03*
X379461D03*
Y395544D03*
X381429D03*
X383398D03*
X385366D03*
X387335D03*
X389303D03*
X489138Y213243D03*
X487170D03*
X485201D03*
X483233D03*
X481264D03*
X479296D03*
Y225055D03*
X481264D03*
X483233D03*
X485201D03*
X487170D03*
X489138D03*
X587563Y213243D03*
X585595D03*
X583626D03*
X581658D03*
Y225055D03*
X583626D03*
X585595D03*
X587563D03*
X591500Y213243D03*
X589532D03*
Y225055D03*
X591500D03*
X684020Y213243D03*
Y225055D03*
X693862Y213243D03*
X691894D03*
X689925D03*
X687957D03*
X685988D03*
Y225055D03*
X687957D03*
X689925D03*
X691894D03*
X693862D03*
X796224Y213243D03*
X794256D03*
X792287D03*
X790319D03*
X788350D03*
X786382D03*
Y225055D03*
X788350D03*
X790319D03*
X792287D03*
X794256D03*
X796224D03*
X880692Y397073D03*
X878724D03*
X876755D03*
X874787D03*
Y408885D03*
X876755D03*
X878724D03*
X880692D03*
X884629Y397073D03*
X882661D03*
Y408885D03*
X884629D03*
X944922Y198414D03*
X942953D03*
X940985D03*
X939016D03*
X937048D03*
Y210226D03*
X939016D03*
X940985D03*
X942953D03*
X944922D03*
X946890Y198414D03*
Y210226D03*
X1042681Y213243D03*
X1040712D03*
X1038744D03*
Y225055D03*
X1040712D03*
X1042681D03*
X1048586Y213243D03*
X1046618D03*
X1044649D03*
Y225055D03*
X1046618D03*
X1048586D03*
X1150948Y213243D03*
X1148980D03*
X1147011D03*
X1145043D03*
X1143074D03*
X1141106D03*
Y225055D03*
X1143074D03*
X1145043D03*
X1147011D03*
X1148980D03*
X1150948D03*
X1253310Y213243D03*
X1251342D03*
X1249373D03*
X1247405D03*
X1245436D03*
X1243468D03*
Y225055D03*
X1245436D03*
X1247405D03*
X1249373D03*
X1251342D03*
X1253310D03*
X1301508Y383732D03*
X1299539D03*
X1297571D03*
X1295602D03*
X1293634D03*
Y395544D03*
X1295602D03*
X1297571D03*
X1299539D03*
X1301508D03*
X1303476Y383732D03*
Y395544D03*
X1399374Y213243D03*
X1397406D03*
X1395437D03*
X1393469D03*
Y225055D03*
X1395437D03*
X1397406D03*
X1399374D03*
X1403311Y213243D03*
X1401343D03*
Y225055D03*
X1403311D03*
X1497799Y213243D03*
X1495831D03*
Y225055D03*
X1497799D03*
X1505673Y213243D03*
X1503705D03*
X1501736D03*
X1499768D03*
Y225055D03*
X1501736D03*
X1503705D03*
X1505673D03*
X1608035Y213243D03*
X1606067D03*
X1604098D03*
X1602130D03*
X1600161D03*
X1598193D03*
Y225055D03*
X1600161D03*
X1602130D03*
X1604098D03*
X1606067D03*
X1608035D03*
X1708429Y213243D03*
X1706460D03*
X1704492D03*
X1702523D03*
X1700555D03*
Y225055D03*
X1702523D03*
X1704492D03*
X1706460D03*
X1708429D03*
X1710397Y213243D03*
Y225055D03*
X1756626Y383732D03*
X1754658D03*
X1752689D03*
X1750721D03*
Y395544D03*
X1752689D03*
X1754658D03*
X1756626D03*
X1760563Y383732D03*
X1758595D03*
Y395544D03*
X1760563D03*
G54D62*
X51160Y613799D03*
X49192D03*
X47224D03*
X45255D03*
X43286D03*
X41318D03*
X51160Y624823D03*
X47224D03*
X49192D03*
X43286D03*
X45255D03*
X41318D03*
X57066Y613799D03*
X55098D03*
X53129D03*
X55098Y624823D03*
X53129D03*
X425641Y449550D03*
X421705D03*
X506278Y613799D03*
X504310D03*
X502341D03*
X500372D03*
X498404D03*
X504310Y624823D03*
X506278D03*
X500372D03*
X502341D03*
X498404D03*
X514152Y613799D03*
X512184D03*
X510215D03*
X508246D03*
Y624823D03*
X512184D03*
X510215D03*
X920967Y465891D03*
X917031D03*
X961397Y613799D03*
X959428D03*
X957459D03*
X955491D03*
X961397Y624823D03*
X957459D03*
X959428D03*
X955491D03*
X971239Y613799D03*
X969271D03*
X967302D03*
X965333D03*
X963365D03*
X965333Y624823D03*
X969271D03*
X963365D03*
X967302D03*
X1339814Y449550D03*
X1335878D03*
X1416515Y613799D03*
X1414546D03*
X1412578D03*
X1414546Y624823D03*
X1416515D03*
X1412578D03*
X1428326Y613799D03*
X1426358D03*
X1424389D03*
X1422420D03*
X1420452D03*
X1418484D03*
X1422420Y624823D03*
X1418484D03*
X1426358D03*
X1420452D03*
X1424389D03*
X1796901Y449550D03*
X1792965D03*
G54D53*
X35158Y1504318D03*
X33189D03*
X31221D03*
X29252D03*
X27284D03*
X25315D03*
Y1538964D03*
X27284D03*
X29252D03*
X31221D03*
X33189D03*
X35158D03*
X50906Y1504318D03*
X48937D03*
X46969D03*
X45000D03*
X43032D03*
X41063D03*
X39095D03*
X37126D03*
Y1538964D03*
X39095D03*
X41063D03*
X43032D03*
X45000D03*
X46969D03*
X48937D03*
X50906D03*
X54843Y1504318D03*
X52874D03*
Y1538964D03*
X54843D03*
G54D17*
X12786Y85412D03*
X10292Y99695D03*
X14292D03*
X15948Y138776D03*
X11999Y138848D03*
X19855Y138871D03*
X12709Y173286D03*
X18826Y235961D03*
X10852Y1541606D03*
X11781Y1532371D03*
X6560Y1550595D03*
X18434Y1551666D03*
X20709Y173286D03*
X36201Y236043D03*
X24091Y236030D03*
X27966Y236018D03*
X29127Y1201683D03*
X27222Y1441611D03*
X48643Y448403D03*
X41643Y470403D03*
X46192Y639295D03*
X42192D03*
X50192D03*
X36692D03*
X40700Y1089630D03*
X58224Y470543D03*
X66224D03*
X53643Y470403D03*
X67684Y602709D03*
X63988Y628151D03*
X54192Y639295D03*
X57553Y1205719D03*
X53056Y1209848D03*
X54339Y1490956D03*
X60013Y1553179D03*
X66291Y1631286D03*
X73381Y91513D03*
X69381D03*
X77711Y176057D03*
X73711D03*
X77938Y187314D03*
X76877Y219666D03*
X80766Y262594D03*
X75819Y287967D03*
X79819D03*
X83819D03*
X83684Y602709D03*
X79684D03*
X71684D03*
X75684D03*
X73968Y665576D03*
X75049Y831202D03*
Y838616D03*
X70941Y1589749D03*
X74291Y1631286D03*
X78291D03*
X82291D03*
X70291D03*
X89845Y278285D03*
X87684Y602709D03*
X91057Y1028286D03*
X86291Y1631286D03*
X107607Y130807D03*
X117607D03*
X106796Y150813D03*
X121661Y130812D03*
X121840Y145921D03*
X120926Y235918D03*
X126453Y236030D03*
X130328Y236018D03*
X127235Y455565D03*
X138563Y236043D03*
X146400Y455284D03*
X175743Y91513D03*
X171743D03*
X179743D03*
X180073Y176057D03*
X176073D03*
X180300Y187314D03*
X179239Y219666D03*
X178181Y287967D03*
X182181D03*
X183752Y91513D03*
X183128Y262594D03*
X192207Y278285D03*
X186181Y287967D03*
X210482Y91788D03*
X214389Y91883D03*
X206533Y91860D03*
X211969Y130807D03*
X209158Y150813D03*
X219969Y130807D03*
X224023Y130812D03*
X224202Y145921D03*
X223288Y235918D03*
X228815Y236030D03*
X217939Y614948D03*
X221809Y614960D03*
X221084Y1482964D03*
X229753Y1537199D03*
X240925Y236043D03*
X232690Y236018D03*
X243278Y623847D03*
X247278D03*
X236498Y1478624D03*
X237753Y1537199D03*
X251278Y623847D03*
X278105Y91513D03*
X274105D03*
X278435Y176057D03*
X282105Y91513D03*
X286114D03*
X282435Y176057D03*
X282662Y187314D03*
X281601Y219666D03*
X285490Y262594D03*
X294569Y278285D03*
X280543Y287967D03*
X284543D03*
X288543D03*
X280500Y858698D03*
Y868798D03*
X286300Y893898D03*
Y904198D03*
X282300Y929398D03*
X282400Y939498D03*
X308895Y91860D03*
X312331Y130807D03*
X311520Y150834D03*
X312263Y314799D03*
X304543Y331926D03*
X316751Y91883D03*
X312844Y91788D03*
X322331Y130807D03*
X326385Y130812D03*
X326564Y145921D03*
X325650Y235918D03*
X331177Y236030D03*
X343287Y236043D03*
X335052Y236018D03*
X342285Y565196D03*
X341748Y1140188D03*
X341455Y1185029D03*
X338322Y1193954D03*
X342152Y1206502D03*
X347591Y396992D03*
X357748Y1140188D03*
X353748D03*
X349748D03*
X345471Y1184959D03*
X350400Y1198478D03*
X354400D03*
X358400D03*
X346387Y1206464D03*
X350402Y1206502D03*
X354402D03*
X358402D03*
X376467Y91513D03*
X377237Y376739D03*
X366486Y382632D03*
X370486D03*
X368587Y406525D03*
X364326Y484942D03*
X361748Y1140188D03*
X366157Y1149996D03*
X366133Y1168276D03*
X366400Y1198478D03*
X362400D03*
X366402Y1206502D03*
X362402D03*
X386112Y33677D03*
X380467Y91513D03*
X388476D03*
X384467D03*
X384797Y176057D03*
X380797D03*
X385024Y187314D03*
X383963Y219666D03*
X387852Y262594D03*
X382905Y287967D03*
X386905D03*
X390905D03*
X379800Y775084D03*
X378472Y793253D03*
X391614Y936135D03*
X408680Y43002D03*
X396680D03*
X396931Y278285D03*
X398237Y376540D03*
X394553Y395886D03*
X401165Y448521D03*
X395390Y875754D03*
X399052Y884257D03*
X402966Y884358D03*
X403159Y1122881D03*
X409461Y1566493D03*
X405461D03*
X415677Y315745D03*
X423551D03*
X419277D03*
X424479Y365141D03*
X416318Y365133D03*
X421459Y628810D03*
X420400Y798598D03*
X412100D03*
X413461Y1566493D03*
X435025Y315745D03*
X431425D03*
X427151D03*
X435574Y442023D03*
X429673Y459085D03*
X433673D03*
X438157Y506093D03*
X431285Y1123880D03*
X435287Y1122881D03*
X444779Y636940D03*
X455619Y1255479D03*
X472332Y130807D03*
X464332D03*
X461521Y150813D03*
X461091Y1027750D03*
X463413Y1123880D03*
X468746Y1122881D03*
X460574Y1255480D03*
X476386Y130812D03*
X476565Y145921D03*
X481178Y236030D03*
X475651Y235918D03*
X485053Y236018D03*
X488485Y415401D03*
X481485Y437401D03*
X488745Y680401D03*
X488091Y995250D03*
X493288Y236043D03*
X493485Y437401D03*
X503729Y445403D03*
X496729Y467403D03*
X503278Y639295D03*
X499278D03*
X507278D03*
X493778D03*
X491373Y657681D03*
X493914Y680419D03*
X505464Y673137D03*
X492091Y995250D03*
X500874Y1122881D03*
X496872Y1123880D03*
X521310Y467543D03*
X513310D03*
X508729Y467403D03*
X521074Y628151D03*
X511278Y639295D03*
X517464Y673137D03*
X513464D03*
X509464D03*
X517412Y761891D03*
X514576Y789287D03*
X519763Y789214D03*
X538477Y91513D03*
X530468D03*
X534468D03*
X526468D03*
X534798Y176057D03*
X530798D03*
X535025Y187314D03*
X533964Y219666D03*
X537853Y262594D03*
X532906Y287967D03*
X536906D03*
X528770Y602709D03*
X532770D03*
X536770D03*
X524770D03*
X537964Y673137D03*
X533964D03*
X529964D03*
X525964D03*
X529000Y1123880D03*
X546932Y278285D03*
X540906Y287967D03*
X544770Y602709D03*
X540770D03*
X542400Y847798D03*
X548144Y1028286D03*
X569114Y91883D03*
X565207Y91788D03*
X561258Y91860D03*
X564694Y130807D03*
X563883Y150813D03*
X567958Y1535299D03*
X574694Y130807D03*
X578748Y130812D03*
X578927Y145921D03*
X578013Y235918D03*
X583540Y236030D03*
X587415Y236018D03*
X584321Y455565D03*
X574504Y753368D03*
X587858Y1523799D03*
X579758Y1523699D03*
X575809Y1538485D03*
X583809D03*
X595650Y236043D03*
X603486Y455284D03*
X592103Y945291D03*
Y952705D03*
X591858Y1529899D03*
X595809Y1538485D03*
X632830Y91513D03*
X636830D03*
X628830D03*
X637160Y176057D03*
X633160D03*
X637387Y187314D03*
X636326Y219666D03*
X635268Y287967D03*
X640839Y91513D03*
X640215Y262594D03*
X649294Y278285D03*
X639268Y287967D03*
X643268D03*
X663620Y91860D03*
X667569Y91788D03*
X669056Y130807D03*
X666245Y150813D03*
X658064Y656220D03*
X662064D03*
X671476Y91883D03*
X677056Y130807D03*
X681110Y130812D03*
X681289Y145921D03*
X680375Y235918D03*
X685902Y236030D03*
X698012Y236043D03*
X689777Y236018D03*
X700364Y623847D03*
X693163Y700132D03*
X704364Y623847D03*
X708364D03*
X731192Y91513D03*
X720260Y699606D03*
X732170Y1625074D03*
X743201Y91513D03*
X739192D03*
X735192D03*
X739522Y176057D03*
X735522D03*
X739749Y187314D03*
X738688Y219666D03*
X742577Y262594D03*
X737630Y287967D03*
X741630D03*
X745630D03*
X751140Y1586794D03*
X735392Y1602249D03*
X744924Y1614852D03*
X743331Y1633703D03*
X765982Y91860D03*
X751656Y278285D03*
X761629Y331926D03*
X755187Y1586808D03*
X759452Y1616826D03*
X773838Y91883D03*
X769931Y91788D03*
X769418Y130807D03*
X779418D03*
X783472Y130812D03*
X783651Y145921D03*
X768607Y150813D03*
X782737Y235918D03*
X769349Y314799D03*
X774844Y1622454D03*
X778358Y1633185D03*
X788264Y236030D03*
X792139Y236018D03*
X799371Y565196D03*
X798835Y1140188D03*
X798542Y1185029D03*
X795159Y1191675D03*
X795418Y1206402D03*
X796972Y1397662D03*
X800374Y236043D03*
X813821Y738355D03*
X816027Y870739D03*
X806835Y1140188D03*
X814835D03*
X810835D03*
X802558Y1184959D03*
X815487Y1198478D03*
X811487D03*
X807487D03*
X802333Y1197995D03*
X815489Y1206502D03*
X811489D03*
X807489D03*
X803604Y1206459D03*
X806148Y1380667D03*
X810148D03*
X805009Y1472569D03*
X821412Y479942D03*
X830484Y744210D03*
X826484D03*
X822831Y839725D03*
X818831D03*
X820027Y870739D03*
X819629Y895614D03*
X828909Y911527D03*
X830913Y929661D03*
X818835Y1140188D03*
X823244Y1149996D03*
X823220Y1168276D03*
X819487Y1198478D03*
X823487D03*
X823489Y1206502D03*
X819489D03*
X833554Y91513D03*
X837554D03*
X845563D03*
X841554D03*
X841884Y176057D03*
X837884D03*
X842111Y187314D03*
X841050Y219666D03*
X844939Y262594D03*
X839992Y287967D03*
X843992D03*
X847992D03*
X846098Y414721D03*
X834484Y744210D03*
X846484D03*
X838484D03*
X842484D03*
X833112Y829697D03*
X832726Y843538D03*
X836311Y877072D03*
X844946Y911527D03*
X840909D03*
X836909D03*
X832909D03*
X838829Y929661D03*
X834829D03*
X845395D03*
X836423Y962178D03*
X832423D03*
X854018Y278285D03*
X863086Y379984D03*
X849680Y692098D03*
X854484Y744210D03*
X850484D03*
X852628Y912573D03*
X860628D03*
X849544Y1454243D03*
X872293Y91788D03*
X876200Y91883D03*
X868344Y91860D03*
X878500Y200409D03*
X879740Y260193D03*
X868086Y379984D03*
X876736Y388764D03*
X867586Y390484D03*
X869342Y414526D03*
X875916Y806374D03*
X879916Y816524D03*
X876628Y912573D03*
X868628D03*
X872817Y1210686D03*
X889879Y412227D03*
X896491Y464862D03*
X896431Y539552D03*
X891933Y615652D03*
X884045Y750219D03*
X887916Y806374D03*
X883916D03*
X891916D03*
X883916Y816524D03*
X887916D03*
X884628Y912573D03*
X887390Y1098633D03*
X896746Y1218851D03*
X891844Y1455143D03*
X897736Y388764D03*
X903431Y539552D03*
X911416Y806374D03*
X910900Y912484D03*
X906128Y959074D03*
X901243Y1214722D03*
X908852Y1227992D03*
X912726D03*
X929418Y130807D03*
X921418D03*
X918607Y150813D03*
X927072Y384391D03*
X923072D03*
X919072D03*
X924999Y475426D03*
X928999D03*
X917250Y554604D03*
X927916Y806374D03*
X923790D03*
X919664D03*
X915716D03*
X914500Y912484D03*
X918100D03*
X924628Y912573D03*
X928628D03*
X925697Y1457310D03*
X921868Y1457340D03*
X933472Y130812D03*
X933651Y145921D03*
X938930Y221201D03*
X942805Y221189D03*
X938657Y367695D03*
X930900Y458364D03*
X931916Y814524D03*
X943916D03*
X943735Y847641D03*
X945035Y833241D03*
X936616Y898088D03*
X936628Y912573D03*
X944628D03*
X940628D03*
X932628D03*
X932716Y898088D03*
X936794Y1210686D03*
X951040Y221214D03*
X955816Y470403D03*
X960365Y639295D03*
X956365D03*
X950865D03*
X947556Y705109D03*
X955950Y731522D03*
X950335Y826341D03*
X948935Y833241D03*
X958682Y834412D03*
X958200Y841584D03*
X950100Y853484D03*
X954000D03*
X954124Y883054D03*
X954567Y933303D03*
X957671Y988727D03*
X951367Y1098633D03*
X960723Y1218851D03*
X962816Y448403D03*
X972397Y470463D03*
X967816Y470403D03*
X978161Y628151D03*
X968365Y639295D03*
X964365D03*
X973712Y719573D03*
X965220Y1214722D03*
X983554Y91513D03*
X987554D03*
X991554D03*
X991884Y176057D03*
X987884D03*
X992111Y187314D03*
X991050Y219666D03*
X989992Y287967D03*
X993992D03*
X990405Y321234D03*
X984045Y364068D03*
X980045D03*
X980397Y470543D03*
X981857Y602709D03*
X989857D03*
X993857D03*
X985857D03*
X991990Y771458D03*
X987990D03*
X990051Y816827D03*
X995563Y91513D03*
X994939Y262594D03*
X1004018Y278285D03*
X997992Y287967D03*
X1004635Y305735D03*
X1008635D03*
X997857Y602709D03*
X1001857D03*
X1003990Y771458D03*
X999990D03*
X1005230Y1028286D03*
X1018344Y91860D03*
X1022293Y91788D03*
X1026200Y91883D03*
X1021780Y130807D03*
X1020969Y150813D03*
X1021259Y1316506D03*
X1024115Y1333873D03*
X1031780Y130807D03*
X1035834Y130812D03*
X1036013Y145921D03*
X1035099Y235918D03*
X1040626Y236030D03*
X1033786Y305735D03*
X1037386D03*
X1041496D03*
X1041408Y455565D03*
X1033719Y942306D03*
Y949720D03*
X1052736Y236043D03*
X1044501Y236018D03*
X1060573Y455284D03*
X1066260Y1445450D03*
X1085916Y91513D03*
X1089916D03*
X1090246Y176057D03*
X1090469Y1585469D03*
X1086904Y1596265D03*
X1083735Y1606682D03*
Y1614618D03*
X1085474Y1634909D03*
X1093916Y91513D03*
X1097925D03*
X1094246Y176057D03*
X1094473Y187314D03*
X1093412Y219666D03*
X1097301Y262594D03*
X1106380Y278285D03*
X1092354Y287967D03*
X1096354D03*
X1100354D03*
X1098376Y1557242D03*
X1093376D03*
X1100233Y1585492D03*
X1104612Y1606661D03*
X1098904Y1596265D03*
X1094904D03*
X1097474Y1634909D03*
X1124655Y91788D03*
X1120706Y91860D03*
X1123331Y150813D03*
X1115151Y656220D03*
X1119151D03*
X1128562Y91883D03*
X1134142Y130807D03*
X1126142D03*
X1138196Y130812D03*
X1138375Y145921D03*
X1137461Y235918D03*
X1142988Y236030D03*
X1155098Y236043D03*
X1146863Y236018D03*
X1152485Y770626D03*
X1157451Y623847D03*
X1161451D03*
X1165451D03*
X1168485Y770494D03*
X1160485Y770626D03*
X1164485D03*
X1188278Y91513D03*
X1180715Y781952D03*
X1196278Y91513D03*
X1200287D03*
X1192278D03*
X1196608Y176057D03*
X1192608D03*
X1196835Y187314D03*
X1195774Y219666D03*
X1199663Y262594D03*
X1194716Y287967D03*
X1198716D03*
X1202716D03*
X1208742Y278285D03*
X1218716Y331926D03*
X1227017Y91788D03*
X1230924Y91883D03*
X1223068Y91860D03*
X1236504Y130807D03*
X1226504D03*
X1225693Y150813D03*
X1226436Y314799D03*
X1240558Y130812D03*
X1240737Y145921D03*
X1239823Y235918D03*
X1245350Y236030D03*
X1249225Y236018D03*
X1251302Y1201909D03*
X1257460Y236043D03*
X1261764Y396992D03*
X1256458Y565196D03*
X1263921Y1140188D03*
X1267921D03*
X1255921D03*
X1255628Y1185029D03*
X1259644Y1184959D03*
X1264573Y1198478D03*
X1268573D03*
X1260771Y1196804D03*
X1264575Y1206502D03*
X1268575D03*
X1260535Y1206507D03*
X1280659Y382632D03*
X1284659D03*
X1282760Y406525D03*
X1278499Y484942D03*
X1284655Y897984D03*
X1275493Y926977D03*
X1279493D03*
X1283493D03*
X1271493D03*
X1275921Y1140188D03*
X1271921D03*
X1280330Y1149996D03*
X1280306Y1168276D03*
X1280573Y1198478D03*
X1276573D03*
X1272573D03*
X1276575Y1206502D03*
X1280575D03*
X1272575D03*
X1300285Y33677D03*
X1298640Y91513D03*
X1294640D03*
X1302649D03*
X1290640D03*
X1298970Y176057D03*
X1294970D03*
X1299197Y187314D03*
X1298136Y219666D03*
X1302025Y262594D03*
X1297078Y287967D03*
X1301078D03*
X1291500Y324484D03*
X1291410Y376739D03*
X1292000Y897984D03*
X1289500Y946984D03*
X1296500Y966984D03*
X1310853Y43002D03*
X1311104Y278285D03*
X1305078Y287967D03*
X1318262Y318837D03*
X1312410Y376540D03*
X1308726Y395886D03*
X1315338Y448521D03*
X1318500Y922984D03*
X1314500D03*
X1317000Y933984D03*
X1318500Y964984D03*
X1311000Y966984D03*
X1315000D03*
X1317333Y1122881D03*
X1322853Y43002D03*
X1329736Y318837D03*
X1334010D03*
X1321862D03*
X1326136D03*
X1320903Y368225D03*
X1329064Y368233D03*
X1327584Y782089D03*
X1330500Y922984D03*
X1334500D03*
X1326500Y933984D03*
X1337610Y318837D03*
X1349747Y442023D03*
X1343846Y459085D03*
X1347846D03*
X1345000Y793484D03*
X1348917D03*
X1342500Y922984D03*
X1338500D03*
X1336000Y933984D03*
X1345948Y949087D03*
X1349948D03*
X1345459Y1123880D03*
X1349461Y1122881D03*
X1352817Y793484D03*
X1365000Y809484D03*
X1361000D03*
X1357000D03*
X1365948Y949087D03*
X1357948D03*
X1353948D03*
X1378505Y130807D03*
X1375694Y150813D03*
X1380500Y593484D03*
Y639984D03*
Y684484D03*
Y731484D03*
X1373000Y809484D03*
X1381000D03*
X1369000D03*
X1377017Y809482D03*
X1382560Y937305D03*
X1378503Y937304D03*
X1369948Y949087D03*
X1375265Y1027750D03*
X1377587Y1123880D03*
X1382920Y1122881D03*
X1386505Y130807D03*
X1390559Y130812D03*
X1390738Y145921D03*
X1389824Y235918D03*
X1395351Y236030D03*
X1399226Y236018D03*
X1394537Y809163D03*
X1398517Y809201D03*
X1407461Y236043D03*
X1410903Y467403D03*
X1413452Y639295D03*
X1407952D03*
X1402517Y809201D03*
X1406483D03*
X1402265Y995250D03*
X1406265D03*
X1411046Y1123880D03*
X1415048Y1122881D03*
X1407747Y1546444D03*
X1407255Y1569122D03*
X1417903Y445403D03*
X1427484Y467543D03*
X1422903Y467403D03*
X1425452Y639295D03*
X1417452D03*
X1421452D03*
X1432258Y1410799D03*
X1444641Y91513D03*
X1440641D03*
X1448641D03*
X1448971Y176057D03*
X1444971D03*
X1449198Y187314D03*
X1448137Y219666D03*
X1447079Y287967D03*
X1435484Y467543D03*
X1442944Y602709D03*
X1438944D03*
X1446944D03*
X1435248Y628151D03*
X1437980Y1031431D03*
X1443174Y1123880D03*
X1436258Y1410799D03*
X1437293Y1543474D03*
X1436801Y1566152D03*
X1452650Y91513D03*
X1452026Y262594D03*
X1461105Y278285D03*
X1451079Y287967D03*
X1455079D03*
X1454944Y602709D03*
X1458944D03*
X1450944D03*
X1462317Y1028286D03*
X1479380Y91788D03*
X1475431Y91860D03*
X1478867Y130807D03*
X1478056Y150813D03*
X1471500Y715984D03*
Y759984D03*
X1483287Y91883D03*
X1488867Y130807D03*
X1492921Y130812D03*
X1493100Y145921D03*
X1492186Y235918D03*
X1497713Y236030D03*
X1488500Y801484D03*
Y845484D03*
X1509823Y236043D03*
X1501588Y236018D03*
X1498495Y455565D03*
X1517660Y455284D03*
X1547003Y91513D03*
X1543003D03*
X1555012D03*
X1551003D03*
X1551333Y176057D03*
X1547333D03*
X1551560Y187314D03*
X1550499Y219666D03*
X1554388Y262594D03*
X1549441Y287967D03*
X1553441D03*
X1557441D03*
X1577793Y91860D03*
X1563467Y278285D03*
X1572238Y656220D03*
X1576238D03*
X1585649Y91883D03*
X1581742Y91788D03*
X1591229Y130807D03*
X1583229D03*
X1595283Y130812D03*
X1595462Y145921D03*
X1580418Y150813D03*
X1594548Y235918D03*
X1587746Y1460616D03*
X1594264Y1472999D03*
X1600075Y236030D03*
X1603950Y236018D03*
X1601500Y1511984D03*
X1598000D03*
X1608500D03*
X1610858Y1523299D03*
X1612185Y236043D03*
X1614538Y623847D03*
X1618538D03*
X1622538D03*
X1653365Y91513D03*
X1657374D03*
X1645365D03*
X1649365D03*
X1653695Y176057D03*
X1649695D03*
X1653922Y187314D03*
X1652861Y219666D03*
X1656750Y262594D03*
X1651803Y287967D03*
X1655803D03*
X1659803D03*
X1665829Y278285D03*
X1675803Y331926D03*
X1680155Y91860D03*
X1684104Y91788D03*
X1688011Y91883D03*
X1683591Y130807D03*
X1682780Y150813D03*
X1683523Y314799D03*
X1693591Y130807D03*
X1697645Y130812D03*
X1697824Y145921D03*
X1702437Y236030D03*
X1696910Y235918D03*
X1706312Y236018D03*
X1714547Y236043D03*
X1718851Y396992D03*
X1713545Y565196D03*
X1721008Y1140188D03*
X1725008D03*
X1713008D03*
X1712715Y1185029D03*
X1716731Y1184959D03*
X1721660Y1198478D03*
X1725660D03*
X1709820Y1199574D03*
X1721662Y1206502D03*
X1725662D03*
X1717568Y1206302D03*
X1741746Y382632D03*
X1737746D03*
X1739847Y406525D03*
X1735586Y484942D03*
X1733008Y1140188D03*
X1729008D03*
X1737417Y1149996D03*
X1737393Y1168276D03*
X1737660Y1198478D03*
X1729660D03*
X1733660D03*
X1729662Y1206502D03*
X1733662D03*
X1737662D03*
X1751727Y91513D03*
X1755727D03*
X1747727D03*
X1756057Y176057D03*
X1752057D03*
X1756284Y187314D03*
X1755223Y219666D03*
X1754165Y287967D03*
X1758165D03*
X1748497Y376739D03*
X1750900Y907884D03*
X1756422Y1637788D03*
X1759736Y91513D03*
X1759112Y262594D03*
X1768191Y278285D03*
X1762165Y287967D03*
X1769497Y376540D03*
X1765813Y395886D03*
X1772425Y448521D03*
X1761072Y1596251D03*
X1765072D03*
X1772422Y1637788D03*
X1768422D03*
X1760422D03*
X1764422D03*
X1782517Y91860D03*
X1786466Y91788D03*
X1790373Y91883D03*
X1776071Y836378D03*
X1789537Y927561D03*
X1780774Y1211172D03*
X1778227Y1443592D03*
X1778104Y1475782D03*
X1776422Y1637788D03*
X1806834Y442023D03*
X1800933Y459085D03*
X1804933D03*
X1797374Y927433D03*
X1795347Y1099119D03*
X1804703Y1219337D03*
X1800046Y1440630D03*
X1799923Y1472820D03*
X1809700Y910084D03*
X1808363Y973144D03*
Y980558D03*
X1809200Y1215208D03*
G54D227*
X944695Y874268D03*
X950691Y857440D03*
X947541D03*
X950691Y861440D03*
X947541D03*
X947845Y874268D03*
G54D80*
X57066Y624724D03*
X514152D03*
X971239D03*
X1428326D03*
G54D35*
X15916Y1041679D03*
X28318D03*
X50051Y1041371D03*
X37649D03*
X438119Y1234726D03*
X450521D03*
X476828D03*
X489230D03*
X862606Y1050682D03*
X875008D03*
X896741Y1050374D03*
X884339D03*
X926583Y1050682D03*
X938985D03*
X960718Y1050374D03*
X948316D03*
X1352293Y1234726D03*
X1364695D03*
X1391002D03*
X1403404D03*
X1770563Y1051168D03*
X1782965D03*
X1804698Y1050860D03*
X1792296D03*
G54D146*
X416886Y331413D03*
Y344012D03*
Y332988D03*
Y339287D03*
Y337713D03*
Y329839D03*
Y336138D03*
Y334563D03*
Y340862D03*
Y342437D03*
Y347161D03*
Y345587D03*
X1319471Y334505D03*
Y336080D03*
Y342379D03*
Y340805D03*
Y332931D03*
Y339230D03*
Y337655D03*
Y343954D03*
Y350253D03*
Y347104D03*
Y348679D03*
Y345529D03*
G54D218*
X906811Y312857D03*
X908385D03*
X906811Y309235D03*
X908385D03*
G54D182*
X710406Y-26826D03*
Y-36826D03*
D03*
Y-26826D03*
X735406D03*
Y-36826D03*
D03*
Y-26826D03*
X830406Y-76006D03*
D03*
Y-66006D03*
D03*
X855406Y-76006D03*
D03*
Y-66006D03*
D03*
X939542Y-36798D03*
Y-26798D03*
D03*
Y-36798D03*
X964386Y-75978D03*
D03*
Y-65978D03*
D03*
X964542Y-36798D03*
Y-26798D03*
D03*
Y-36798D03*
X989386Y-75978D03*
D03*
Y-65978D03*
D03*
X993906Y-46826D03*
Y-36826D03*
D03*
Y-26826D03*
X1018906Y-46826D03*
Y-36826D03*
D03*
Y-26826D03*
X1063906Y-76006D03*
Y-86006D03*
Y-76006D03*
Y-66006D03*
X1088906Y-76006D03*
Y-86006D03*
Y-76006D03*
Y-66006D03*
X1217686Y-85978D03*
Y-75978D03*
D03*
Y-65978D03*
X1223042Y-46928D03*
Y-36928D03*
Y-26928D03*
Y-36928D03*
X1242686Y-85978D03*
Y-75978D03*
D03*
Y-65978D03*
X1248042Y-46928D03*
Y-36928D03*
Y-26928D03*
Y-36928D03*
X1280406Y-46956D03*
Y-36956D03*
D03*
Y-26956D03*
X1305406Y-46956D03*
Y-36956D03*
D03*
Y-26956D03*
X1320406Y-76006D03*
Y-86006D03*
Y-76006D03*
Y-66006D03*
X1345406Y-76006D03*
Y-86006D03*
Y-76006D03*
Y-66006D03*
X1474186Y-85978D03*
Y-75978D03*
D03*
Y-65978D03*
X1499186Y-85978D03*
Y-75978D03*
D03*
Y-65978D03*
X1509542Y-47058D03*
Y-37058D03*
Y-27058D03*
Y-37058D03*
X1534542Y-47058D03*
Y-37058D03*
Y-27058D03*
Y-37058D03*
X1564906Y-47086D03*
Y-37086D03*
D03*
Y-27086D03*
X1574906Y-76006D03*
Y-86006D03*
Y-76006D03*
Y-66006D03*
X1589906Y-47086D03*
Y-37086D03*
D03*
Y-27086D03*
X1599906Y-76006D03*
Y-86006D03*
Y-76006D03*
Y-66006D03*
X1728686Y-85978D03*
Y-75978D03*
D03*
Y-65978D03*
X1753686Y-85978D03*
Y-75978D03*
D03*
Y-65978D03*
X1794042Y-47188D03*
Y-37188D03*
Y-27188D03*
Y-37188D03*
X1819042Y-47188D03*
Y-37188D03*
Y-27188D03*
Y-37188D03*
G54D273*
G01X7271Y66681D02*
Y70981D01*
G01X8786Y82353D02*
X12786D01*
G01X11011Y75343D02*
Y79720D01*
G01D02*
X12286D01*
X12786Y80220D01*
Y82353D01*
G01X14292Y96636D02*
Y94264D01*
X14264Y94236D01*
G01X10292Y96636D02*
Y94236D01*
G01X6298Y96591D02*
X7261D01*
X10292Y99622D01*
Y99786D01*
G01D02*
Y99792D01*
X11778Y101278D01*
Y107903D01*
X11314Y109024D01*
Y111710D01*
G01X18298Y96591D02*
X17315D01*
X14292Y99614D01*
Y99786D01*
G01D02*
X13500Y100578D01*
Y107966D01*
X13874Y108869D01*
Y111710D01*
G01X41988Y95236D02*
X20119D01*
X12786Y87903D01*
G01D02*
Y85503D01*
G01X41988Y92874D02*
X20874D01*
X18000Y90000D01*
G01X10131Y115473D02*
X11314Y114290D01*
Y111710D01*
G01X13874D02*
Y114312D01*
X15143Y115581D01*
G01X13874Y128836D02*
Y131912D01*
X14996Y133034D01*
G01D02*
X15948Y133986D01*
Y135717D01*
G01X11314Y128836D02*
Y132591D01*
X11442Y132719D01*
G01D02*
Y135232D01*
X11999Y135789D01*
G01X16728Y128836D02*
Y129873D01*
X19855Y133000D01*
G01X11999Y138939D02*
Y141415D01*
G01X15948Y138867D02*
Y141267D01*
G01X16919Y156163D02*
Y153273D01*
X16909Y153263D01*
G01D02*
X15184Y151538D01*
Y150378D01*
G01X12247Y166341D02*
X14391D01*
X14951Y165781D01*
Y164037D01*
G01X17313Y166937D02*
X16919Y165985D01*
Y164037D01*
G01X19184Y150378D02*
X23184D01*
G01X21909Y153263D02*
X19637D01*
X18887Y154013D01*
Y156163D01*
G01Y164037D02*
Y165687D01*
X19921Y166721D01*
X22335D01*
G01X16709Y175943D02*
Y173377D01*
G01Y175943D02*
X23166Y182400D01*
X35605D01*
X37965Y180040D01*
Y177606D01*
G01X12709Y170227D02*
Y168519D01*
X12247Y168057D01*
Y166341D01*
G01X16709Y170227D02*
Y168871D01*
X17313Y168267D01*
Y166937D01*
G01X13715Y242078D02*
X9537D01*
X7000Y244615D01*
Y255701D01*
X8039Y256740D01*
X22221D01*
X24361Y258880D01*
X57987D01*
G01X18826Y232902D02*
X19800Y231445D01*
X22599Y228646D01*
G01X20694Y242078D02*
X16865D01*
G01X18463Y247292D02*
X18206Y247035D01*
Y244571D01*
G01D02*
X16865Y243230D01*
Y242078D01*
G01X13715Y262078D02*
Y259381D01*
G01X20694Y262078D02*
X16865D01*
G01X18206Y264571D02*
X16865Y263230D01*
Y262078D01*
G01X12895Y252371D02*
Y248371D01*
G01X18463Y250245D02*
X16723D01*
X15586Y249108D01*
G01D02*
X15314D01*
X14577Y248371D01*
X12895D01*
G01X18463Y267292D02*
X18206Y267035D01*
Y264571D01*
G01X18463Y270245D02*
X16723D01*
X15586Y269108D01*
G01X12895Y272371D02*
Y268371D01*
G01X15586Y269108D02*
X15314D01*
X14577Y268371D01*
X12895D01*
G01X19075Y287035D02*
X17006D01*
X15499Y288542D01*
G01X8335Y284118D02*
Y280663D01*
G01X19075Y284082D02*
X16708D01*
X14807Y282181D01*
G01D02*
X12870Y284118D01*
X11485D01*
G01X17644Y1480986D02*
X14136Y1484494D01*
Y1492501D01*
X15889Y1494254D01*
G01X16215Y1496782D02*
X15782Y1497215D01*
Y1501619D01*
G01X16215Y1496782D02*
Y1494580D01*
X15889Y1494254D01*
G01X12265Y1496782D02*
X12632Y1497149D01*
Y1501619D01*
G01X10952Y1489648D02*
X7965D01*
X7545Y1490068D01*
Y1493150D01*
X8649Y1494254D01*
X10089D01*
G01D02*
X11234D01*
X12265Y1495285D01*
Y1496782D01*
G01X15782Y1501619D02*
Y1509109D01*
X17487Y1510814D01*
X22756D01*
G01X12632Y1501619D02*
Y1509217D01*
X16198Y1512783D01*
X22756D01*
G01X10852Y1538547D02*
X6951D01*
G01X16463Y1536219D02*
X19634D01*
X21417Y1534436D01*
X22756D01*
G01X16463Y1536219D02*
X10985Y1541697D01*
X10852D01*
G01D02*
Y1545383D01*
X10367Y1545868D01*
Y1547505D01*
G01X16080Y1541684D02*
X21359Y1536405D01*
X22756D01*
G01X14375Y1547498D02*
Y1543389D01*
X16080Y1541684D01*
G01X18879Y1534334D02*
X20745Y1532468D01*
X22756D01*
G01X6560Y1547536D02*
X8296D01*
X8356Y1547596D01*
X10276D01*
X10367Y1547505D01*
G01X22381Y1548602D02*
X22376Y1548607D01*
X18434D01*
G01X31105Y1549755D02*
Y1554063D01*
X28940Y1556228D01*
X14919D01*
X11825Y1559322D01*
X7624D01*
X6457Y1558155D01*
Y1556883D01*
G01X41988Y97599D02*
X35510D01*
X35442Y97667D01*
G01D02*
X32173D01*
G01X31971Y103411D02*
X35048D01*
G01X41988Y99961D02*
X37213D01*
X35048Y102126D01*
Y103411D01*
G01X27989Y106495D02*
X31905D01*
X31971Y106561D01*
G01D02*
X35207D01*
G01X27989Y102495D02*
Y106495D01*
G01X19855Y133000D02*
Y135812D01*
G01X21909Y153263D02*
X23184Y151988D01*
Y150378D01*
G01X29357Y177448D02*
X26565D01*
G01X32507D02*
Y180517D01*
G01D02*
X34191D01*
X34889Y179819D01*
Y177448D01*
X39423Y172914D01*
Y170744D01*
G01X22335Y166721D02*
Y168601D01*
X20709Y170227D01*
G01X28114Y225055D02*
Y229782D01*
X27340Y230556D01*
G01X32201Y232984D02*
Y231180D01*
X31595Y230574D01*
Y227824D01*
G01D02*
Y227724D01*
X30083Y226212D01*
Y225055D01*
G01X24177D02*
Y227068D01*
X22599Y228646D01*
G01X33902Y241681D02*
Y244297D01*
G01X27966Y232959D02*
X27340Y232333D01*
Y230556D01*
G01X30752Y241681D02*
X30111Y241040D01*
Y233636D01*
X30763Y232984D01*
X32201D01*
G01X30356Y250599D02*
X30002Y250245D01*
X25549D01*
G01Y253198D02*
Y256394D01*
G01D02*
X28081D01*
X30552Y253923D01*
Y250795D01*
X30356Y250599D01*
G01Y270599D02*
X30002Y270245D01*
X25549D01*
G01Y273198D02*
Y276394D01*
G01D02*
X28081D01*
X30552Y273923D01*
Y270795D01*
X30356Y270599D01*
G01X31695Y281272D02*
X31552Y281129D01*
X29116D01*
G01X31695Y285272D02*
Y281272D01*
G01Y289272D02*
Y285272D01*
G01X29116Y281129D02*
X26161D01*
G01X34845Y281272D02*
X36126Y279991D01*
X37117D01*
G01X31549Y527726D02*
Y531726D01*
G01X34732Y534909D02*
X31549Y531726D01*
G01X38323Y536487D02*
X36310D01*
X34732Y534909D01*
G01X28399Y527726D02*
X25819D01*
G01X31549Y544726D02*
Y548726D01*
G01X34425Y546553D02*
Y548226D01*
X33925Y548726D01*
X31549D01*
G01X38323Y542393D02*
X36870D01*
X34425Y544838D01*
Y546553D01*
G01X31549Y552726D02*
X34448D01*
G01X38323Y544361D02*
X37601D01*
X37013Y544949D01*
Y550161D01*
X34448Y552726D01*
G01X34359Y541135D02*
X31958D01*
X31549Y540726D01*
G01X38323Y540424D02*
X36437D01*
X35726Y541135D01*
X34359D01*
G01X28399Y544726D02*
X25819D01*
G01X30117Y625311D02*
X27686D01*
G01X33267Y621311D02*
X35332D01*
X36306Y622285D01*
G01X33267Y625311D02*
Y621311D01*
G01X24074Y1496519D02*
X20500Y1500093D01*
Y1506129D01*
X21248Y1506877D01*
X22756D01*
G01X25674Y1491866D02*
Y1494919D01*
X24074Y1496519D01*
G01X22756Y1508846D02*
X19745D01*
G01X33189Y1504318D02*
Y1501373D01*
G01X22756Y1520657D02*
X19859D01*
G01X22756Y1530499D02*
X19735D01*
G01X21080Y1543113D02*
X22840D01*
X25315Y1540638D01*
Y1538964D01*
G01X22381Y1548602D02*
Y1546844D01*
X21080Y1545543D01*
Y1543113D01*
G01X31105Y1549755D02*
X28476Y1547126D01*
Y1543516D01*
X29252Y1542740D01*
Y1538964D01*
G01X27284D02*
Y1542664D01*
X26017Y1543931D01*
G01D02*
Y1548370D01*
X26231Y1548584D01*
G01X36364Y1544384D02*
X33189Y1541209D01*
Y1538964D01*
G01X35158D02*
Y1539817D01*
X40453Y1545112D01*
X41522D01*
G01X31221Y1538964D02*
Y1544634D01*
G01D02*
Y1545526D01*
X35850Y1550155D01*
G01X41988Y90512D02*
X45988D01*
G01X51550Y90615D02*
X49085Y88150D01*
X41988D01*
G01X41115Y177606D02*
X45326D01*
G01X48085Y167004D02*
Y170679D01*
X50285Y172879D01*
G01D02*
X48161D01*
X45326Y175714D01*
Y177606D01*
G01X48596Y451419D02*
Y454376D01*
G01Y451419D02*
X48643Y451372D01*
Y448494D01*
G01D02*
X46355D01*
X45643Y449206D01*
Y454376D01*
G01X41643Y470494D02*
Y473419D01*
G01X45643Y461462D02*
Y463419D01*
X46643Y464419D01*
X49643D01*
G01Y467344D02*
Y464419D01*
G01X53643Y467344D02*
X49643D01*
G01X42690Y461462D02*
Y463872D01*
X41643Y464919D01*
G01Y467344D02*
Y464919D01*
G01X45643Y467344D02*
X41643D01*
G01X43948Y492108D02*
Y491148D01*
X41380Y488580D01*
Y487982D01*
G01X44563Y482165D02*
X41380Y478982D01*
G01X48154Y489743D02*
X47269D01*
X45200Y487674D01*
Y482802D01*
X44563Y482165D01*
G01X43948Y492108D02*
X44908D01*
X46480Y493680D01*
X48154D01*
G01X43804Y500202D02*
X41600D01*
X41380Y499982D01*
G01X48154Y497617D02*
X47951D01*
X45366Y500202D01*
X43804D01*
G01X38230Y491982D02*
X35650D01*
G01X41380D02*
Y495982D01*
G01X48154Y495649D02*
X45600D01*
X45256Y495993D01*
G01D02*
X45245Y495982D01*
X41380D01*
G01X54192Y633473D02*
Y631693D01*
X51160Y628661D01*
Y624823D01*
G01X36306Y622285D02*
X37312Y621279D01*
X39743D01*
G01X68245Y1212054D02*
X74045D01*
X96333Y1189766D01*
Y1103265D01*
X77680Y1084612D01*
Y966720D01*
X83228Y961172D01*
Y945220D01*
X68443Y930435D01*
X46208Y921225D01*
X45404Y920421D01*
Y917663D01*
X46637Y916430D01*
X48429D01*
G01X47264Y919649D02*
X70756Y929380D01*
X85749Y944373D01*
Y962851D01*
X78800Y969800D01*
Y1081342D01*
X97846Y1100388D01*
Y1191354D01*
X75122Y1214078D01*
X64760D01*
X62234Y1216604D01*
X57381D01*
X54486Y1213709D01*
G01X45755Y1210558D02*
X47511D01*
X48842Y1211109D01*
G01D02*
X51336Y1213603D01*
Y1213709D01*
G01X45755Y1212527D02*
X46813D01*
X50542Y1216256D01*
X53479D01*
G01X48937Y1504318D02*
Y1502235D01*
X48089Y1501387D01*
G01X39095Y1504318D02*
Y1501361D01*
G01X52048Y1550121D02*
Y1549890D01*
X46818Y1544660D01*
G01D02*
X44868Y1542710D01*
X40000D01*
X37126Y1539836D01*
Y1538964D01*
G01X52264Y1545189D02*
X50769D01*
X46806Y1541226D01*
X42026D01*
X41063Y1540263D01*
Y1538964D01*
G01X57598Y1544760D02*
X55672D01*
X50906Y1539994D01*
Y1538964D01*
G01X40951Y1550155D02*
Y1548971D01*
X36364Y1544384D01*
G01X41522Y1545112D02*
X42802D01*
X47074Y1549384D01*
Y1550146D01*
G01X76660Y98198D02*
X75558Y97096D01*
X75412D01*
X74728Y96412D01*
X66223D01*
X64829Y95018D01*
Y92874D01*
G01D02*
X60098D01*
G01Y99961D02*
X55871D01*
G01X55921Y95236D02*
X60098D01*
G01X61759Y443069D02*
X65759D01*
G01X65122Y451557D02*
Y448560D01*
X65737Y447945D01*
Y445603D01*
G01X65759Y443069D02*
Y445581D01*
X65737Y445603D01*
G01X63154Y451557D02*
Y448505D01*
X60720Y446071D01*
X57857D01*
G01X57759Y443069D02*
Y445973D01*
X57857Y446071D01*
G01X62224Y470634D02*
Y473045D01*
G01X65122Y459431D02*
Y461146D01*
X67670Y463694D01*
Y464818D01*
G01X66224Y467484D02*
X67670Y466038D01*
Y464818D01*
G01X58224Y467484D02*
Y465004D01*
G01X61186Y459431D02*
Y462042D01*
X58224Y465004D01*
G01X63154Y459431D02*
Y462371D01*
G01X62224Y467484D02*
Y463301D01*
X63154Y462371D01*
G01X63859Y590801D02*
X67987D01*
G01X59684Y605443D02*
Y594976D01*
X63859Y590801D01*
G01X70546Y593360D02*
Y594108D01*
X69804Y594850D01*
X65964D01*
X63684Y597130D01*
G01D02*
Y599650D01*
G01Y602800D02*
Y605443D01*
G01X67684Y602800D02*
Y605637D01*
G01X71684Y602800D02*
X67684D01*
G01X54192Y633473D02*
Y636236D01*
G01X57692D02*
Y632038D01*
X58181Y631549D01*
Y627908D01*
G01X61192Y636236D02*
X57692D01*
G01X64692D02*
X61192D01*
G01X58181Y627908D02*
X57066Y626793D01*
Y624724D01*
G01X64692Y639386D02*
Y642184D01*
G01X63969Y869475D02*
X63149Y870295D01*
X59134D01*
G01X63930Y874694D02*
X62479Y875295D01*
X59134D01*
G01X52077Y905295D02*
X58504D01*
G01D02*
X59134D01*
G01X64509Y1067656D02*
Y1071656D01*
G01X58219Y1081713D02*
X59261D01*
X60131Y1080843D01*
Y1075938D01*
X61588Y1074481D01*
G01D02*
X64413Y1071656D01*
X64509D01*
G01X80593Y946082D02*
Y960907D01*
X75700Y965800D01*
Y1090600D01*
X72693Y1093607D01*
X57220D01*
X55660Y1092047D01*
Y1090178D01*
G01X64509Y1083656D02*
X63109D01*
X62109Y1084656D01*
G01D02*
X61115Y1085650D01*
X58219D01*
G01X64509Y1075656D02*
Y1079656D01*
G01X58219Y1083682D02*
X59654D01*
X62109Y1081227D01*
Y1079656D01*
G01D02*
X64509D01*
G01X62109Y1091656D02*
X60633D01*
X60133Y1091156D01*
Y1088119D01*
X59633Y1087619D01*
X58219D01*
G01X67659Y1083656D02*
X70175D01*
X72162Y1081669D01*
Y957591D01*
X76332Y953421D01*
G01X67659Y1087656D02*
Y1083656D01*
G01X64509Y1091656D02*
X62109D01*
G01X78167Y949261D02*
X78192Y949286D01*
Y954375D01*
X76907Y955660D01*
Y956324D01*
X78093Y957510D01*
Y958174D01*
X77010Y959257D01*
X76346D01*
X76293Y959204D01*
X75629D01*
X73882Y960951D01*
Y1088472D01*
X70698Y1091656D01*
X67659D01*
G01X57702Y1198820D02*
X60269D01*
G01X54843Y1504318D02*
Y1501625D01*
G01X57402Y1514751D02*
X60227D01*
G01X57402Y1528531D02*
X60141D01*
X60277Y1528395D01*
G01X52264Y1545189D02*
X56114Y1549039D01*
Y1550120D01*
G01X57598Y1544760D02*
X61529Y1548691D01*
X63242D01*
X64664Y1550113D01*
X64747D01*
G01X62328Y1544571D02*
X61611Y1543854D01*
Y1539765D01*
G01X54843Y1538964D02*
X60810D01*
X61611Y1539765D01*
G01X55862Y1541791D02*
X54703D01*
X52874Y1539962D01*
Y1538964D01*
G01X57402Y1534436D02*
X60303D01*
G01X60013Y1550120D02*
X56114D01*
G01X66291Y1628227D02*
X70291D01*
G01X76660Y98198D02*
X80660D01*
G01X77804Y95879D02*
X81678D01*
X82942Y97143D01*
Y98587D01*
X84808Y100453D01*
G01X85149Y141247D02*
X81320D01*
G01X82918Y146461D02*
X82661Y146204D01*
Y143740D01*
G01D02*
X81320Y142399D01*
Y141247D01*
G01X77350Y151540D02*
Y147540D01*
G01X82918Y149414D02*
X81178D01*
X80041Y148277D01*
G01D02*
X79769D01*
X79032Y147540D01*
X77350D01*
G01X80766Y259535D02*
Y256303D01*
G01X75438Y265701D02*
X76766Y264373D01*
Y262685D01*
G01X80525Y265896D02*
Y264086D01*
X80766Y263845D01*
Y262685D01*
G01X79038Y269603D02*
Y267575D01*
X78342Y266879D01*
X76616D01*
X75438Y265701D01*
G01X82974Y269603D02*
Y268681D01*
X85541Y266114D01*
G01X83014Y281982D02*
X81006Y279974D01*
Y277477D01*
G01X77073Y281716D02*
X79038Y279751D01*
Y277477D01*
G01X81006Y269603D02*
Y267599D01*
X80525Y267118D01*
Y265896D01*
G01X83819Y284908D02*
Y282787D01*
X83014Y281982D01*
G01X75819Y284908D02*
X79819D01*
G01D02*
Y283104D01*
X78431Y281716D01*
X77073D01*
G01X83684Y599650D02*
Y596729D01*
G01X87684Y599650D02*
X83684D01*
G01Y596729D02*
X80315Y593360D01*
X76452D01*
G01X71684Y599650D02*
X72515Y598819D01*
Y596089D01*
G01D02*
Y593360D01*
G01X79684Y599650D02*
Y597282D01*
X79184Y596782D01*
X77734D01*
G01X75684Y599650D02*
X79684D01*
G01X77734Y596782D02*
X76014D01*
X74483Y595251D01*
Y593360D01*
G01X84699Y1004541D02*
X83065D01*
X82098Y1005508D01*
Y1011581D01*
X82730Y1012213D01*
X84679D01*
G01X84141Y1021048D02*
Y1023092D01*
X84780Y1023731D01*
X88479D01*
G01X70941Y1586690D02*
X80740D01*
X89028Y1578402D01*
Y1573758D01*
X88558Y1573288D01*
X84872D01*
X84402Y1572818D01*
Y1571788D01*
X84872Y1571318D01*
X88558D01*
X89028Y1570848D01*
Y1569818D01*
X88558Y1569348D01*
X84872D01*
X84402Y1568878D01*
Y1567848D01*
X84872Y1567378D01*
X88558D01*
X89028Y1566908D01*
Y1432071D01*
X92799Y1428300D01*
X207430D01*
X210721Y1431591D01*
Y1440406D01*
X213556Y1443241D01*
X228596D01*
X234191Y1437646D01*
Y1433165D01*
X235912Y1431444D01*
Y1430780D01*
X234057Y1428925D01*
Y1428261D01*
X234574Y1427744D01*
X235238D01*
X237093Y1429599D01*
X237757D01*
X238274Y1429082D01*
Y1428418D01*
X236419Y1426563D01*
Y1425899D01*
X236936Y1425382D01*
X237600D01*
X239455Y1427237D01*
X240119D01*
X240411Y1426945D01*
X370044D01*
X390554Y1447455D01*
X393951D01*
G01X68689Y1597855D02*
Y1593654D01*
X69816Y1592527D01*
G01X70941Y1589840D02*
Y1591402D01*
X69816Y1592527D01*
G01X73689Y1597855D02*
Y1594229D01*
X74909Y1593009D01*
G01D02*
X77181D01*
X91100Y1579090D01*
Y1434299D01*
X94994Y1430405D01*
X206938D01*
X208517Y1431984D01*
Y1462665D01*
X211860Y1466008D01*
X230146D01*
X236274Y1459880D01*
Y1433776D01*
X241385Y1428665D01*
X369166D01*
X390523Y1450022D01*
X395888D01*
G01X71910Y1625009D02*
X70291Y1626628D01*
Y1628227D01*
G01X73689Y1618721D02*
Y1623230D01*
X71910Y1625009D01*
G01X78291Y1625743D02*
Y1628227D01*
G01X78689Y1618721D02*
Y1623293D01*
X78291Y1623691D01*
Y1625743D01*
G01X83689Y1624736D02*
X82291Y1626134D01*
Y1628227D01*
G01X83689Y1618721D02*
Y1624736D01*
G01X74291Y1628227D02*
X78291D01*
G01X86291D02*
X82291D01*
G01X91224Y141247D02*
X88299D01*
G01X91224D02*
X94024D01*
X94771Y140500D01*
X104973D01*
X107121Y142648D01*
X108643D01*
G01X92337Y144172D02*
X93836Y144793D01*
X94811Y145768D01*
G01X202859Y158194D02*
X202858Y158193D01*
X142631D01*
X135124Y165700D01*
X107699D01*
X101261Y159262D01*
Y148325D01*
X100761Y147825D01*
X95432D01*
X94811Y147204D01*
Y145768D01*
G01X97961D02*
Y143868D01*
X97611Y143518D01*
X95711D01*
G01D02*
Y142392D01*
X95938Y142165D01*
X104265D01*
X107000Y144900D01*
X110077D01*
X110800Y144177D01*
Y140400D01*
X110095Y139695D01*
X108643D01*
G01X90004Y149414D02*
X94457D01*
X94811Y149768D01*
G01X90004Y152367D02*
X94805D01*
X94811Y152373D01*
G01D02*
Y149768D01*
G01X95457Y179897D02*
Y176034D01*
X98826Y172665D01*
G01D02*
X101747D01*
G01X98763Y178560D02*
Y179904D01*
G01X101747Y180665D02*
X99524D01*
X98763Y179904D01*
G01D02*
Y180204D01*
X97101Y181866D01*
X95457D01*
G01X101747Y196665D02*
X97073D01*
X92898Y192490D01*
G01D02*
Y188362D01*
G01X101747Y192665D02*
X99108D01*
X98173Y191730D01*
Y190185D01*
G01D02*
X96364D01*
X95457Y189278D01*
Y185803D01*
G01Y183834D02*
X98653D01*
G01D02*
X100916D01*
X101747Y184665D01*
G01X98966Y207037D02*
X100793Y208864D01*
X101842D01*
G01X95068Y211197D02*
X96521D01*
X98966Y208752D01*
Y207037D01*
G01X101842Y200864D02*
X98943D01*
G01D02*
X96362Y203445D01*
Y208398D01*
X95531Y209229D01*
X95068D01*
G01X99032Y212455D02*
X101433D01*
X101842Y212864D01*
G01X95068Y213166D02*
X96754D01*
X97465Y212455D01*
X99032D01*
G01X95068Y217103D02*
X97081D01*
X101842Y221864D01*
G01X85541Y266114D02*
Y264678D01*
X84766Y263903D01*
Y262685D01*
G01X91838Y679427D02*
X97033D01*
G01X103770Y868206D02*
X101681Y870295D01*
X96930D01*
G01Y880295D02*
X101682D01*
X105387Y884000D01*
X110887D01*
G01X103692Y900295D02*
X96930D01*
G01Y905295D02*
X91387D01*
G01X99836Y986106D02*
Y988436D01*
X100200Y988800D01*
G01D02*
X99836Y989164D01*
Y991956D01*
G01X95836Y986106D02*
Y988813D01*
G01D02*
Y991956D01*
G01X97609Y1010822D02*
X97376D01*
X94398Y1007844D01*
Y1006648D01*
G01D02*
Y1003349D01*
G01X90658D02*
X88553D01*
X87632Y1004270D01*
Y1007522D01*
G01D02*
X86257Y1008897D01*
X85042D01*
X84679Y1009260D01*
G01X91436Y1021177D02*
X91057Y1021556D01*
Y1025227D01*
G01X91765Y1015166D02*
X93522D01*
X93998Y1014690D01*
Y1012690D01*
X93521Y1012213D01*
X91765D01*
G01Y1015166D02*
Y1018307D01*
G01D02*
Y1020848D01*
X91436Y1021177D01*
G01X87291Y1021048D02*
Y1017840D01*
X88007Y1017124D01*
Y1013678D01*
G01D02*
X86542Y1012213D01*
X84679D01*
G01X91057Y1028377D02*
X88620D01*
X88287Y1028044D01*
Y1026537D01*
G01X93496Y1547768D02*
Y1435404D01*
X96704Y1432196D01*
X205698D01*
X206652Y1433150D01*
Y1463250D01*
X212769Y1469367D01*
Y1497659D01*
X219312Y1504202D01*
X224979D01*
X227831Y1507054D01*
X233555D01*
X249399Y1491210D01*
Y1442720D01*
X254854Y1437265D01*
X364264D01*
X376300Y1449301D01*
Y1562266D01*
X385650Y1571616D01*
X420044D01*
X421461Y1570199D01*
Y1566584D01*
G01X115582Y107899D02*
X119582D01*
G01X115285Y113684D02*
Y111534D01*
X116035Y110784D01*
X118307D01*
G01X113317Y113684D02*
Y110794D01*
X113307Y110784D01*
G01D02*
X111582Y109059D01*
Y107899D01*
G01X106796Y147754D02*
X111034D01*
X113607Y145177D01*
Y135500D01*
X113800Y135307D01*
Y133593D01*
X113607Y133400D01*
Y130898D01*
G01X115285Y121558D02*
Y124163D01*
X115785Y124663D01*
X117886D01*
G01X113607Y127748D02*
X112864Y127005D01*
Y124879D01*
G01X113317Y121558D02*
Y123785D01*
X112864Y124879D01*
G01X111349Y121558D02*
Y123126D01*
X110192Y124283D01*
X107798D01*
G01D02*
X107830Y124315D01*
Y127525D01*
X107607Y127748D01*
G01X103456Y157370D02*
Y148980D01*
X104685Y147754D01*
X106796D01*
G01X115729Y136742D02*
Y138338D01*
X116229Y138838D01*
X119230D01*
G01X106796Y150904D02*
Y154865D01*
G01X121448Y161958D02*
Y158209D01*
X120948Y157709D01*
X114577D01*
X111733Y154865D01*
G01D02*
X106796D01*
G01X101747Y168665D02*
Y172665D01*
G01Y176665D02*
Y180665D01*
G01X104897Y196665D02*
X107540D01*
G01X104897Y192665D02*
X107540D01*
G01X104897Y184665D02*
X106920D01*
X107653Y185398D01*
Y186778D01*
G01D02*
Y187934D01*
X106922Y188665D01*
X104897D01*
G01X104992Y208864D02*
X107572D01*
G01X101842Y204864D02*
Y208864D01*
G01X101839Y225719D02*
Y221867D01*
X101842Y221864D01*
G01X101839Y225719D02*
Y226629D01*
X103841Y228631D01*
G01X116077Y242078D02*
X108805D01*
X106317Y244566D01*
Y255458D01*
X109739Y258880D01*
X160349D01*
G01X115257Y252371D02*
Y248371D01*
G01D02*
X116939D01*
X117676Y249108D01*
X117948D01*
G01X111836Y991956D02*
Y988813D01*
G01D02*
Y986106D01*
G01X103836D02*
Y988813D01*
G01D02*
Y991956D01*
G01X115836D02*
Y988813D01*
G01D02*
Y986106D01*
G01X107836Y991956D02*
Y988813D01*
G01D02*
Y986106D01*
G01X117421Y1204453D02*
X114593Y1207281D01*
G01D02*
X115928Y1208616D01*
X117654D01*
X118533Y1207737D01*
G01X111764Y1210110D02*
X108936Y1212938D01*
G01D02*
X110370Y1214372D01*
X112048D01*
G01X105754Y1216120D02*
X107803Y1218169D01*
G01X135448Y1234921D02*
X132470D01*
X121899Y1230543D01*
X109543D01*
X105601Y1226601D01*
G01X117428Y1228380D02*
X114015D01*
X112236Y1226601D01*
X109601D01*
G01X130360Y106495D02*
X130351D01*
Y102495D01*
G01X134333Y106561D02*
X134267Y106495D01*
X130360D01*
G01X118307Y110784D02*
X119582Y109509D01*
Y107899D01*
G01X121661Y130903D02*
X121630Y130934D01*
Y134838D01*
G01X121661Y127753D02*
Y126313D01*
X122867Y125107D01*
G01X117886Y124663D02*
Y126008D01*
X117607Y126287D01*
Y127748D01*
G01X128251Y143762D02*
X131481D01*
G01X117708Y153296D02*
Y150265D01*
X119256Y148717D01*
X125381D01*
G01D02*
X127534D01*
X128251Y148000D01*
Y146912D01*
G01X121630Y134838D02*
Y138838D01*
G01X119230D02*
X121630D01*
G01X130476Y225055D02*
Y229782D01*
X129702Y230556D01*
G01X133957Y227824D02*
Y227724D01*
X132445Y226212D01*
Y225055D01*
G01X120926Y232859D02*
Y232681D01*
X124961Y228646D01*
G01X126539Y225055D02*
Y227068D01*
X124961Y228646D01*
G01X130328Y232959D02*
X129702Y232333D01*
Y230556D01*
G01X133114Y241681D02*
X132473Y241040D01*
Y233636D01*
X133125Y232984D01*
X134563D01*
G01X123056Y242078D02*
X119227D01*
G01X120825Y247292D02*
X120568Y247035D01*
Y244571D01*
G01D02*
X119227Y243230D01*
Y242078D01*
G01X117948Y249108D02*
X119085Y250245D01*
X120825D01*
G01X132718Y250599D02*
X132364Y250245D01*
X127911D01*
G01Y253198D02*
Y256394D01*
G01D02*
X130443D01*
X132914Y253923D01*
Y250795D01*
X132718Y250599D01*
G01X148176Y458711D02*
X142387Y464500D01*
X129645D01*
X127235Y462090D01*
Y455656D01*
G01Y452506D02*
X128944D01*
X130700Y450750D01*
X133095D01*
G01X127235Y452506D02*
Y448656D01*
G01X133095Y450750D02*
Y462264D01*
X134020Y463189D01*
X140898D01*
X145376Y458711D01*
G01X131836Y991956D02*
Y988813D01*
G01D02*
Y986106D01*
G01X119836Y991956D02*
Y988813D01*
G01D02*
Y986106D01*
G01X123836Y991956D02*
Y988813D01*
G01D02*
Y986106D01*
G01X127836Y991956D02*
Y988813D01*
G01D02*
Y986106D01*
G01X136432Y1224472D02*
X136145D01*
X128740Y1217067D01*
G01X123084Y1222724D02*
X125912Y1219896D01*
G01X131569Y1214239D02*
X134397Y1211411D01*
X134398D01*
G01X135757Y1221407D02*
Y1218427D01*
X131569Y1214239D01*
G01X135448Y1229402D02*
X135250Y1229600D01*
X128400D01*
X125624Y1226824D01*
X121527D01*
X120255Y1225552D01*
G01X117428Y1228380D02*
X124406D01*
X126433Y1230407D01*
G01X123084Y1222724D02*
X123082D01*
G01X129250Y1227650D02*
X125587Y1223987D01*
X124347D01*
X123084Y1222724D01*
G01X144350Y99961D02*
X139575D01*
X137410Y102126D01*
Y103411D01*
G01X134535Y97667D02*
X137804D01*
G01X144350Y97599D02*
X137872D01*
X137804Y97667D01*
G01X144350Y90512D02*
X148462D01*
X148600Y90650D01*
G01X144350Y88150D02*
X151447D01*
X153912Y90615D01*
G01X148350Y95236D02*
X144350D01*
G01Y92874D02*
X135437D01*
X133200Y95111D01*
G01X137410Y103411D02*
X134333D01*
G01X137569Y106561D02*
X134333D01*
G01X134563Y232984D02*
Y231180D01*
X133957Y230574D01*
Y227824D01*
G01X136264Y241681D02*
X138646D01*
X138664Y241699D01*
G01X148061Y378600D02*
X151025D01*
G01X148940Y455921D02*
X146946D01*
X146400Y455375D01*
G01D02*
X144012D01*
X139975Y459412D01*
X136835D01*
G01X148176Y458711D02*
X149065Y459600D01*
X151025D01*
G01X147263Y554555D02*
X151113D01*
G01X147263Y562555D02*
X151133D01*
X151145Y562567D01*
G01X147263Y558555D02*
X151113D01*
G01X147836Y991956D02*
Y988813D01*
G01D02*
Y986106D01*
G01X135836D02*
Y988813D01*
G01D02*
Y991956D01*
G01X139836Y986106D02*
Y988813D01*
G01D02*
Y991956D01*
G01X143836D02*
Y988813D01*
G01D02*
Y986106D01*
G01X148818Y1090157D02*
X146948Y1088287D01*
G01X145078Y1090157D02*
X143208Y1088287D01*
G01X148818Y1101377D02*
X146948Y1099507D01*
G01X145078Y1101377D02*
X143208Y1099507D01*
G01X148818Y1108858D02*
X146948Y1106988D01*
G01X145078Y1108858D02*
X143208Y1106988D01*
G01X148818Y1116338D02*
X146948Y1114468D01*
G01X148818Y1123818D02*
X146948Y1121948D01*
G01X145078Y1116338D02*
X143208Y1114468D01*
G01X145078Y1123818D02*
X143208Y1121948D01*
G01X148818Y1131299D02*
X146948Y1129429D01*
G01X145078Y1131299D02*
X143208Y1129429D01*
G01X148818Y1149999D02*
X146948Y1148129D01*
G01X145078Y1149999D02*
X143208Y1148129D01*
G01X162460Y92874D02*
X167191D01*
G01X158283Y95236D02*
X162460D01*
G01Y99961D02*
X158233D01*
G01X181269Y382067D02*
X167679D01*
X167146Y382600D01*
X158929D01*
G01X154175Y378600D02*
Y382600D01*
G01X158929D02*
X154175D01*
G01X151025Y459600D02*
Y458038D01*
X151525Y457538D01*
X162582D01*
X165379Y460335D01*
X206693D01*
X212004Y455024D01*
X221375D01*
G01X181269Y465177D02*
X159020D01*
G01X154175Y459600D02*
Y463600D01*
G01X159020Y465177D02*
X155752D01*
X154175Y463600D01*
G01X151113Y554555D02*
Y553175D01*
X151614Y552674D01*
X159044D01*
G01D02*
X162925Y556555D01*
X181269D01*
G01X151145Y562567D02*
Y563575D01*
X152144Y564574D01*
X158779D01*
X158982Y564371D01*
G01D02*
X164260D01*
X167351Y561280D01*
X181269D01*
G01X151113Y558555D02*
Y559925D01*
X151613Y560425D01*
X155746D01*
X156800Y559371D01*
X158982D01*
G01D02*
X161663D01*
X162117Y558917D01*
X181269D01*
G01X153543Y595588D02*
X155267D01*
X156000Y596321D01*
X158198D01*
G01D02*
X163939D01*
X172185Y604567D01*
X181269D01*
G01X153543Y591588D02*
X158820D01*
X159020Y591388D01*
G01D02*
X167665D01*
X169033Y592756D01*
X181269D01*
G01X153543Y607588D02*
Y603632D01*
X153575Y603600D01*
G01X158220Y606190D02*
X155630Y603600D01*
X153575D01*
G01X181269Y606929D02*
X170938D01*
X165266Y601257D01*
X159042D01*
G01D02*
X157373Y599588D01*
X153543D01*
G01X159046Y621005D02*
X157641Y619600D01*
X153575D01*
G01Y611600D02*
X155363D01*
X155837Y611126D01*
X159049D01*
G01D02*
X166295D01*
X166823Y611654D01*
X181269D01*
G01Y609291D02*
X169021D01*
X165920Y606190D01*
X158220D01*
G01X153575Y615600D02*
X155043D01*
X155512Y616069D01*
X158242D01*
G01D02*
X169307D01*
X171360Y614016D01*
X181269D01*
G01Y616378D02*
X173146D01*
X168529Y620995D01*
X159056D01*
X159046Y621005D01*
G01X158555Y637979D02*
X160703Y635831D01*
X164608D01*
X176974Y623465D01*
X181269D01*
G01X153575Y627600D02*
X155737D01*
X159023Y630886D01*
G01D02*
X165901D01*
X175685Y621102D01*
X181269D01*
G01Y618740D02*
X174618D01*
X167408Y625950D01*
X158219D01*
G01D02*
X155869Y623600D01*
X153575D01*
G01X149469Y634190D02*
X150425Y633234D01*
Y631421D01*
G01Y627600D02*
Y631421D01*
G01X153575Y641974D02*
Y637969D01*
G01D02*
X158545D01*
X158555Y637979D01*
G01X152658Y645389D02*
X151958D01*
X150425Y643856D01*
Y641974D01*
G01X151836Y991956D02*
Y988813D01*
G01D02*
Y986106D01*
G01X159836Y991956D02*
Y988813D01*
G01D02*
Y986106D01*
G01X155836Y995106D02*
Y997860D01*
G01X160039Y1075196D02*
X158169Y1073326D01*
G01X152559Y1075196D02*
X150689Y1073326D01*
G01X163779Y1086417D02*
X161909Y1084547D01*
G01X160039Y1078936D02*
X158169Y1077066D01*
G01X156299Y1086417D02*
X154429Y1084547D01*
G01X163779Y1082677D02*
X161909Y1080807D01*
G01X156299Y1082677D02*
X154429Y1080807D01*
G01X163779Y1105117D02*
X161909Y1103247D01*
G01X160039Y1097637D02*
X158169Y1095767D01*
G01X156299Y1105117D02*
X154429Y1103247D01*
G01X152559Y1097637D02*
X150689Y1095767D01*
G01X163779Y1101377D02*
X161909Y1099507D01*
G01X160039Y1093897D02*
X158169Y1092027D01*
G01X156299Y1101377D02*
X154429Y1099507D01*
G01X152559Y1093897D02*
X150689Y1092027D01*
G01X163779Y1112598D02*
X161909Y1110728D01*
G01X156299Y1112598D02*
X154429Y1110728D01*
G01X156299Y1120078D02*
X154429Y1118208D01*
G01X152559Y1112598D02*
X150689Y1110728D01*
G01X152559Y1120078D02*
X150689Y1118208D01*
G01X156299Y1127558D02*
X154429Y1125688D01*
G01X152559Y1127558D02*
X150689Y1125688D01*
G01X183022Y98198D02*
X179022D01*
G01X167191Y92874D02*
Y95018D01*
X168585Y96412D01*
X177361D01*
X179022Y98073D01*
Y98198D01*
G01X179712Y151540D02*
Y147540D01*
G01X182403Y148277D02*
X182131D01*
X181394Y147540D01*
X179712D01*
G01X177800Y265701D02*
X179128Y264373D01*
Y262685D01*
G01X179435Y281716D02*
X181400Y279751D01*
Y277477D01*
G01Y269603D02*
Y267575D01*
X180704Y266879D01*
X178978D01*
X177800Y265701D01*
G01X178181Y284908D02*
X182181D01*
G01D02*
Y283104D01*
X180793Y281716D01*
X179435D01*
G01X181269Y554193D02*
X183779D01*
X191807Y562221D01*
Y575460D01*
X194063Y577716D01*
G01X185328Y545528D02*
Y547359D01*
X183218Y549469D01*
X181269D01*
G01X167519Y1075196D02*
X165649Y1073326D01*
G01X171259Y1086417D02*
X169389Y1084547D01*
G01X167519Y1078936D02*
X165649Y1077066D01*
G01X171259Y1082677D02*
X169389Y1080807D01*
G01X171259Y1105117D02*
X169389Y1103247D01*
G01X167519Y1097637D02*
X165649Y1095767D01*
G01X167519Y1093897D02*
X165649Y1092027D01*
G01X167519Y1112598D02*
X165649Y1110728D01*
G01X167519Y1153740D02*
X165649Y1151870D01*
G01X171259Y1157480D02*
X169389Y1155610D01*
G01X167519Y1149999D02*
X165649Y1148129D01*
G01X171259Y1153740D02*
X169389Y1151870D01*
G01X171259Y1149999D02*
X169389Y1148129D01*
G01X167519Y1146259D02*
X165649Y1144389D01*
G01X167519Y1157480D02*
X165649Y1155610D01*
G01X171259Y1161220D02*
X169389Y1159350D01*
G01X167519Y1161220D02*
X165649Y1159350D01*
G01X193923Y68581D02*
Y69564D01*
X196946Y72587D01*
X197118D01*
G01X205848Y64722D02*
Y72853D01*
X203934Y74767D01*
X199298D01*
X197118Y72587D01*
G01X193923Y80581D02*
Y79618D01*
X196954Y76587D01*
X197118D01*
G01D02*
X204788D01*
X208408Y72967D01*
Y64722D01*
G01X191568Y76587D02*
X193968D01*
G01X191568Y72615D02*
X191596Y72587D01*
X193968D01*
G01X193007Y100625D02*
X194373Y99259D01*
X197929D01*
G01X188526Y97475D02*
X186026D01*
G01X197380Y112083D02*
Y112402D01*
X199466Y114488D01*
G01X188526Y100625D02*
X193007D01*
G01X188526Y105087D02*
Y100625D01*
G01X193586Y141247D02*
X190661D01*
G01X193586D02*
X196386D01*
X197133Y140500D01*
X207335D01*
X209483Y142648D01*
X211005D01*
G01X202859Y158194D02*
Y148325D01*
X202359Y147825D01*
X197742D01*
X197173Y147256D01*
Y145768D01*
G01X211005Y139695D02*
X212457D01*
X213100Y140338D01*
Y144101D01*
X212301Y144900D01*
X209400D01*
X206665Y142165D01*
X198300D01*
X198073Y142392D01*
Y143518D01*
G01X187511Y141247D02*
X183682D01*
G01X185280Y146461D02*
X185023Y146204D01*
Y143740D01*
G01D02*
X183682Y142399D01*
Y141247D01*
G01X185280Y149414D02*
X183540D01*
X182403Y148277D01*
G01X192366Y152367D02*
X197167D01*
X197173Y152373D01*
G01X192366Y149414D02*
X196819D01*
X197173Y149768D01*
G01Y152373D02*
Y149768D01*
G01X197819Y179897D02*
Y176034D01*
X201188Y172665D01*
G01X197819Y183834D02*
X201015D01*
G01X201125Y179904D02*
Y180204D01*
X199463Y181866D01*
X197819D01*
G01X204109Y196665D02*
X199435D01*
X195260Y192490D01*
G01D02*
Y188362D01*
G01X197819Y185803D02*
Y189278D01*
X198726Y190185D01*
X200535D01*
G01X197430Y213166D02*
X199116D01*
X199827Y212455D01*
X201394D01*
G01X197430Y209229D02*
X198152D01*
X198740Y208641D01*
Y203429D01*
X201305Y200864D01*
G01X197430Y211197D02*
X198883D01*
X201328Y208752D01*
Y207037D01*
G01X197430Y217103D02*
X199443D01*
X204204Y221864D01*
G01X183128Y259535D02*
Y256303D01*
G01X187903Y266114D02*
Y264678D01*
X187128Y263903D01*
Y262685D01*
G01X182887Y265896D02*
Y264086D01*
X183128Y263845D01*
Y262685D01*
G01X185376Y281982D02*
X183368Y279974D01*
Y277477D01*
G01X185336Y269603D02*
Y268681D01*
X187903Y266114D01*
G01X183368Y269603D02*
Y267599D01*
X182887Y267118D01*
Y265896D01*
G01X186181Y284908D02*
Y282787D01*
X185376Y281982D01*
G01X189960Y1116338D02*
X188090Y1114468D01*
G01X186220Y1116338D02*
X184350Y1114468D01*
G01X193700Y1116338D02*
X191830Y1114468D01*
G01X197440Y1116338D02*
X195570Y1114468D01*
G01X193700Y1135039D02*
X191830Y1133169D01*
G01X193700Y1131299D02*
X191830Y1129429D01*
G01X193700Y1142519D02*
X191830Y1140649D01*
G01X197440Y1142519D02*
X195570Y1140649D01*
G01X197440Y1213582D02*
X195570Y1215452D01*
G01X205848Y64722D02*
Y60513D01*
G01X208408Y64722D02*
X208645Y64485D01*
Y60369D01*
G01X211262Y81848D02*
Y82885D01*
X214389Y86012D01*
G01X209530Y86046D02*
X208408Y84924D01*
Y81848D01*
G01X205976Y85731D02*
X205848Y85603D01*
Y81848D01*
G01X206533Y91951D02*
Y94351D01*
G01X210482Y91879D02*
Y94279D01*
G01Y88729D02*
Y86998D01*
X209530Y86046D01*
G01X206533Y88801D02*
X205976Y88244D01*
Y85731D01*
G01X201669Y107921D02*
Y103621D01*
G01X213944Y107899D02*
Y109059D01*
X215669Y110784D01*
G01X213711Y121558D02*
Y123126D01*
X212554Y124283D01*
X210160D01*
G01D02*
X210192Y124315D01*
Y125971D01*
X211969Y127748D01*
G01X205818Y157370D02*
Y148980D01*
X207047Y147754D01*
X209158D01*
G01X215969Y130898D02*
Y133400D01*
X216200Y133631D01*
Y135201D01*
X215969Y135432D01*
Y145177D01*
X213396Y147754D01*
X209158D01*
G01X198073Y143518D02*
X199973D01*
X200323Y143868D01*
Y145768D01*
G01X202859Y158194D02*
Y160110D01*
X208349Y165600D01*
X237586D01*
X244993Y158193D01*
X305220D01*
X305221Y158194D01*
G01X209158Y150904D02*
Y154865D01*
G01X223810Y161958D02*
Y158209D01*
X223310Y157709D01*
X216939D01*
X214095Y154865D01*
G01D02*
X209158D01*
G01X204109Y176665D02*
Y180665D01*
G01D02*
X201886D01*
X201125Y179904D01*
G01Y178560D02*
Y179904D01*
G01X204109Y168665D02*
Y172665D01*
G01X201188D02*
X204109D01*
G01X201015Y183834D02*
X203278D01*
X204109Y184665D01*
G01X200535Y190185D02*
Y191730D01*
X201470Y192665D01*
X204109D01*
G01X207259Y196665D02*
X209902D01*
G01X207259Y192665D02*
X209902D01*
G01X207259Y184665D02*
X209282D01*
X210015Y185398D01*
Y186778D01*
G01D02*
Y187934D01*
X209284Y188665D01*
X207259D01*
G01X207354Y208864D02*
X209934D01*
G01X204204Y212864D02*
X203795Y212455D01*
X201394D01*
G01X201305Y200864D02*
X204204D01*
G01Y204864D02*
Y208864D01*
G01X201328Y207037D02*
X203155Y208864D01*
X204204D01*
G01X204201Y225719D02*
Y221867D01*
X204204Y221864D01*
G01X204201Y225719D02*
Y226629D01*
X206203Y228631D01*
G01X218439Y242078D02*
X211167D01*
X208679Y244566D01*
Y255458D01*
X212101Y258880D01*
X262711D01*
G01X214469Y248371D02*
X211691D01*
G01X199380Y382067D02*
X204633D01*
X204675Y382109D01*
G01X199380Y465177D02*
X207957D01*
X210334Y462800D01*
X213594D01*
G01D02*
X218225D01*
G01X218425Y549800D02*
X216725D01*
X216394Y549469D01*
X213662D01*
G01D02*
X199380D01*
G01Y551831D02*
X204526D01*
X204674Y551683D01*
G01X227025Y549700D02*
X224362Y552363D01*
X219735D01*
X217500Y554598D01*
X213797D01*
G01D02*
X207505D01*
X205548Y556555D01*
X199380D01*
G01Y558917D02*
X204674D01*
G01D02*
X207293D01*
X208710Y557500D01*
X217125D01*
X218425Y558800D01*
G01X204674Y561420D02*
X207436D01*
X208816Y562800D01*
X218425D01*
G01X199380Y561280D02*
X203280D01*
X203420Y561420D01*
X204674D01*
G01X199380Y592756D02*
X205756D01*
X208500Y595500D01*
G01X199380Y616378D02*
X202960D01*
X203460Y616878D01*
Y618400D01*
G01X218825Y621400D02*
X216925Y619500D01*
X214000D01*
G01D02*
X206500D01*
X204898Y621102D01*
X199380D01*
G01Y606929D02*
X203500D01*
G01X199380Y611654D02*
X202803D01*
X203741Y612592D01*
G01X199380Y609291D02*
X202586D01*
X203367Y610072D01*
X209158D01*
G01X199380Y614016D02*
X202395D01*
X203663Y615284D01*
X208061D01*
X209094Y616317D01*
G01X199380Y604567D02*
X208000D01*
G01X218825Y625400D02*
X214000D01*
G01D02*
X212400D01*
X210600Y627200D01*
X204899D01*
X201164Y623465D01*
X199380D01*
G01X204921Y1116338D02*
X203051Y1114468D01*
G01X201181Y1116338D02*
X199311Y1114468D01*
G01X208661Y1116338D02*
X206791Y1114468D01*
G01X212401Y1116338D02*
X210531Y1114468D01*
G01X216141Y1213582D02*
X214271Y1211712D01*
G01X212401Y1213582D02*
X210531Y1215452D01*
G01X214389Y86012D02*
Y88824D01*
G01X217944Y107899D02*
X221944D01*
G01X217647Y113684D02*
Y111534D01*
X218397Y110784D01*
X220669D01*
G01D02*
X221944Y109509D01*
Y107899D01*
G01X215669Y110784D02*
X215679Y110794D01*
Y113684D01*
G01X224023Y130903D02*
X223992Y130934D01*
Y134838D01*
G01X224023Y127753D02*
Y126313D01*
X225229Y125107D01*
G01X217647Y121558D02*
Y124163D01*
X218147Y124663D01*
X220248D01*
G01D02*
Y126008D01*
X219969Y126287D01*
Y127748D01*
G01X215679Y121558D02*
Y123785D01*
X215226Y124879D01*
G01D02*
Y127005D01*
X215969Y127748D01*
G01X220070Y153296D02*
Y150265D01*
X221618Y148717D01*
X227743D01*
G01D02*
X229896D01*
X230613Y148000D01*
Y146912D01*
G01X218091Y136742D02*
Y138338D01*
X218591Y138838D01*
X221592D01*
G01X223992Y134838D02*
Y138838D01*
G01X221592D02*
X223992D01*
G01X227323Y228646D02*
X223288Y232681D01*
Y232859D01*
G01X228901Y225055D02*
Y227068D01*
X227323Y228646D01*
G01X225418Y242078D02*
X221589D01*
G01X223187Y247292D02*
X222930Y247035D01*
Y244571D01*
G01D02*
X221589Y243230D01*
Y242078D01*
G01X217619Y252371D02*
Y248371D01*
G01X223187Y250245D02*
X221447D01*
X220310Y249108D01*
G01D02*
X220038D01*
X219301Y248371D01*
X217619D01*
G01X230273Y253198D02*
X233417D01*
G01X230273Y250245D02*
X234726D01*
X235080Y250599D01*
G01X221375Y455024D02*
Y458800D01*
G01X218225D02*
Y462800D01*
G01X221575Y545800D02*
Y541000D01*
X222075Y540500D01*
X225000D01*
G01X230175Y549700D02*
Y553700D01*
G01D02*
Y557700D01*
G01X218425Y545800D02*
Y549800D01*
G01X230175Y557700D02*
Y561325D01*
X223500Y568000D01*
G01X221809Y611901D02*
X219565Y609657D01*
Y597110D01*
X221693Y594982D01*
G01X217939Y611889D02*
Y595245D01*
X222289Y590895D01*
G01X221809Y615051D02*
Y616454D01*
X220333Y617930D01*
G01X221809Y615051D02*
X217951D01*
X217939Y615039D01*
G01X220333Y617930D02*
X221975Y619572D01*
Y621400D01*
G01Y625400D02*
Y621400D01*
G01X226566Y836900D02*
X238400D01*
G01X226566Y904200D02*
X279500D01*
G01X227362Y1116338D02*
X225492Y1114468D01*
G01X223622Y1116338D02*
X221752Y1114468D01*
G01X219881Y1116338D02*
X218011Y1114468D01*
G01X216141Y1217322D02*
X218011Y1215452D01*
G01X227362Y1217322D02*
X229232Y1215452D01*
G01X227468Y1482442D02*
X225754D01*
X224780Y1481468D01*
Y1478149D01*
G01X227468Y1478442D02*
Y1474523D01*
X227469Y1474522D01*
G01D02*
Y1473689D01*
X225765Y1471985D01*
G01X217985Y1483055D02*
X221084D01*
G01D02*
X222473D01*
X225860Y1486442D01*
X227468D01*
G01Y1490442D02*
X225826Y1488800D01*
X221899D01*
G01X398747Y1500959D02*
X399570Y1500136D01*
Y1476253D01*
X393806Y1470489D01*
Y1455806D01*
X368385Y1430385D01*
X242187D01*
X238913Y1433659D01*
Y1489670D01*
X231505Y1497078D01*
X224841D01*
X224196Y1496433D01*
X219730D01*
X218021Y1494724D01*
G01X230612Y1494361D02*
Y1490448D01*
X230618Y1490442D01*
G01X226135Y1502442D02*
X231559D01*
X245700Y1488301D01*
Y1439601D01*
X251476Y1433825D01*
X366626D01*
X388669Y1455868D01*
Y1475615D01*
X395199Y1482145D01*
Y1482223D01*
G01X395370Y1501022D02*
Y1497408D01*
X397487Y1495291D01*
Y1477028D01*
X391383Y1470924D01*
Y1456084D01*
X367404Y1432105D01*
X243174D01*
X240827Y1434452D01*
Y1490498D01*
X232251Y1499074D01*
X223475D01*
X222843Y1498442D01*
G01X222790Y1522542D02*
X224748Y1524500D01*
X231801D01*
X232623Y1523678D01*
Y1522578D01*
G01X225753Y1534140D02*
X224269Y1532656D01*
Y1530730D01*
X226395Y1528604D01*
X237580D01*
G01X229473Y1522578D02*
X226971D01*
G01X229473Y1526578D02*
X224200D01*
X219981Y1530797D01*
G01X229473Y1518578D02*
X227578D01*
X224642Y1515642D01*
X223090D01*
G01D02*
Y1518346D01*
X223322Y1518578D01*
G01X229473Y1514578D02*
X226971D01*
G01X229753Y1534140D02*
Y1532958D01*
X227552Y1530757D01*
Y1530675D01*
G01X221942Y1534310D02*
X225583D01*
X225753Y1534140D01*
G01Y1537290D02*
Y1539121D01*
X224933Y1539941D01*
X222119D01*
G01X229753Y1537290D02*
Y1538945D01*
X227882Y1540816D01*
G01X229942Y1546310D02*
Y1542876D01*
X227882Y1540816D01*
G01X246712Y99961D02*
X241937D01*
X239772Y102126D01*
Y103411D01*
G01X246712Y97599D02*
X240234D01*
X240166Y97667D01*
G01D02*
X236897D01*
G01X246712Y90512D02*
X250824D01*
X250962Y90650D01*
G01X246712Y88150D02*
X253809D01*
X256274Y90615D01*
G01X250712Y95236D02*
X246712D01*
G01Y92874D02*
X237799D01*
X235562Y95111D01*
G01X239772Y103411D02*
X236695D01*
G01X232713Y106495D02*
X236629D01*
X236695Y106561D01*
G01D02*
X239931D01*
G01X232713Y102495D02*
Y106495D01*
G01X230613Y143762D02*
X233843D01*
G01X232838Y225055D02*
Y229782D01*
X232064Y230556D01*
G01X236925Y232984D02*
Y231180D01*
X236319Y230574D01*
Y227824D01*
G01D02*
Y227724D01*
X234807Y226212D01*
Y225055D01*
G01X232690Y232959D02*
X232064Y232333D01*
Y230556D01*
G01X238626Y241681D02*
Y244297D01*
G01X235476Y241681D02*
X234835Y241040D01*
Y233636D01*
X235487Y232984D01*
X236925D01*
G01X233417Y253198D02*
X234921D01*
X235276Y252843D01*
Y250795D01*
X235080Y250599D01*
G01X230689Y380718D02*
Y373081D01*
X233070Y370700D01*
X255141D01*
X275618Y350223D01*
X291396D01*
G01X230689Y384718D02*
Y380718D01*
G01X270305Y382047D02*
X266562D01*
X265233Y380718D01*
X241825D01*
G01D02*
X233839D01*
G01X230689Y388718D02*
Y390010D01*
X231190Y390511D01*
X247729D01*
X248714Y391496D01*
X253186D01*
G01X233839Y384718D02*
X252004D01*
G01X270305Y389134D02*
X258968D01*
X257718Y387884D01*
X246141D01*
G01D02*
X242903D01*
X242069Y388718D01*
X233839D01*
G01Y392718D02*
X243820D01*
X244960Y393858D01*
G01X233839Y396718D02*
Y392718D01*
G01Y408718D02*
X251601D01*
G01X233839Y400718D02*
X252819D01*
G01X270305Y398583D02*
X262205D01*
X256070Y404718D01*
X242398D01*
G01D02*
X233839D01*
G01X244960Y393858D02*
X270305D01*
G01Y412756D02*
X242599D01*
X242561Y412718D01*
G01D02*
X233839D01*
G01X245362Y546712D02*
X248310D01*
G01X243278Y620788D02*
Y618288D01*
G01X246031Y633786D02*
Y631449D01*
X243278Y628696D01*
G01D02*
Y623938D01*
G01X246031Y640872D02*
Y643255D01*
X246976Y644200D01*
X248126D01*
X249867Y645941D01*
G01X243078Y640872D02*
Y645900D01*
G01X246102Y650671D02*
X242102D01*
G01X243078Y645900D02*
Y647895D01*
X242102Y648871D01*
Y650671D01*
G01X246102Y653821D02*
Y656321D01*
G01X238062Y826900D02*
X245300D01*
X246311Y825889D01*
Y819000D01*
G01D02*
Y816300D01*
G01X238400Y836900D02*
X238500Y836800D01*
X245311D01*
G01X238062Y894200D02*
X280600D01*
G01X246062Y1112598D02*
X246063D01*
X247933Y1114468D01*
G01X246062Y1116338D02*
X246063D01*
X247933Y1118208D01*
G01X244192Y1215452D02*
X242322Y1213582D01*
G01X240452Y1215452D02*
X238582Y1213582D01*
G01X247932Y1215451D02*
X246062Y1217322D01*
G01X247932Y1211711D02*
X246062Y1213582D01*
G01X230618Y1478442D02*
X232813D01*
X233313Y1477942D01*
Y1476699D01*
G01X236498Y1478715D02*
Y1480154D01*
X234976Y1481676D01*
G01X395380Y1485778D02*
X386539Y1476937D01*
Y1456340D01*
X365744Y1435545D01*
X253255D01*
X247600Y1441200D01*
Y1490499D01*
X233053Y1505046D01*
X230758D01*
G01X230618Y1482442D02*
X232730D01*
X233496Y1481676D01*
X234976D01*
G01X230618Y1486442D02*
X233180D01*
G01X230618Y1490442D02*
X232154D01*
X233166Y1491454D01*
G01X232618Y1510442D02*
X240808Y1518632D01*
Y1519942D01*
G01X246310Y1506058D02*
Y1509961D01*
X246491Y1510142D01*
G01D02*
X244866D01*
X243535Y1511473D01*
G01X237753Y1534140D02*
X240423D01*
X242648Y1536365D01*
X253565D01*
X255390Y1534540D01*
Y1523140D01*
X253415Y1521165D01*
X245125D01*
X237633Y1513673D01*
Y1511909D01*
G01X244600Y1531700D02*
X245368Y1530932D01*
Y1529045D01*
X234901Y1518578D01*
X232623D01*
G01X248042Y1527310D02*
X245404D01*
X232672Y1514578D01*
X232623D01*
G01Y1522578D02*
X235687D01*
G01X248610Y1517958D02*
Y1516288D01*
X246491Y1514169D01*
G01X248610Y1517958D02*
X246425D01*
X245500Y1517033D01*
G01X232623Y1526578D02*
X233295Y1525906D01*
X239438D01*
X240842Y1527310D01*
G01X245937Y1524237D02*
X250937D01*
X252911Y1526211D01*
Y1533543D01*
X251419Y1535035D01*
X243935D01*
X242738Y1533838D01*
Y1528137D01*
X241911Y1527310D01*
X240842D01*
G01X233753Y1534140D02*
Y1532235D01*
X232622Y1531104D01*
G01D02*
X231759Y1531967D01*
Y1541416D01*
X233942Y1543599D01*
Y1546310D01*
G01X237753Y1537290D02*
Y1538985D01*
X239949Y1541181D01*
Y1541327D01*
G01X237942Y1546310D02*
Y1543334D01*
X239949Y1541327D01*
G01X244942Y1546310D02*
Y1539419D01*
X244912Y1539389D01*
G01X233753Y1537290D02*
Y1539752D01*
G01X264822Y99961D02*
X260595D01*
G01X260645Y95236D02*
X264822D01*
G01X253186Y391496D02*
X270305D01*
G01X252004Y384718D02*
X259556D01*
X259864Y384410D01*
X270305D01*
G01X251601Y408718D02*
X255635D01*
X260377Y403976D01*
Y403961D01*
X263393Y400945D01*
X270305D01*
G01X252819Y400718D02*
X255705D01*
X260202Y396221D01*
X270305D01*
G01X249125Y453873D02*
Y449873D01*
G01Y445873D02*
Y443426D01*
X249595Y442956D01*
X252695D01*
G01X249125Y449873D02*
Y445873D01*
G01X261965Y458455D02*
X264377Y456043D01*
X270305D01*
G01X252275Y453873D02*
X259761D01*
X262526Y451108D01*
G01D02*
X264677Y448957D01*
X270305D01*
G01X249125Y465874D02*
Y462859D01*
G01X252275D02*
Y458859D01*
G01D02*
X257747D01*
X258151Y458455D01*
X261965D01*
G01X318660Y545912D02*
Y547474D01*
X318160Y547974D01*
X307103D01*
X304306Y545177D01*
X262992D01*
X259293Y548876D01*
X248810D01*
X248310Y548376D01*
Y546712D01*
G01X251460D02*
Y542712D01*
G01D02*
X256091D01*
G01D02*
X259351D01*
X261728Y540335D01*
X270305D01*
G01X250583Y669913D02*
Y660353D01*
X252688Y658248D01*
Y636364D01*
G01X251278Y620788D02*
X256120D01*
G01D02*
X258514D01*
X261171Y623445D01*
X270305D01*
G01X248984Y633786D02*
Y628670D01*
G01X251278Y623938D02*
X247278D01*
G01X248984Y628670D02*
X247278Y626964D01*
Y623938D01*
G01X249867Y645941D02*
X250102Y646176D01*
Y650671D01*
G01Y653821D02*
Y656321D01*
G01X250583Y669913D02*
Y672788D01*
X251840Y674045D01*
Y675889D01*
G01X249461Y816300D02*
X250700Y817539D01*
Y819900D01*
G01X248461Y836800D02*
X252100D01*
G01X261023Y1116338D02*
X262893Y1118208D01*
G01X257283Y1112598D02*
X259153Y1114468D01*
G01X261023Y1112598D02*
X262893Y1114468D01*
G01X253543Y1116338D02*
X255413Y1118208D01*
G01X253543Y1112598D02*
X255413Y1114468D01*
G01X257283Y1116338D02*
X259153Y1118208D01*
G01X253543Y1217322D02*
X255413Y1215452D01*
G01X261023Y1217322D02*
X262893Y1215452D01*
G01X251673Y1211711D02*
X249803Y1213582D01*
G01X250876Y1532782D02*
X250900Y1532758D01*
Y1527800D01*
X250410Y1527310D01*
X248042D01*
G01X264822Y92874D02*
X269553D01*
G01D02*
Y95018D01*
X270947Y96412D01*
X279723D01*
X281384Y98073D01*
Y98198D01*
G01X278784Y435158D02*
X280478Y436852D01*
Y441873D01*
X283645Y445040D01*
X285831D01*
X286639Y444232D01*
X288416D01*
G01X278529Y440489D02*
Y441509D01*
X283615Y446595D01*
X288416D01*
G01Y448957D02*
X287363D01*
X285458Y448168D01*
X283368D01*
X280041Y444841D01*
X278827D01*
G01X270305Y453681D02*
X265211D01*
X265011Y453881D01*
G01X270305Y444232D02*
X263301D01*
G01X270305Y446595D02*
X265011D01*
G01X280500Y855639D02*
X277961Y853100D01*
X269700D01*
G01X280500Y865739D02*
X279161Y864400D01*
X275400D01*
G01X286300Y890839D02*
X278400D01*
G01X286300Y901139D02*
X284561Y899400D01*
X275400D01*
G01X282400Y936439D02*
X278739D01*
G01X268503Y1112598D02*
X270373Y1114468D01*
G01X272244Y1116338D02*
X274114Y1114468D01*
G01X275984Y1112598D02*
X277854Y1114468D01*
G01X274114Y1211712D02*
X272244Y1213582D01*
G01X277854Y1207972D02*
X275984Y1206102D01*
G01X270374Y1215452D02*
X268504Y1217322D01*
X268503D01*
G01X289797Y36735D02*
X287166Y34104D01*
Y31938D01*
X283794Y28566D01*
Y27156D01*
G01X294959Y24408D02*
X291333D01*
X290113Y23188D01*
G01X284666Y34068D02*
X281716Y31118D01*
Y25234D01*
X283794Y23156D01*
X290081D01*
X290113Y23188D01*
G01X294959Y29408D02*
X290758D01*
X289631Y28281D01*
G01D02*
X288506Y27156D01*
X286944D01*
G01X293930Y76587D02*
X296330D01*
G01X293930Y72615D02*
X293958Y72587D01*
X296330D01*
G01X285384Y98198D02*
X281384D01*
G01X290888Y97475D02*
X288388D01*
G01X290888Y105087D02*
Y100625D01*
G01X300291Y99259D02*
X296735D01*
X295369Y100625D01*
G01D02*
X290888D01*
G01X295948Y141247D02*
X293023D01*
G01X289873D02*
X286044D01*
G01X287642Y146461D02*
X287385Y146204D01*
Y143740D01*
G01D02*
X286044Y142399D01*
Y141247D01*
G01X282074Y151540D02*
Y147540D01*
G01X287642Y149414D02*
X285902D01*
X284765Y148277D01*
G01D02*
X284493D01*
X283756Y147540D01*
X282074D01*
G01X299535Y149768D02*
X299181Y149414D01*
X294728D01*
G01X299535Y152373D02*
X299529Y152367D01*
X294728D01*
G01X285490Y259535D02*
Y256303D01*
G01X280162Y265701D02*
X281490Y264373D01*
Y262685D01*
G01X290265Y266114D02*
Y264678D01*
X289490Y263903D01*
Y262685D01*
G01X285249Y265896D02*
Y264086D01*
X285490Y263845D01*
Y262685D01*
G01X283762Y269603D02*
Y267575D01*
X283066Y266879D01*
X281340D01*
X280162Y265701D01*
G01X287698Y269603D02*
Y268681D01*
X290265Y266114D01*
G01X281797Y281716D02*
X283762Y279751D01*
Y277477D01*
G01X287738Y281982D02*
X285730Y279974D01*
Y277477D01*
G01Y269603D02*
Y267599D01*
X285249Y267118D01*
Y265896D01*
G01X280543Y284908D02*
X284543D01*
G01D02*
Y283104D01*
X283155Y281716D01*
X281797D01*
G01X288543Y284908D02*
Y282787D01*
X287738Y281982D01*
G01X290090Y317873D02*
X290128Y317911D01*
X294841D01*
G01X299833Y316731D02*
X296021D01*
X294841Y317911D01*
G01X299833Y319290D02*
X296220D01*
X294841Y317911D01*
G01X311947Y342319D02*
X310882D01*
X307384Y345817D01*
Y348805D01*
X305966Y350223D01*
X291396D01*
G01X288416Y386772D02*
X294228D01*
X299000Y382000D01*
Y377912D01*
G01X288416Y389134D02*
X296366D01*
X299000Y386500D01*
G01X288416Y384410D02*
X292520D01*
G01X288416Y391496D02*
X298000D01*
G01X288416Y382047D02*
X295699D01*
G01X288416Y400945D02*
X293445D01*
X296000Y403500D01*
G01X288416Y396221D02*
X297397D01*
X299088Y397912D01*
G01X288416Y398583D02*
X294000D01*
G01X288416Y393858D02*
X292358D01*
G01X288416Y412756D02*
X294244D01*
X298000Y409000D01*
G01X282230Y458572D02*
X284198Y456604D01*
X286042D01*
X286603Y456043D01*
X288416D01*
G01Y451319D02*
X286511D01*
X285153Y449961D01*
X281688D01*
X280220Y448493D01*
G01X288416Y540335D02*
X310665D01*
G01X288416Y623445D02*
X302006D01*
X302539Y622912D01*
X310756D01*
G01X318462Y858900D02*
X286784D01*
G01D02*
X280389D01*
X280500Y858789D01*
G01X306966Y868900D02*
X287471D01*
G01D02*
X280489D01*
X280500Y868889D01*
G01X280600Y894200D02*
X286089D01*
X286300Y893989D01*
G01X279500Y904200D02*
X286211D01*
X286300Y904289D01*
G01X282300Y926339D02*
X279261D01*
G01X319462Y929400D02*
X288580D01*
G01X282300Y929489D02*
X288491D01*
X288580Y929400D01*
G01X307966Y939400D02*
X288084D01*
G01D02*
X287895Y939589D01*
X282400D01*
G01X283464Y1112598D02*
X285334Y1114468D01*
G01X279724Y1112598D02*
X281594Y1114468D01*
G01X283464Y1138779D02*
X285334Y1136909D01*
G01X294685Y1138779D02*
X292815Y1140649D01*
G01X283464Y1146259D02*
X281594Y1144389D01*
G01X283464Y1149999D02*
X285334Y1148129D01*
G01X287204Y1146259D02*
X285334Y1144389D01*
G01X287204Y1142519D02*
X289074Y1140649D01*
G01X283464Y1142519D02*
X285334Y1140649D01*
G01X287204Y1149999D02*
X289074Y1148129D01*
G01X294685Y1146259D02*
X292815Y1148129D01*
G01X294685Y1153740D02*
X292815Y1155610D01*
G01X285334Y1204232D02*
X287204Y1206102D01*
G01X281594Y1200491D02*
X283464Y1198621D01*
G01X285334Y1207972D02*
X283464Y1209842D01*
G01X285334Y1215452D02*
X287204Y1217322D01*
G01X285334Y1211712D02*
X287204Y1213582D01*
G01X281594Y1215452D02*
X279724Y1217322D01*
G01X283464Y1206102D02*
X281594Y1207972D01*
G01X283464Y1213582D02*
X281594Y1211712D01*
G01X310817Y60393D02*
X310770Y60440D01*
Y64722D01*
G01D02*
Y72967D01*
X307150Y76587D01*
X299480D01*
G01X307916Y60529D02*
Y64428D01*
X308210Y64722D01*
G01D02*
Y72689D01*
X306132Y74767D01*
X301660D01*
X299480Y72587D01*
G01X296285Y80581D02*
Y79618D01*
X299316Y76587D01*
X299480D01*
G01X296285Y68581D02*
Y69564D01*
X299308Y72587D01*
X299480D01*
G01X308338Y85731D02*
X308210Y85603D01*
Y81848D01*
G01X311892Y86046D02*
X310770Y84924D01*
Y81848D01*
G01X308895Y91951D02*
Y94351D01*
G01Y88801D02*
X308338Y88244D01*
Y85731D01*
G01X299742Y112083D02*
Y112402D01*
X301828Y114488D01*
G01X304031Y107921D02*
Y103621D01*
G01X295948Y141247D02*
X298748D01*
X299595Y140400D01*
X309597D01*
X311845Y142648D01*
X313367D01*
G01X305221Y158194D02*
Y148325D01*
X304721Y147825D01*
X300104D01*
X299535Y147256D01*
Y145768D01*
G01X311520Y147775D02*
X309387D01*
X309012Y148150D01*
X308180Y148980D01*
Y157370D01*
G01X318222Y130789D02*
X318331Y130898D01*
Y133400D01*
X318600Y133669D01*
Y135099D01*
X318331Y135368D01*
Y145177D01*
X316196Y147316D01*
X315737Y147775D01*
X311520D01*
G01X302685Y145768D02*
Y143868D01*
X302335Y143518D01*
X300435D01*
G01D02*
Y142392D01*
X300662Y142165D01*
X308965D01*
X311700Y144900D01*
X314599D01*
X315400Y144099D01*
Y140276D01*
X314819Y139695D01*
X313367D01*
G01X305221Y158194D02*
X305780Y158753D01*
Y158980D01*
X312344Y165544D01*
X339385D01*
X346735Y158194D01*
X455222D01*
G01X311520Y154865D02*
X316457D01*
G01X311520D02*
Y150925D01*
G01X299535Y152373D02*
Y149768D01*
G01X306471Y168665D02*
Y172665D01*
G01X300181Y179897D02*
Y176034D01*
X303550Y172665D01*
G01D02*
X306471D01*
G01X303487Y178560D02*
Y179904D01*
G01X306471Y176665D02*
Y180665D01*
G01X303487Y179904D02*
X304248Y180665D01*
X306471D01*
G01X303487Y179904D02*
Y180204D01*
X301825Y181866D01*
X300181D01*
G01X306471Y196665D02*
Y196783D01*
X304731Y198523D01*
X296954D01*
X295832Y197401D01*
Y194280D01*
X297622Y192490D01*
G01D02*
Y188362D01*
G01X300181Y183834D02*
X303377D01*
G01D02*
X305640D01*
X306471Y184665D01*
G01X302666Y196286D02*
X302850D01*
X306471Y192665D01*
G01D02*
X303832D01*
X302897Y191730D01*
Y190185D01*
G01D02*
X300181Y187469D01*
Y185803D01*
G01X309621Y196665D02*
X312264D01*
G01X309621Y192665D02*
X312264D01*
G01X309621Y188665D02*
X311646D01*
X312377Y187934D01*
Y186778D01*
G01D02*
Y185398D01*
X311644Y184665D01*
X309621D01*
G01X299516Y196286D02*
Y194157D01*
X300814Y192859D01*
G01X309716Y208864D02*
X312296D01*
G01X303667Y200864D02*
X306566D01*
G01X299792Y209229D02*
X300514D01*
X301102Y208641D01*
Y203429D01*
X303667Y200864D01*
G01X306566Y212864D02*
X306157Y212455D01*
X303756D01*
G01X299792Y213166D02*
X301478D01*
X302189Y212455D01*
X303756D01*
G01X306566Y204864D02*
Y208864D01*
G01X303690Y207037D02*
X305517Y208864D01*
X306566D01*
G01X299792Y211197D02*
X301245D01*
X303690Y208752D01*
Y207037D01*
G01X307937Y219379D02*
X307814D01*
X306566Y218131D01*
Y216864D01*
G01X299792Y217103D02*
X301805D01*
X306566Y221864D01*
G01D02*
Y225716D01*
X306563Y225719D01*
G01D02*
Y226629D01*
X308565Y228631D01*
G01X320801Y242078D02*
X313529D01*
X311041Y244566D01*
Y255458D01*
X314463Y258880D01*
X365073D01*
G01X307313Y319290D02*
X305290D01*
X304591Y318591D01*
Y313149D01*
X316776Y300964D01*
X336795D01*
X339624Y303793D01*
Y326604D01*
X349120Y336100D01*
G01X307313Y321849D02*
X312222D01*
X312263Y321890D01*
G01X303285Y344878D02*
X298189D01*
X297719Y344408D01*
Y339559D01*
G01D02*
Y337606D01*
X299001Y336324D01*
X310628D01*
G01X315510Y541912D02*
X313933Y540335D01*
X310665D01*
G01X310756Y622912D02*
X315510D01*
G01X302165Y1142519D02*
X304035Y1144389D01*
G01X302165Y1149999D02*
X304035Y1151869D01*
G01X305905Y1142519D02*
X307775Y1144389D01*
G01X305905Y1149999D02*
X307775Y1151869D01*
G01X298425Y1153740D02*
X296555Y1155610D01*
G01X313385Y1142519D02*
X311515Y1140649D01*
G01X313385Y1149999D02*
X311515Y1148129D01*
G01X313385Y1157480D02*
X311515Y1155610D01*
G01X322847Y19806D02*
X320795D01*
X320397Y19408D01*
X315825D01*
G01X325331Y11806D02*
Y15806D01*
G01X315825Y14408D02*
X321840D01*
G01D02*
X323238Y15806D01*
X325331D01*
G01X315825Y24408D02*
X320334D01*
X322113Y26187D01*
G01X325331Y31806D02*
Y27806D01*
G01X322113Y26187D02*
X323732Y27806D01*
X325331D01*
G01Y19806D02*
X322847D01*
G01X325331Y23806D02*
Y19806D01*
G01X313624Y81848D02*
Y82885D01*
X316751Y86012D01*
G01X312844Y91879D02*
Y94279D01*
G01X316751Y86012D02*
Y88824D01*
G01X311892Y86046D02*
X312844Y86998D01*
Y88729D01*
G01X318041Y113684D02*
Y110794D01*
X318031Y110784D01*
G01D02*
X316306Y109059D01*
Y107899D01*
G01X320306D02*
X324306D01*
G01X320009Y113684D02*
Y111534D01*
X320759Y110784D01*
X323031D01*
G01D02*
X324306Y109509D01*
Y107899D01*
G01X326385Y130903D02*
X326354Y130934D01*
Y134838D01*
G01X326385Y127753D02*
Y126313D01*
X327591Y125107D01*
G01X320009Y121558D02*
Y124163D01*
X320509Y124663D01*
X322610D01*
G01D02*
Y126008D01*
X322331Y126287D01*
Y127748D01*
G01X316073Y121558D02*
Y123126D01*
X314916Y124283D01*
X312522D01*
G01D02*
X312554Y124315D01*
Y127525D01*
X312331Y127748D01*
G01X318041Y121558D02*
Y123785D01*
X317588Y124879D01*
G01D02*
Y127005D01*
X318222Y127639D01*
G01X322432Y153296D02*
Y150265D01*
X323980Y148717D01*
X330105D01*
G01X326354Y138838D02*
X323954D01*
G01X326354Y134838D02*
Y138838D01*
G01X323954D02*
X320953D01*
X320453Y138338D01*
Y136742D01*
G01X316457Y154865D02*
X319301Y157709D01*
X325672D01*
X326172Y158209D01*
Y161958D01*
G01X325650Y232859D02*
Y232681D01*
X329685Y228646D01*
G01X327780Y242078D02*
X323951D01*
G01X325549Y247292D02*
X325292Y247035D01*
Y244571D01*
G01D02*
X323951Y243230D01*
Y242078D01*
G01X319981Y252371D02*
Y248371D01*
G01X325549Y250245D02*
X323809D01*
X322672Y249108D01*
G01D02*
X322400D01*
X321663Y248371D01*
X319981D01*
G01X312263Y318740D02*
Y314890D01*
G01X319427Y312849D02*
X317120D01*
X315079Y314890D01*
G01D02*
X312263D01*
G01Y321890D02*
Y324518D01*
G01D02*
X316589Y328844D01*
X320274D01*
G01X317416Y342319D02*
X311947D01*
G01X321416D02*
X317416D01*
G01X320274Y332584D02*
X315944D01*
G01X317416Y345469D02*
Y346588D01*
X316067Y347937D01*
G01X321416Y345469D02*
Y348015D01*
G01X342285Y555137D02*
Y552483D01*
X337102Y547300D01*
X334444D01*
X331865Y544721D01*
X319851D01*
X318660Y545912D01*
G01X315510D02*
Y541912D01*
G01X327456Y550065D02*
Y554802D01*
X328978Y556324D01*
X333684D01*
X336425Y559065D01*
Y560043D01*
G01X323285Y550137D02*
X325422Y548000D01*
X330400D01*
X332685Y550285D01*
Y551381D01*
G01X342285Y555137D02*
X346883D01*
X347819Y556073D01*
Y613727D01*
X334634Y626912D01*
X318660D01*
G01X315510D02*
Y622912D01*
G01X320866Y1138779D02*
X322736Y1136909D01*
G01X324606Y1138779D02*
X326476Y1136909D01*
G01X320866Y1146259D02*
X322736Y1144389D01*
G01X320866Y1153740D02*
X322736Y1151870D01*
G01X317125Y1142519D02*
X315255Y1140649D01*
G01X324606Y1146259D02*
X326476Y1144389D01*
G01X317125Y1149999D02*
X315255Y1148129D01*
G01X324606Y1153740D02*
X326476Y1151870D01*
G01X317125Y1157480D02*
X315255Y1155610D01*
G01X320866Y1161220D02*
X322736Y1159350D01*
G01X324606Y1161220D02*
X326476Y1159350D01*
G01X320866Y1176180D02*
X322736Y1174310D01*
G01X320866Y1183661D02*
X322736Y1181791D01*
G01X324606Y1176180D02*
X326476Y1174310D01*
G01X324606Y1183661D02*
X326476Y1181791D01*
G01X320866Y1191141D02*
X322736Y1189271D01*
G01X324606Y1191141D02*
X326476Y1189271D01*
G01X349074Y99961D02*
X344299D01*
X342134Y102126D01*
Y103411D01*
G01X339259Y97667D02*
X342528D01*
G01X349074Y97599D02*
X342596D01*
X342528Y97667D01*
G01X349074Y92874D02*
X340161D01*
X337924Y95111D01*
G01X342134Y103411D02*
X339057D01*
G01X335075Y102495D02*
Y106495D01*
G01X339057Y106561D02*
X342293D01*
G01X335075Y106495D02*
X338991D01*
X339057Y106561D01*
G01X332975Y143762D02*
X336205D01*
G01X330105Y148717D02*
X332258D01*
X332975Y148000D01*
Y146912D01*
G01X339287Y232984D02*
Y231180D01*
X338681Y230574D01*
Y227824D01*
G01D02*
Y227724D01*
X337169Y226212D01*
Y225055D01*
G01X335200D02*
Y229782D01*
X334426Y230556D01*
G01X331263Y225055D02*
Y227068D01*
X329685Y228646D01*
G01X340988Y241681D02*
Y244297D01*
G01X337838Y241681D02*
X337197Y241040D01*
Y233636D01*
X337849Y232984D01*
X339287D01*
G01X335052Y232959D02*
X334426Y232333D01*
Y230556D01*
G01X332635Y250245D02*
X337088D01*
X337442Y250599D01*
G01X332635Y253198D02*
Y256394D01*
G01D02*
X335167D01*
X337638Y253923D01*
Y250795D01*
X337442Y250599D01*
G01X342486Y382723D02*
X346486D01*
G01X385131Y487382D02*
Y541098D01*
X381511Y544718D01*
X335399D01*
G01X332685Y551381D02*
X337078D01*
G01X336425Y560043D02*
X338969D01*
X340725Y558287D01*
X342285D01*
G01D02*
Y562137D01*
G01X339251Y1138130D02*
X340252Y1137129D01*
X341748D01*
G01X335190Y1173065D02*
X333900Y1171775D01*
Y1138100D01*
X334871Y1137129D01*
X336755D01*
G01X341748Y1140279D02*
Y1141313D01*
X343073Y1142638D01*
X352073D01*
X352101Y1142666D01*
X352545D01*
G01X343826Y1153242D02*
Y1146095D01*
X343850Y1146071D01*
G01D02*
X341929D01*
X340500Y1147500D01*
G01X338707Y1153242D02*
X338700Y1153249D01*
Y1160200D01*
X339900Y1161400D01*
X342200D01*
G01D02*
X343100D01*
X343826Y1160674D01*
Y1153242D01*
G01X341266D02*
Y1150166D01*
X340700Y1149600D01*
X339800D01*
X336755Y1146555D01*
Y1143489D01*
G01D02*
Y1140279D01*
G01X342200Y1161400D02*
Y1162500D01*
X343826Y1164126D01*
Y1167808D01*
G01X341455Y1181970D02*
X340000Y1180515D01*
Y1174300D01*
X341266Y1173034D01*
Y1171956D01*
G01D02*
Y1167808D01*
G01X342298Y1190841D02*
Y1189235D01*
X343121Y1188412D01*
G01X342009Y1176100D02*
X342557D01*
X343600Y1177143D01*
Y1184600D01*
X344050Y1185050D01*
X345471D01*
G01X341455Y1185120D02*
Y1186283D01*
X339776Y1187962D01*
G01X338322Y1190895D02*
X338175D01*
X335502Y1188222D01*
G01X342152Y1203443D02*
X339540Y1200831D01*
Y1196894D01*
G01X342152Y1206593D02*
X343057D01*
X344178Y1205472D01*
Y1201109D01*
X342399Y1199330D01*
Y1198783D01*
G01D02*
Y1194392D01*
X342298Y1194291D01*
Y1193991D01*
G01X338322Y1194045D02*
X342244D01*
X342298Y1193991D01*
G01X349074Y88150D02*
X356171D01*
X358636Y90615D01*
G01X349074Y90512D02*
X353186D01*
X353324Y90650D01*
G01X353074Y95236D02*
X349074D01*
G01X349120Y336100D02*
X354385Y341365D01*
X369797D01*
X378848Y350416D01*
Y368687D01*
X381237Y371076D01*
G01X358486Y382723D02*
Y384123D01*
X359486Y385123D01*
G01X360480Y389013D02*
Y386117D01*
X359486Y385123D01*
G01X356543Y389013D02*
Y387971D01*
X355673Y387101D01*
X350768D01*
X349311Y385644D01*
G01D02*
X346486Y382819D01*
Y382723D01*
G01X350486D02*
X354486D01*
G01D02*
Y385123D01*
G01D02*
X356057D01*
X358512Y387578D01*
Y389013D01*
G01X358486Y379573D02*
X358491Y379568D01*
Y377173D01*
G01D02*
X360086D01*
X362486Y379573D01*
G01X347450Y454334D02*
X345050D01*
G01X356790Y456044D02*
X355150D01*
X353320Y454214D01*
G01D02*
X352152D01*
X352032Y454334D01*
X350600D01*
G01X356790Y454076D02*
Y453350D01*
X353663Y450223D01*
Y449045D01*
G01D02*
X352374Y450334D01*
X350600D01*
G01X356790Y458012D02*
X354685D01*
X353367Y459330D01*
G01D02*
X352371Y458334D01*
X350600D01*
G01X349748Y1137129D02*
Y1134729D01*
G01X357748D02*
Y1137129D01*
G01X353748Y1134729D02*
Y1137129D01*
G01X361748Y1140279D02*
X357748D01*
G01X358128Y1146842D02*
Y1140659D01*
X357748Y1140279D01*
G01X360877Y1157404D02*
X358128Y1154655D01*
Y1146842D01*
G01X349748Y1140279D02*
X345748D01*
G01X349748D02*
X353748D01*
G01X355568Y1146842D02*
Y1142099D01*
X353748Y1140279D01*
G01X354420Y1157544D02*
X355568Y1156396D01*
Y1146842D01*
G01X352714D02*
Y1142835D01*
X352545Y1142666D01*
G01X354420Y1157544D02*
X351992D01*
X350201Y1159335D01*
Y1170540D01*
X350781Y1171120D01*
G01X353931D02*
Y1173495D01*
X354414Y1173978D01*
Y1175090D01*
G01X353931Y1171120D02*
Y1168768D01*
X352931Y1167768D01*
G01X355568Y1163968D02*
Y1167231D01*
X355031Y1167768D01*
X352931D01*
G01X358128Y1163968D02*
Y1167590D01*
X357950Y1167768D01*
G01D02*
X357823Y1167895D01*
Y1170370D01*
G01D02*
Y1173487D01*
X358443Y1174107D01*
Y1174111D01*
G01X345631Y1174897D02*
Y1174519D01*
X346385Y1173765D01*
Y1167808D01*
G01X357796Y1188058D02*
X355398D01*
X354022Y1189434D01*
X349425D01*
X347792Y1191067D01*
X346227D01*
X346136Y1190976D01*
G01X357083Y1185205D02*
X354442D01*
G01X359761Y1185201D02*
X361792Y1187232D01*
Y1187310D01*
G01X348432Y1187215D02*
X350442Y1185205D01*
G01X354442Y1182055D02*
X350442D01*
G01X350414Y1178240D02*
X348626D01*
X348125Y1178741D01*
Y1180175D01*
G01D02*
Y1181255D01*
X348925Y1182055D01*
X350442D01*
G01X359761Y1182051D02*
X363692D01*
X363729Y1182088D01*
G01X354414Y1175090D02*
X350414D01*
G01X362282Y1174774D02*
X362062Y1174994D01*
X359326D01*
X358443Y1174111D01*
G01X345631Y1174897D02*
Y1181740D01*
X345471Y1181900D01*
G01X358400Y1198569D02*
Y1201011D01*
X358368Y1201043D01*
G01D02*
X358402Y1201077D01*
Y1203443D01*
G01X354400Y1198569D02*
Y1201041D01*
X354398Y1201043D01*
G01D02*
X354402Y1201047D01*
Y1203443D01*
G01X350402Y1201043D02*
Y1201151D01*
G01D02*
X350400Y1201149D01*
Y1198569D01*
G01X350402Y1201151D02*
Y1203443D01*
G01X346387Y1203405D02*
Y1199256D01*
G01X360523Y1192282D02*
X358648Y1190407D01*
X355534D01*
X354342Y1191599D01*
G01X351192D02*
X350009D01*
X347482Y1194126D01*
X346136D01*
G01X344444Y1211312D02*
X344868Y1211736D01*
X345577D01*
X348352Y1208961D01*
Y1198093D01*
X346075Y1195816D01*
Y1194187D01*
X346136Y1194126D01*
G01X351165Y1214986D02*
Y1215339D01*
X349276Y1217228D01*
G01D02*
X347967Y1218537D01*
X346694D01*
G01X355215Y1223170D02*
X356822Y1221563D01*
Y1220643D01*
G01X349523Y1221364D02*
X350471D01*
X351940Y1219895D01*
G01D02*
X353993Y1217842D01*
Y1217814D01*
G01X346387Y1206555D02*
Y1209369D01*
X344444Y1211312D01*
G01X352352Y1224193D02*
X354192D01*
X355215Y1223170D01*
G01X362479Y1226300D02*
X360553Y1228226D01*
X360273D01*
G01D02*
X356385D01*
X355181Y1227022D01*
G01X359651Y1223472D02*
Y1224427D01*
X358062Y1226016D01*
G01X367184Y92874D02*
X371915D01*
G01D02*
Y95018D01*
X373309Y96412D01*
X382085D01*
X383746Y98073D01*
Y98198D01*
G01X363007Y95236D02*
X367184D01*
G01Y99961D02*
X362957D01*
G01X371417Y353820D02*
X369500Y355737D01*
Y361528D01*
X370931Y362959D01*
Y364289D01*
G01X365559Y354300D02*
Y355360D01*
X367200Y357001D01*
Y376499D01*
X366526Y377173D01*
G01X373264Y379429D02*
Y375754D01*
G01X370931Y367439D02*
X370486Y367884D01*
Y377173D01*
G01X379461Y383732D02*
Y383478D01*
X379104Y383121D01*
X376956D01*
X373264Y379429D01*
G01X362449Y389013D02*
Y387599D01*
X362949Y387099D01*
X365986D01*
X366486Y386599D01*
Y385123D01*
G01D02*
Y382723D01*
G01X370486D02*
Y388006D01*
X370160Y388332D01*
Y391569D01*
G01D02*
X370157Y391572D01*
X365008D01*
G01X366486Y379573D02*
Y377213D01*
X366526Y377173D01*
G01X370486Y379573D02*
Y377173D01*
G01X364664Y456044D02*
X367554D01*
X367564Y456034D01*
G01D02*
X369289Y454309D01*
X370449D01*
G01X364664Y458012D02*
X366814D01*
X367564Y458762D01*
Y461034D01*
G01X370449Y458309D02*
Y462309D01*
G01X367564Y461034D02*
X368839Y462309D01*
X370449D01*
G01X376011Y745300D02*
X373400D01*
X372400Y746300D01*
G01X376025Y750000D02*
X372300D01*
G01X370415Y766108D02*
X370592D01*
X372200Y764500D01*
X374311D01*
G01X365850Y773950D02*
X370600Y778700D01*
Y782675D01*
X374325Y786400D01*
G01X374714Y790194D02*
X378472D01*
G01X363893Y943480D02*
Y946863D01*
G01X376007Y971812D02*
Y973596D01*
X375507Y974096D01*
X369531D01*
X366285Y970850D01*
Y952323D01*
X361796Y947834D01*
Y940718D01*
X362538Y939976D01*
X372857D01*
G01X367043Y943480D02*
X367375Y943812D01*
X370214D01*
G01X372857D02*
X370214D01*
G01X376007Y939976D02*
Y943812D01*
G01D02*
X380681D01*
X384856Y947987D01*
G01X376007Y947812D02*
X377966D01*
X379928Y949774D01*
G01X376007Y955812D02*
X376838Y956643D01*
X379245D01*
G01X376007Y963812D02*
Y959812D01*
G01D02*
X377476D01*
X377742Y960078D01*
Y960729D01*
X378875Y961862D01*
G01X372857Y947812D02*
X370214D01*
G01X370101Y953699D02*
Y952313D01*
X370602Y951812D01*
X372857D01*
G01Y955812D02*
X370602D01*
X370101Y955311D01*
Y953699D01*
G01X376007Y971812D02*
Y967812D01*
G01D02*
X378928D01*
G01X361748Y1137129D02*
Y1134856D01*
X361621Y1134729D01*
G01X365748Y1140279D02*
X361748D01*
G01X360877Y1157404D02*
X363605D01*
X368500Y1162299D01*
Y1172070D01*
X367870Y1172700D01*
X362898D01*
X360952Y1170754D01*
Y1170391D01*
X360973Y1170370D01*
G01X363729Y1185238D02*
X366429D01*
G01X363729Y1182088D02*
X365722D01*
X366222Y1181588D01*
Y1180235D01*
G01X362282Y1177924D02*
Y1178928D01*
X363589Y1180235D01*
X366222D01*
G01X362400Y1198569D02*
Y1200817D01*
X362402Y1200819D01*
Y1201039D01*
G01D02*
Y1203443D01*
G01X366402D02*
Y1200969D01*
G01D02*
Y1198571D01*
X366400Y1198569D01*
G01X388612Y31168D02*
X392821D01*
G01D02*
X400868D01*
X402866Y33166D01*
Y37718D01*
X400686Y39898D01*
G01X387948Y27288D02*
X389268Y28608D01*
X392821D01*
G01D02*
X401066D01*
X404686Y32228D01*
Y39898D01*
G01X387746Y98198D02*
X383746D01*
G01X393250Y97475D02*
X390750D01*
G01X387852Y259535D02*
Y256303D01*
G01X387611Y265896D02*
Y264086D01*
X387852Y263845D01*
Y262685D01*
G01X382524Y265701D02*
X383852Y264373D01*
Y262685D01*
G01X392627Y266114D02*
Y264678D01*
X391852Y263903D01*
Y262685D01*
G01X388092Y269603D02*
Y267599D01*
X387611Y267118D01*
Y265896D01*
G01X386124Y269603D02*
Y267575D01*
X385428Y266879D01*
X383702D01*
X382524Y265701D01*
G01X390060Y269603D02*
Y268681D01*
X392627Y266114D01*
G01X384159Y281716D02*
X386124Y279751D01*
Y277477D01*
G01X390100Y281982D02*
X388092Y279974D01*
Y277477D01*
G01X382905Y284908D02*
X386905D01*
G01D02*
Y283104D01*
X385517Y281716D01*
X384159D01*
G01X390905Y284908D02*
Y282787D01*
X390100Y281982D01*
G01X384173Y379028D02*
X385237Y377964D01*
Y376629D01*
G01X381237Y371076D02*
Y373479D01*
G01Y376629D02*
X377237D01*
Y376830D01*
G01X383398Y383732D02*
Y379803D01*
X384173Y379028D01*
G01X387335Y383732D02*
Y382742D01*
X388858Y381219D01*
X392609D01*
X394237Y379591D01*
G01X378875Y379088D02*
X377603D01*
X377237Y378722D01*
Y376830D01*
G01X381429Y383732D02*
Y381642D01*
X378875Y379088D01*
G01X388093Y474382D02*
Y470382D01*
G01X385634Y472020D02*
Y470748D01*
X386000Y470382D01*
X388093D01*
G01X380990Y474574D02*
X383080D01*
X385634Y472020D01*
G01X385293Y466409D02*
X388093D01*
G01X380990Y472606D02*
X381244D01*
X381601Y472249D01*
Y470101D01*
X385293Y466409D01*
G01X393646Y474382D02*
X391243D01*
G01X388093Y478382D02*
X386758D01*
X385694Y477318D01*
G01X380990Y476543D02*
X384919D01*
X385694Y477318D01*
G01X385131Y487382D02*
X388093D01*
G01X380990Y480480D02*
X381980D01*
X383503Y482003D01*
Y485754D01*
X385131Y487382D01*
G01X388093D02*
Y489224D01*
X388668Y489799D01*
X397156D01*
X426577Y477612D01*
X448700Y455489D01*
Y426755D01*
X446546Y424601D01*
X443748D01*
G01X379161Y745300D02*
X380361Y744100D01*
X383900D01*
G01D02*
X387836Y748036D01*
X390780D01*
G01Y750005D02*
X384600D01*
G01D02*
X379180D01*
X379175Y750000D01*
G01X390780Y771658D02*
X388458D01*
X382607Y765807D01*
Y764500D01*
G01D02*
X377461D01*
G01X393536Y780320D02*
Y781464D01*
X391600Y783400D01*
X390025D01*
X383200Y790225D01*
G01X377475Y786400D02*
X379075Y784800D01*
X383800D01*
X386500Y782100D01*
G01X390780Y777564D02*
X389616D01*
X386500Y780680D01*
Y782100D01*
G01X469300Y799500D02*
X436964D01*
X432564Y803900D01*
X389136D01*
X378580Y793344D01*
X378472D01*
G01Y790194D02*
X378580D01*
X378611Y790225D01*
X383200D01*
G01X398834Y860535D02*
X383462D01*
G01X398776Y868286D02*
X392770D01*
G01D02*
Y864433D01*
X392745Y864408D01*
G01X392770Y868286D02*
Y869582D01*
X392201Y870151D01*
X382675D01*
G01X379928Y949774D02*
Y952431D01*
X380386Y952889D01*
Y954131D01*
X380929Y954674D01*
X382297D01*
G01X378928Y967812D02*
X382297Y964443D01*
Y960580D01*
G01X379245Y956643D02*
X382297D01*
G01X378875Y961862D02*
Y960142D01*
X380406Y958611D01*
X382297D01*
G01X384856Y947987D02*
Y952115D01*
G01X378790Y1001083D02*
X378965Y1000908D01*
X418853D01*
X447261Y972500D01*
X497943D01*
X520343Y950100D01*
X551464D01*
X566683Y965319D01*
X573895D01*
G01X380280Y1006071D02*
X381914D01*
X383877Y1004108D01*
X420179D01*
X447124Y977163D01*
X489163D01*
G01X392234Y1364501D02*
X394184Y1362551D01*
X403649D01*
X412300Y1353900D01*
Y1342900D01*
X416900Y1338300D01*
X424600D01*
X429600Y1333300D01*
X450000D01*
X467400Y1315900D01*
X478112D01*
X487600Y1306412D01*
Y1302100D01*
G01X392234Y1369579D02*
X400221D01*
X415600Y1354200D01*
Y1342600D01*
X418000Y1340200D01*
X425388D01*
X430388Y1335200D01*
X450788D01*
X468188Y1317800D01*
X478900D01*
X490100Y1306600D01*
Y1302100D01*
G01X387592Y1543700D02*
X389811D01*
X391740Y1545629D01*
G01D02*
X394457D01*
X394711Y1545883D01*
X397498D01*
G01Y1543915D02*
X395126D01*
X391740Y1540529D01*
G01D02*
X390911Y1539700D01*
X387592D01*
G01Y1547700D02*
X388711D01*
X391740Y1550729D01*
G01D02*
X394617Y1547852D01*
X397498D01*
G01X387592Y1555700D02*
Y1559700D01*
G01Y1555700D02*
Y1551700D01*
G01D02*
X387611D01*
X391740Y1555829D01*
G01D02*
X394828Y1552741D01*
Y1550381D01*
X395388Y1549821D01*
X397498D01*
G01X396680Y43093D02*
X397663D01*
X400686Y40070D01*
Y39898D01*
G01X408680Y43093D02*
X407717D01*
X404686Y40062D01*
Y39898D01*
G01X400714Y45448D02*
X400686Y45420D01*
Y43048D01*
G01X404686Y45448D02*
Y43048D01*
G01X397731Y100625D02*
X399097Y99259D01*
X402653D01*
G01X402104Y112083D02*
Y112402D01*
X404190Y114488D01*
G01X406393Y107921D02*
Y103621D01*
G01X393250Y100625D02*
X397731D01*
G01X393250Y105087D02*
Y100625D01*
G01X408833Y168665D02*
Y172665D01*
G01X402543Y179897D02*
Y176034D01*
X405912Y172665D01*
G01D02*
X408833D01*
G01X405849Y178560D02*
Y179904D01*
G01X408833Y180665D02*
X406610D01*
X405849Y179904D01*
G01X408833Y176665D02*
Y180665D01*
G01X405849Y179904D02*
Y180204D01*
X404187Y181866D01*
X402543D01*
G01Y183834D02*
X405739D01*
G01D02*
X408002D01*
X408833Y184665D01*
G01Y196665D02*
X404704D01*
X404659Y196620D01*
G01X399984Y188362D02*
Y192490D01*
G01D02*
X401859Y194365D01*
X403961D01*
X404659Y195063D01*
Y196620D01*
G01X402543Y185803D02*
Y189278D01*
X403450Y190185D01*
X405259D01*
G01D02*
Y191730D01*
X406194Y192665D01*
X408833D01*
G01X401509Y196620D02*
X397488D01*
X395942Y195074D01*
Y192300D01*
G01X406029Y200864D02*
X408928D01*
G01X402154Y209229D02*
X402876D01*
X403464Y208641D01*
Y203429D01*
X406029Y200864D01*
G01X402154Y213166D02*
X403840D01*
X404551Y212455D01*
X406118D01*
G01X408928Y212864D02*
X408519Y212455D01*
X406118D01*
G01X408928Y204864D02*
Y208864D01*
G01X406052Y207037D02*
X407879Y208864D01*
X408928D01*
G01X402154Y211197D02*
X403607D01*
X406052Y208752D01*
Y207037D01*
G01X408925Y225719D02*
Y226629D01*
X410927Y228631D01*
G01X402154Y217103D02*
X404167D01*
X408928Y221864D01*
G01X408925Y225719D02*
Y221867D01*
X408928Y221864D01*
G01X410086Y336795D02*
X408337D01*
X407131Y335589D01*
G01Y331589D02*
X409655D01*
G01X403981D02*
X400993D01*
G01X403981Y335589D02*
X400993D01*
G01X398237Y376631D02*
X394237D01*
G01Y379591D02*
Y376631D01*
G01X398237Y373481D02*
X398935Y372783D01*
X420909D01*
X423331Y375205D01*
X438521D01*
X443748Y380432D01*
Y424601D01*
G01X399726Y467560D02*
X398239D01*
X395926Y469873D01*
X395200Y471624D01*
Y472828D01*
X393646Y474382D01*
G01X408758Y471560D02*
X406801D01*
X405801Y472560D01*
Y475560D01*
G01X402876Y471560D02*
Y467560D01*
G01X408758Y468607D02*
X406348D01*
X405301Y467560D01*
G01D02*
X402876D01*
G01Y479560D02*
Y475560D01*
G01X405801D02*
X402876D01*
G01X416200Y786700D02*
X414300D01*
X409284Y781684D01*
Y780320D01*
G01X411800Y790900D02*
Y786700D01*
X407316Y782216D01*
Y780320D01*
G01X401984Y860535D02*
Y864409D01*
G01X401926Y868286D02*
X405289D01*
X406770Y869767D01*
G01X410938Y872074D02*
X409077D01*
X406770Y869767D01*
G01X401984Y864409D02*
X401986Y864407D01*
X404468D01*
G01X410938Y870105D02*
X410148D01*
X406992Y866949D01*
Y866931D01*
X404468Y864407D01*
G01X397431Y870654D02*
X395999D01*
X395392Y871261D01*
Y872693D01*
G01X407540Y1446807D02*
X407970Y1447237D01*
Y1449751D01*
G01X407690Y1442942D02*
Y1446657D01*
X407540Y1446807D01*
G01X405461Y1563434D02*
Y1561059D01*
X405496Y1561024D01*
G01D02*
X406996Y1559524D01*
Y1553413D01*
G01X403059D02*
Y1555733D01*
X400558Y1558234D01*
X398086D01*
X395296Y1561024D01*
G01D02*
Y1562936D01*
X395794Y1563434D01*
X397461D01*
G01X401461D02*
Y1562089D01*
X400396Y1561024D01*
G01D02*
X405028Y1556392D01*
Y1553413D01*
G01X408964D02*
Y1559392D01*
X410596Y1561024D01*
G01X420050Y30483D02*
X422450D01*
G01X419978Y26534D02*
X422378D01*
G01X409947Y25754D02*
Y23469D01*
X410789Y22627D01*
G01D02*
X416923D01*
G01X414145Y27486D02*
X415097Y26534D01*
X416828D01*
G01X409947Y28608D02*
X413023D01*
X414145Y27486D01*
G01X413904Y32569D02*
X412503Y31168D01*
X409947D01*
G01X416900Y30483D02*
X416156Y31227D01*
X415246D01*
X413904Y32569D01*
G01X411983Y196665D02*
X414626D01*
G01X411983Y192665D02*
X414626D01*
G01X411983Y188665D02*
X414008D01*
X414739Y187934D01*
Y186778D01*
G01D02*
Y185398D01*
X414006Y184665D01*
X411983D01*
G01X412078Y208864D02*
X414658D01*
G01X410086Y336795D02*
X411643D01*
X414135Y339287D01*
X416886D01*
G01X409655Y331589D02*
Y333042D01*
X414326Y337713D01*
X416886D01*
G01X419839Y350114D02*
Y354263D01*
X416574Y357528D01*
G01D02*
Y359642D01*
X416318Y359898D01*
Y362074D01*
G01X411007Y356743D02*
Y351929D01*
X415775Y347161D01*
X416886D01*
G01X421413Y350114D02*
Y359053D01*
G01D02*
X420422Y360044D01*
Y362082D01*
G01X412318Y362074D02*
X416318D01*
G01X424479Y362082D02*
X420422D01*
G01X421726Y474560D02*
Y472060D01*
X421226Y471560D01*
X415844D01*
G01Y474513D02*
X418801D01*
G01D02*
X418848Y474560D01*
X421726D01*
G01X423064Y780320D02*
Y782936D01*
X422333Y783667D01*
X420034D01*
X419000Y784701D01*
Y789300D01*
X420400Y790700D01*
G01X423700Y795500D02*
Y797200D01*
X422211Y798689D01*
X420400D01*
G01X434100Y797400D02*
X429300Y802200D01*
X415611D01*
X412100Y798689D01*
G01X416200Y786700D02*
Y795525D01*
G01X420400Y790700D02*
Y795539D01*
G01X412100D02*
Y793903D01*
X411800Y793603D01*
Y790900D01*
G01X421200Y786400D02*
X424175Y789375D01*
X426000D01*
G01X430600Y797400D02*
X427300Y800700D01*
X418225D01*
X416200Y798675D01*
G01X421454Y1544625D02*
X419996D01*
X419286Y1543915D01*
X416494D01*
G01X424649Y1546372D02*
Y1545312D01*
X423962Y1544625D01*
X421454D01*
G01X416494Y1538009D02*
Y1534917D01*
X417050Y1534361D01*
X422539D01*
G01D02*
X424041Y1535863D01*
Y1537088D01*
G01X416494Y1541947D02*
X426701D01*
G01X410596Y1561024D02*
X409461Y1562159D01*
Y1563434D01*
G01X427378Y1555499D02*
X426679Y1556198D01*
X423171D01*
X422671Y1555698D01*
Y1553511D01*
X423578Y1552604D01*
X427096D01*
X427755Y1551945D01*
Y1550255D01*
X427711Y1550211D01*
G01X421461Y1566584D02*
X422591D01*
X424342Y1568335D01*
X439294D01*
X444036Y1563593D01*
Y1449487D01*
X449723Y1443800D01*
X722600D01*
X728495Y1437905D01*
X758027D01*
X760398Y1440276D01*
G01X417461Y1563434D02*
X421461D01*
G01X413461D02*
X417461D01*
G01X409461D02*
X413461D01*
G01X436045Y141247D02*
Y142399D01*
X437386Y143740D01*
G01D02*
X439874Y141252D01*
Y141247D01*
G01X437386Y143740D02*
Y146204D01*
X437643Y146461D01*
G01X432075Y151540D02*
Y147540D01*
G01X437643Y149414D02*
X435903D01*
X434766Y148277D01*
G01D02*
X434494D01*
X433757Y147540D01*
X432075D01*
G01X437161Y326886D02*
Y325562D01*
X437662Y325061D01*
X441296D01*
G01X435587Y326886D02*
Y323662D01*
X436666Y322583D01*
G01X427713Y326886D02*
Y321965D01*
G01X440114Y337713D02*
X443508D01*
G01X446566Y337917D02*
Y339085D01*
X446066Y339585D01*
X442550D01*
X442252Y339287D01*
X440114D01*
G01X426830Y359026D02*
X427833Y358023D01*
Y357249D01*
X430862Y354220D01*
Y350114D01*
G01X440538Y355372D02*
X437161Y351995D01*
Y350114D01*
G01X440598Y424601D02*
Y428101D01*
G01X429185Y438133D02*
X433023D01*
X436055Y435101D01*
X437835D01*
G01D02*
X440598D01*
G01Y428101D02*
Y431601D01*
G01X429086Y432227D02*
X431155D01*
X432270Y431112D01*
G01D02*
X435911D01*
X436400Y431601D01*
X440598D01*
G01X425641Y449550D02*
Y451981D01*
X426647Y452987D01*
G01X429673Y456026D02*
X425673D01*
G01X426647Y452987D02*
X425673Y453961D01*
Y456026D01*
G01X429673Y459176D02*
Y461607D01*
G01X438087Y639654D02*
X438773D01*
X439767Y640066D01*
X442089Y642388D01*
X443090Y642803D01*
X445642D01*
X446987Y643360D01*
G01X443433Y640876D02*
Y640584D01*
X441162Y638313D01*
G01X438087Y637685D02*
X440056D01*
X440872Y638023D01*
X441162Y638313D01*
G01X425820Y777564D02*
X431600D01*
G01D02*
Y780399D01*
X429999Y782000D01*
X427101D01*
X426000Y783101D01*
Y786225D01*
G01X426701Y1541947D02*
X427938D01*
X430044Y1544053D01*
X431741Y1548150D01*
Y1550066D01*
X431649Y1550158D01*
G01D02*
Y1552039D01*
X430754Y1552934D01*
Y1557301D01*
X434070Y1560617D01*
G01X427799Y1546372D02*
Y1550123D01*
X427711Y1550211D01*
G01X443024Y141247D02*
X445949D01*
G01X463368Y142648D02*
X461846D01*
X459698Y140500D01*
X449496D01*
X448749Y141247D01*
X445949D01*
G01X455222Y158194D02*
Y148325D01*
X454722Y147825D01*
X450105D01*
X449536Y147256D01*
Y145768D01*
G01X452686D02*
Y143868D01*
X452336Y143518D01*
X450436D01*
G01D02*
Y142392D01*
X450663Y142165D01*
X458866D01*
X461501Y144800D01*
X464900D01*
X465500Y144200D01*
Y140375D01*
X464820Y139695D01*
X463368D01*
G01X455222Y158194D02*
X455781Y158753D01*
Y158982D01*
X462343Y165544D01*
X489386D01*
X496735Y158195D01*
X557583D01*
X557584Y158194D01*
G01X444729Y149414D02*
X449182D01*
X449536Y149768D01*
G01X444729Y152367D02*
X449530D01*
X449536Y152373D01*
G01D02*
Y149768D01*
G01X453544Y468809D02*
X451144D01*
G01X459414Y468689D02*
X458246D01*
X458126Y468809D01*
X456694D01*
G01X459757Y463520D02*
X458468Y464809D01*
X456694D01*
G01X459461Y473805D02*
X458465Y472809D01*
X456694D01*
G01X460537Y501905D02*
Y500577D01*
X457617Y497657D01*
X454610D01*
G01Y493720D02*
X457878D01*
X459929Y491669D01*
G01X459952Y496842D02*
X458798Y495688D01*
X454610D01*
G01Y501594D02*
X455795D01*
X456620Y502419D01*
Y504509D01*
X459645Y507534D01*
Y509486D01*
G01X450397Y642588D02*
X448851D01*
X446987Y643360D01*
G01X456469Y638302D02*
X454491Y640280D01*
X448696D01*
X448100Y640876D01*
X446583D01*
G01X483059Y662649D02*
X473560Y653150D01*
Y643145D01*
X473003Y642588D01*
X453547D01*
G01X455667Y1047047D02*
X463188D01*
X467878Y1042357D01*
G01X455744Y1043140D02*
X460551D01*
X461897Y1041794D01*
G01X470307Y107899D02*
X474307D01*
G01D02*
Y109509D01*
X473032Y110784D01*
G01D02*
X470760D01*
X470010Y111534D01*
Y113684D01*
G01X468042D02*
Y110794D01*
X468032Y110784D01*
G01D02*
X466307Y109059D01*
Y107899D01*
G01X461521Y147754D02*
X465759D01*
X468332Y145177D01*
Y135300D01*
X468500Y135132D01*
Y133568D01*
X468332Y133400D01*
Y130898D01*
G01X466074Y121558D02*
Y123126D01*
X464917Y124283D01*
X462523D01*
G01D02*
X462555Y124315D01*
Y125971D01*
X464332Y127748D01*
G01X468042Y121558D02*
Y123785D01*
X467589Y124879D01*
G01D02*
Y127005D01*
X468332Y127748D01*
G01X470010Y121558D02*
Y124163D01*
X470510Y124663D01*
X472611D01*
G01D02*
Y126008D01*
X472332Y126287D01*
Y127748D01*
G01X472433Y153296D02*
Y150265D01*
X473981Y148717D01*
X480106D01*
G01X458181Y157370D02*
Y148980D01*
X459410Y147754D01*
X461521D01*
G01X476355Y138838D02*
X473955D01*
G01D02*
X470954D01*
X470454Y138338D01*
Y136742D01*
G01X461521Y150904D02*
Y154865D01*
G01D02*
X466458D01*
G01D02*
X469302Y157709D01*
X475673D01*
X476173Y158209D01*
Y161958D01*
G01X470802Y242078D02*
X463530D01*
X461900Y243708D01*
Y253401D01*
X462989Y254490D01*
X471424D01*
X472643Y255709D01*
X477751D01*
X480922Y258880D01*
X515074D01*
G01X477781Y242078D02*
X473952D01*
G01D02*
Y243230D01*
X475293Y244571D01*
G01X469982Y252371D02*
Y248371D01*
G01D02*
X471664D01*
X472401Y249108D01*
X472673D01*
G01D02*
X473810Y250245D01*
X475550D01*
G01X478382Y352495D02*
Y354111D01*
X477493Y355000D01*
X472001D01*
X470700Y353699D01*
Y342110D01*
X472610Y340200D01*
X486626D01*
X511790Y315036D01*
Y313804D01*
G01X467335Y359944D02*
X470078Y357201D01*
X476977D01*
X478485Y358709D01*
Y360089D01*
G01X469530Y366754D02*
X469684Y366600D01*
X478084D01*
X478485Y366199D01*
Y364589D01*
G01X462884Y470519D02*
X461244D01*
X459414Y468689D01*
G01X459757Y463520D02*
X461134Y464897D01*
Y467963D01*
X461722Y468551D01*
X462884D01*
G01X473658Y470509D02*
X473648Y470519D01*
X470758D01*
G01X476543Y468784D02*
X475383D01*
X473658Y470509D01*
G01X462884Y472487D02*
X460779D01*
X459461Y473805D01*
G01X470758Y472487D02*
X472908D01*
X473658Y473237D01*
Y475509D01*
G01X476543Y476784D02*
X474933D01*
X473658Y475509D01*
G01X465978Y499669D02*
X468558D01*
G01X460537Y501905D02*
Y503125D01*
X461081Y503669D01*
X462828D01*
G01X459929Y491669D02*
X462828D01*
G01Y499669D02*
Y495669D01*
G01X459952Y496842D02*
X461125Y495669D01*
X462828D01*
G01Y516609D02*
Y512669D01*
G01X459645Y509486D02*
X462828Y512669D01*
G01X473133Y1007854D02*
Y1003467D01*
X473778Y1002822D01*
Y997682D01*
X472148Y996052D01*
G01X471443Y1001144D02*
X471558Y1001258D01*
Y1007854D01*
G01Y1026752D02*
Y1029482D01*
G01X473639Y1030952D02*
Y1028854D01*
X473133Y1028348D01*
Y1026752D01*
G01X467878Y1042357D02*
X469394Y1043873D01*
X471454D01*
X476658Y1038669D01*
Y1028343D01*
X476282Y1027433D01*
Y1026752D01*
G01X474708D02*
Y1027880D01*
X475500Y1028672D01*
Y1038035D01*
X472049Y1041486D01*
X470834D01*
X469160Y1039812D01*
X466688D01*
X464706Y1041794D01*
X461897D01*
G01X489260Y97667D02*
X492529D01*
G01X499075Y92874D02*
X490162D01*
X487925Y95111D01*
G01X489058Y103411D02*
X492135D01*
G01X485076Y102495D02*
Y106495D01*
G01X489058Y106561D02*
X492294D01*
G01X485076Y106495D02*
X488992D01*
X489058Y106561D01*
G01X476386Y130903D02*
X476355Y130934D01*
Y134838D01*
G01X476386Y127753D02*
Y126313D01*
X477592Y125107D01*
G01X482976Y143762D02*
X486206D01*
G01X480106Y148717D02*
X482259D01*
X482976Y148000D01*
Y146912D01*
G01X476355Y134838D02*
Y138838D01*
G01X485201Y225055D02*
Y229782D01*
X484427Y230556D01*
G01X489288Y232984D02*
Y231180D01*
X488682Y230574D01*
Y227824D01*
G01D02*
Y227724D01*
X487170Y226212D01*
Y225055D01*
G01X479686Y228646D02*
X475651Y232681D01*
Y232859D01*
G01X481264Y225055D02*
Y227068D01*
X479686Y228646D01*
G01X485053Y232959D02*
X484427Y232333D01*
Y230556D01*
G01X487839Y241681D02*
X487198Y241040D01*
Y233636D01*
X487850Y232984D01*
X489288D01*
G01X475293Y244571D02*
Y247035D01*
X475550Y247292D01*
G01X482636Y250245D02*
X487089D01*
X487443Y250599D01*
G01X482636Y253198D02*
Y256394D01*
G01D02*
X485168D01*
X487639Y253923D01*
Y250795D01*
X487443Y250599D01*
G01X478382Y347995D02*
Y344855D01*
X480806Y342431D01*
X487931D01*
X514769Y315593D01*
Y312953D01*
G01X478382Y352495D02*
X485232D01*
G01X485335Y360089D02*
X478485D01*
G01X485232Y347995D02*
X478382D01*
G01X488382Y352495D02*
Y354926D01*
X490567Y357111D01*
X492817D01*
G01X496023Y362913D02*
X493905D01*
X491081Y360089D01*
X488485D01*
G01X488382Y347995D02*
X491043D01*
X491843Y348795D01*
Y351089D01*
G01X485335Y373589D02*
X481724D01*
G01D02*
X478485D01*
G01X485335Y369089D02*
X481724D01*
G01D02*
X478485D01*
G01X485335Y364589D02*
X478485D01*
G01X488485Y373589D02*
X490885D01*
G01X488485Y369089D02*
X488846Y369450D01*
X497048D01*
G01X488485Y364589D02*
X490219D01*
X491053Y365423D01*
G01X478485Y391589D02*
X481010Y394114D01*
X487792D01*
X488485Y393421D01*
Y391589D01*
G01D02*
X491289D01*
G01X488485Y387089D02*
X495004D01*
X495203Y386890D01*
G01X478485Y387089D02*
X480455Y389059D01*
X488116D01*
X488485Y388690D01*
Y387089D01*
G01X485335Y382589D02*
X481724D01*
G01D02*
X478485D01*
G01Y378089D02*
X481724D01*
G01D02*
X485335D01*
G01X488485D02*
X488696Y378300D01*
X493514D01*
X494283Y377531D01*
X495750D01*
G01X490885Y382570D02*
X490746D01*
X490727Y382589D01*
X488485D01*
G01Y415492D02*
X485985D01*
X485485Y415992D01*
Y421374D01*
G01X488438D02*
Y418417D01*
G01D02*
X488485Y418370D01*
Y415492D01*
G01X481485Y437492D02*
Y439900D01*
G01X485485Y434342D02*
X481485D01*
G01X482532Y428460D02*
Y430870D01*
X481485Y431917D01*
G01D02*
Y434342D01*
G01X493485D02*
X489485D01*
G01X485485Y428460D02*
Y430417D01*
X486485Y431417D01*
X489485D01*
G01D02*
Y434342D01*
G01X476543Y472784D02*
Y476784D01*
G01X488635Y531726D02*
X491818Y534909D01*
G01X488635Y527726D02*
Y531726D01*
G01X485485Y527726D02*
X482905D01*
G01X485485Y544726D02*
X482905D01*
G01X488635Y552726D02*
X491534D01*
G01X488635Y548726D02*
X490874D01*
X491511Y548089D01*
Y546553D01*
G01X488635Y544726D02*
Y548726D01*
G01Y540726D02*
X489044Y541135D01*
X491445D01*
G01X487203Y625311D02*
X484772D01*
G01X490353D02*
Y621311D01*
G01X493392Y622285D02*
X492418Y621311D01*
X490353D01*
G01X486623Y655447D02*
X484097Y652921D01*
X483588D01*
X483573Y652906D01*
X481937D01*
G01X478831Y648968D02*
X478787Y649012D01*
Y652906D01*
G01X488765Y667224D02*
Y671200D01*
G01X486623Y655447D02*
X488765Y657589D01*
Y663326D01*
G01X481742Y657477D02*
X478787Y654522D01*
Y652906D01*
G01X488745Y677342D02*
Y671220D01*
X488765Y671200D01*
G01X488091Y992191D02*
Y990550D01*
X487091Y989550D01*
G01D02*
Y986528D01*
X521353Y952266D01*
G01X482582Y1007854D02*
Y1006406D01*
X483297Y1005691D01*
X487727D01*
X491006Y1002412D01*
Y1000497D01*
G01X484944Y1011791D02*
X487959D01*
X495574Y1004176D01*
G01X481007Y1007854D02*
Y1005950D01*
X483378Y1003579D01*
Y1002585D01*
X484497Y1001466D01*
G01X488091Y995341D02*
Y997872D01*
X484497Y1001466D01*
G01X484944Y1010216D02*
X485898D01*
X498524Y997590D01*
G01X477248Y1001052D02*
X475983Y1002317D01*
Y1005083D01*
X476022Y1005122D01*
Y1005136D01*
X476282Y1005396D01*
Y1007854D01*
G01X474708D02*
Y1003692D01*
X474913Y1003487D01*
Y998387D01*
X477248Y996052D01*
G01X484944Y1016516D02*
X493017D01*
X495663Y1015420D01*
G01X492042Y1020491D02*
X489718Y1022815D01*
X484944D01*
G01Y1018090D02*
X496761D01*
X498585Y1016266D01*
G01X484944Y1014941D02*
X492260D01*
X498435Y1008766D01*
G01X484944Y1024390D02*
X495404D01*
X497073Y1026059D01*
G01X484944Y1013366D02*
X490244D01*
X491647Y1011963D01*
G01X484944Y1021240D02*
X487241D01*
X488041Y1020440D01*
G01X484944Y1019665D02*
X487266D01*
X488041Y1020440D01*
G01X499075Y99961D02*
X494300D01*
X492135Y102126D01*
Y103411D01*
G01X499075Y97599D02*
X492597D01*
X492529Y97667D01*
G01X499075Y90512D02*
X503187D01*
X503325Y90650D01*
G01X499075Y88150D02*
X506172D01*
X508637Y90615D01*
G01X503075Y95236D02*
X499075D01*
G01X490989Y241681D02*
Y244297D01*
G01X492817Y357111D02*
X493211D01*
X497873Y361773D01*
X501821D01*
G01X491843Y351089D02*
X494789Y354035D01*
Y355549D01*
X498454Y359214D01*
X501821D01*
G01X490885Y373589D02*
X491973D01*
X493552Y372010D01*
X501821D01*
G01X497048Y369450D02*
X501821D01*
G01X495750Y377531D02*
Y375857D01*
X497038Y374569D01*
X501821D01*
G01X491053Y365423D02*
X492521Y366891D01*
X501821D01*
G01X496023Y362913D02*
X497442Y364332D01*
X501821D01*
G01X491289Y391589D02*
X494809D01*
X497082Y389316D01*
Y385489D01*
X497766Y384805D01*
X501821D01*
G01X495203Y386890D02*
Y385012D01*
X497969Y382246D01*
X501821D01*
G01X490885Y382570D02*
X493580D01*
X499022Y377128D01*
X501821D01*
G01Y379687D02*
X506500D01*
G01X503729Y445494D02*
X501441D01*
X500729Y446206D01*
Y451376D01*
G01X503682D02*
Y448419D01*
G01D02*
X503729Y448372D01*
Y445494D01*
G01X496729Y467494D02*
Y470419D01*
G01X500729Y464344D02*
X496729D01*
G01X497776Y458462D02*
Y460872D01*
X496729Y461919D01*
G01D02*
Y464344D01*
G01X508729D02*
X504729D01*
G01X500729Y458462D02*
Y460419D01*
X501729Y461419D01*
X504729D01*
G01D02*
Y464344D01*
G01X501224Y492050D02*
Y491327D01*
X498466Y488569D01*
Y487982D01*
G01Y478982D02*
X501649Y482165D01*
G01X505240Y489743D02*
X504356D01*
X502900Y488287D01*
Y483416D01*
X501649Y482165D01*
G01X495316Y491982D02*
X492736D01*
G01X501224Y492050D02*
X502854Y493680D01*
X505240D01*
G01X500890Y500202D02*
X498686D01*
X498466Y499982D01*
G01X505240Y497617D02*
X505037D01*
X502452Y500202D01*
X500890D01*
G01X498466Y491982D02*
Y495982D01*
G01D02*
X500338D01*
X500671Y495649D01*
X502225D01*
X502493Y495917D01*
G01D02*
X502761Y495649D01*
X505240D01*
G01X495409Y536487D02*
X493396D01*
X491818Y534909D01*
G01X495409Y544361D02*
X494687D01*
X494099Y544949D01*
Y550161D01*
X491534Y552726D01*
G01X495409Y542393D02*
X493956D01*
X491511Y544838D01*
Y546553D01*
G01X495409Y540424D02*
X493665D01*
X492954Y541135D01*
X491445D01*
G01X493392Y622285D02*
X494398Y621279D01*
X496829D01*
G01X496070Y665976D02*
X493883Y668163D01*
Y671200D01*
G01X499263Y665627D02*
X502678Y662212D01*
Y660441D01*
G01X499263Y665627D02*
Y663127D01*
X497184Y661048D01*
X494624D01*
X493883Y661789D01*
Y663326D01*
G01X499528Y660441D02*
Y657843D01*
G01D02*
Y655226D01*
X499605Y655149D01*
G01X493914Y677360D02*
Y671231D01*
X493883Y671200D01*
G01X493091Y989550D02*
X496684Y980876D01*
X522566Y954994D01*
X525074D01*
X527879Y952189D01*
G01X501082Y992756D02*
X501174Y992664D01*
X502802D01*
X502894Y992756D01*
X509065D01*
X509163Y992854D01*
X522544D01*
G01X510695Y969933D02*
X510233D01*
X508084Y972082D01*
Y977565D01*
X506702Y978947D01*
G01X501082Y989606D02*
X499689Y988213D01*
Y981790D01*
X502746Y978733D01*
X506488D01*
X506702Y978947D01*
G01X492091Y992191D02*
Y990550D01*
X493091Y989550D01*
G01X505019Y989235D02*
X504618D01*
X501847Y986464D01*
Y983478D01*
X503933Y981392D01*
G01X510647Y973885D02*
Y975647D01*
X511200Y976200D01*
X515100D01*
X515900Y977000D01*
Y978600D01*
X515100Y979400D01*
X508910D01*
X506845Y981465D01*
X504006D01*
X503933Y981392D01*
G01X498435Y1008766D02*
X501016D01*
G01X492091Y995341D02*
X491006Y996426D01*
Y1000497D01*
G01X495574Y1004176D02*
X498984Y1000766D01*
X501016D01*
G01X508515Y998813D02*
X501729D01*
X501016Y999526D01*
Y1000766D01*
G01X509016Y1004766D02*
Y1003480D01*
X508209Y1002673D01*
X503182D01*
X501089Y1004766D01*
X501016D01*
G01X491647Y1011963D02*
X498844Y1004766D01*
X501016D01*
G01X498524Y997590D02*
X499348Y996766D01*
X501016D01*
G01X495663Y1015420D02*
X498817Y1012266D01*
X501016D01*
G01X492042Y1020491D02*
X492275Y1020258D01*
X500883D01*
G01X501016Y1016266D02*
Y1014753D01*
X501516Y1014253D01*
X508591D01*
X509016Y1014678D01*
Y1016266D01*
G01X498585D02*
X501016D01*
G01X497073Y1026059D02*
X500906Y1029892D01*
Y1030656D01*
X501016Y1030766D01*
G01X509016D02*
Y1032518D01*
X508297Y1033237D01*
X501738D01*
X501016Y1032515D01*
Y1030766D01*
G01X533747Y98198D02*
Y98073D01*
X532086Y96412D01*
X523310D01*
X521916Y95018D01*
Y92874D01*
G01D02*
X517185D01*
G01Y99961D02*
X512958D01*
G01X513008Y95236D02*
X517185D01*
G01X512943Y443071D02*
X512845Y442973D01*
Y440069D01*
G01X516845D02*
X520845D01*
G01X520823Y442603D02*
X520845Y442581D01*
Y440069D01*
G01X518240Y448557D02*
Y445505D01*
X515806Y443071D01*
X512943D01*
G01X513310Y462004D02*
X516272Y459042D01*
Y456431D01*
G01X520208Y448557D02*
Y445560D01*
X520823Y444945D01*
Y442603D01*
G01X522756Y461818D02*
Y460694D01*
X520208Y458146D01*
Y456431D01*
G01X518240Y459371D02*
Y456431D01*
G01X517310Y467634D02*
Y470045D01*
G01X513310Y464484D02*
Y462004D01*
G01X521310Y464484D02*
X522756Y463038D01*
Y461818D01*
G01X517310Y464484D02*
Y460301D01*
X518240Y459371D01*
G01X516770Y599650D02*
Y594976D01*
X520945Y590801D01*
G01D02*
X525073D01*
G01X520770Y602800D02*
Y605443D01*
G01X516770Y602800D02*
Y605443D01*
G01X527632Y593360D02*
Y594108D01*
X526890Y594850D01*
X523050D01*
X520770Y597130D01*
G01D02*
Y599650D01*
G01X514778Y636236D02*
Y632038D01*
X515267Y631549D01*
Y627908D01*
G01X518278Y636236D02*
X514778D01*
G01X521778D02*
X518278D01*
G01X515267Y627908D02*
X514152Y626793D01*
Y624724D01*
G01X508246Y624823D02*
Y628661D01*
X511278Y631693D01*
Y633473D01*
G01D02*
Y636236D01*
G01X521778Y639386D02*
Y642184D01*
G01X517603Y690553D02*
X518299Y692384D01*
G01X519571Y690553D02*
X520799Y692384D01*
G01X521540Y688584D02*
Y686319D01*
G01X517603Y708269D02*
X518389Y706388D01*
G01X524598Y753387D02*
Y750693D01*
X523348Y749443D01*
X518782D01*
G01Y754155D02*
Y749443D01*
G01X508833Y765565D02*
Y764039D01*
X510890Y761982D01*
X513504D01*
G01X508833Y765565D02*
X510227Y766959D01*
X513907D01*
X514635Y767687D01*
Y769259D01*
G01X509096Y758865D02*
X513471D01*
X513504Y758832D01*
G01D02*
Y755804D01*
G01X524319Y758806D02*
X523353D01*
X518782Y754235D01*
Y754155D01*
G01X519753Y777133D02*
Y774469D01*
X520833Y773389D01*
G01X519753Y777133D02*
Y786145D01*
X519763Y786155D01*
G01X514635Y777133D02*
Y774287D01*
X513551Y773203D01*
G01X514576Y786228D02*
X515269Y785535D01*
Y781784D01*
X514635Y781150D01*
Y777133D01*
G01X519753Y769259D02*
Y770698D01*
X520369Y771314D01*
X525729D01*
X526210Y770833D01*
Y768013D01*
G01X526897Y799071D02*
X521680D01*
X519891Y797282D01*
Y795848D01*
G01X520741Y805149D02*
Y802907D01*
X522609Y801039D01*
X526897D01*
G01Y803008D02*
X523600D01*
X522741Y803867D01*
Y805910D01*
X521321Y807330D01*
X514549D01*
X507095Y814784D01*
G01X524741Y845149D02*
Y834149D01*
X520146Y829554D01*
Y823493D01*
X520539Y823100D01*
X521300D01*
X521600Y822800D01*
X522413D01*
X524489Y820724D01*
X526897D01*
G01X516074Y875295D02*
X519419D01*
X520870Y874694D01*
G01X515444Y870295D02*
X508904D01*
X508248Y870951D01*
Y873319D01*
G01X515444Y905295D02*
X509017D01*
G01X513797Y973885D02*
X517412D01*
X521762Y978235D01*
X686052D01*
X740507Y1032690D01*
X819744D01*
X840935Y1011499D01*
G01X513845Y969933D02*
X518007D01*
X524542Y976468D01*
X687602D01*
X741096Y1029962D01*
X816658D01*
X837267Y1009353D01*
X841673D01*
X844058Y1011738D01*
G01X532868Y992854D02*
X522544D01*
G01X521372Y982854D02*
X514550D01*
X512232Y985172D01*
G01D02*
X508169Y989235D01*
G01X509016Y996766D02*
Y998312D01*
X508515Y998813D01*
G01X509016Y1000766D02*
Y999314D01*
X508515Y998813D01*
G01X512166Y996766D02*
X514690D01*
G01X512166Y1004766D02*
X514690D01*
G01X509016Y1016266D02*
Y1020266D01*
G01X512166D02*
X514649D01*
G01X512166Y1030766D02*
X514843D01*
G01X519500Y1028377D02*
X548144D01*
G01X537747Y98198D02*
X533747D01*
G01X542236Y141247D02*
X538407D01*
G01D02*
Y142399D01*
X539748Y143740D01*
G01X534437Y151540D02*
Y147540D01*
G01X540005Y149414D02*
X538265D01*
X537128Y148277D01*
G01D02*
X536856D01*
X536119Y147540D01*
X534437D01*
G01X537853Y259535D02*
Y256303D01*
G01X532525Y265701D02*
X533853Y264373D01*
Y262685D01*
G01X537612Y265896D02*
Y264086D01*
X537853Y263845D01*
Y262685D01*
G01X534160Y281716D02*
X536125Y279751D01*
Y277477D01*
G01X540101Y281982D02*
X538093Y279974D01*
Y277477D01*
G01X536125Y269603D02*
Y267575D01*
X535429Y266879D01*
X533703D01*
X532525Y265701D01*
G01X538093Y269603D02*
Y267599D01*
X537612Y267118D01*
Y265896D01*
G01X532906Y284908D02*
X536906D01*
G01D02*
Y283104D01*
X535518Y281716D01*
X534160D01*
G01X535611Y359223D02*
X535277Y359557D01*
X532659D01*
G01D02*
X532059D01*
X527284Y364332D01*
X523869D01*
G01X535611Y345723D02*
X531966D01*
X526388Y351301D01*
G01D02*
X526900Y351813D01*
Y356155D01*
X526400Y356655D01*
X523869D01*
G01X535611Y354723D02*
X533912D01*
X533461Y354272D01*
X531612D01*
G01D02*
Y356788D01*
X526627Y361773D01*
X523869D01*
G01X535611Y350223D02*
X534211D01*
X533045Y349057D01*
X531636D01*
G01D02*
X529000Y351693D01*
Y356900D01*
X526686Y359214D01*
X523869D01*
G01X538761Y350223D02*
X545611D01*
G01X538761Y359223D02*
X545611D01*
G01X538761Y345723D02*
X545611D01*
G01X538761Y354723D02*
X545611D01*
G01X535611Y368223D02*
X529753D01*
X528812Y369164D01*
G01D02*
X527411D01*
X527125Y369450D01*
X523869D01*
G01X533211Y364746D02*
X533275D01*
X534298Y363723D01*
X535611D01*
G01X533211Y364746D02*
X531469Y366488D01*
X528090D01*
X527687Y366891D01*
X523869D01*
G01X535611Y372723D02*
X534744Y371856D01*
X533115D01*
G01D02*
X532961Y372010D01*
X523869D01*
G01Y374569D02*
X528651D01*
X530144Y376062D01*
G01D02*
X531305Y377223D01*
X535611D01*
G01X538761Y368223D02*
X545611D01*
G01X538761Y363723D02*
X545611D01*
G01X538761Y372723D02*
X545611D01*
G01X535611Y381723D02*
X534637Y380749D01*
X531953D01*
G01D02*
X531653D01*
X528032Y377128D01*
X523869D01*
G01X545611Y381723D02*
X544378D01*
X542301Y383800D01*
X536354D01*
X535611Y383057D01*
Y381723D01*
G01X538761Y390723D02*
X540548D01*
X542034Y392209D01*
G01X538761Y386223D02*
X541706D01*
G01X523869Y382246D02*
X527516D01*
X529667Y384397D01*
Y387201D01*
X533189Y390723D01*
G01D02*
X535611D01*
G01X523869Y379687D02*
X527553D01*
X531953Y384087D01*
Y385749D01*
G01D02*
X533781D01*
X534255Y386223D01*
X535611D01*
G01X538761Y377223D02*
X545611D01*
G01X536770Y599650D02*
Y597282D01*
X536270Y596782D01*
X534820D01*
G01X532770Y599650D02*
X536770D01*
G01X534820Y596782D02*
X533100D01*
X531569Y595251D01*
Y593360D01*
G01X533538D02*
X537401D01*
X540770Y596729D01*
G01X528770Y599650D02*
X529601Y598819D01*
Y596089D01*
G01D02*
Y593360D01*
G01X524770Y602800D02*
X528770D01*
G01X524770D02*
Y605637D01*
G01X531382Y696458D02*
X529493Y697443D01*
G01X531382Y702364D02*
Y702142D01*
X529493Y700253D01*
Y699943D01*
G01X525477Y690553D02*
X524493Y692443D01*
G01X525477Y708269D02*
X523929Y706388D01*
G01X533351Y702364D02*
X536087D01*
G01X537944Y760782D02*
X538449D01*
X542430Y764763D01*
Y769954D01*
X540908Y771476D01*
X538530D01*
X537578Y772428D01*
G01X524319Y761956D02*
X526210Y763847D01*
Y768013D01*
G01X534624Y774889D02*
Y776990D01*
X535599Y777965D01*
Y779889D01*
G01X534624Y774889D02*
X534861D01*
X537322Y772428D01*
X537578D01*
G01X536641Y789327D02*
Y784373D01*
X535599Y783331D01*
Y779889D01*
G01X538609Y789327D02*
Y785873D01*
X539449Y785033D01*
Y782389D01*
G01X544741Y823149D02*
X542741D01*
X534672Y831218D01*
Y834405D01*
G01D02*
Y836629D01*
X532261Y839040D01*
Y840700D01*
G01X537300Y842900D02*
X535200Y845000D01*
X533299D01*
X531550Y843251D01*
X531350D01*
X529111Y841012D01*
Y840700D01*
G01X552389Y834405D02*
Y837400D01*
X551889Y837900D01*
X545200D01*
X539900Y843200D01*
Y845900D01*
X538000Y847800D01*
X533392D01*
X530741Y845149D01*
G01X576378Y961807D02*
X581266D01*
X583416Y963957D01*
Y967485D01*
X582101Y968800D01*
X537545D01*
X530473Y961728D01*
G01X541766Y1012213D02*
X539616D01*
X536799Y1009396D01*
X536715D01*
G01X548648Y68581D02*
Y69564D01*
X551671Y72587D01*
X551843D01*
G01X560573Y64722D02*
Y72527D01*
X558333Y74767D01*
X554023D01*
X551843Y72587D01*
G01X548648Y80581D02*
Y79618D01*
X551679Y76587D01*
X551843D01*
G01D02*
X559513D01*
X563133Y72967D01*
Y64722D01*
G01X546293Y76587D02*
X548693D01*
G01X546293Y72615D02*
X546321Y72587D01*
X548693D01*
G01X547732Y100625D02*
X549098Y99259D01*
X552654D01*
G01X543251Y97475D02*
X540751D01*
G01X552105Y112083D02*
Y112402D01*
X554191Y114488D01*
G01X543251Y105087D02*
Y100625D01*
G01D02*
X547732D01*
G01X545386Y141247D02*
X548311D01*
G01X565730Y142648D02*
X564348D01*
X562000Y140300D01*
X552058D01*
X551111Y141247D01*
X548311D01*
G01X551898Y145768D02*
Y147256D01*
X552467Y147825D01*
X557084D01*
X557584Y148325D01*
Y158194D01*
G01X552798Y143518D02*
X554698D01*
X555048Y143868D01*
Y145768D01*
G01X552798Y143518D02*
Y142392D01*
X553025Y142165D01*
X561564D01*
X564099Y144700D01*
X567300D01*
X567800Y144200D01*
Y140313D01*
X567182Y139695D01*
X565730D01*
G01X539748Y143740D02*
Y146204D01*
X540005Y146461D01*
G01X547091Y149414D02*
X551544D01*
X551898Y149768D01*
G01X547091Y152367D02*
X551892D01*
X551898Y152373D01*
G01D02*
Y149768D01*
G01X555850Y179904D02*
Y180204D01*
X554188Y181866D01*
X552544D01*
G01Y179897D02*
Y176034D01*
X555913Y172665D01*
G01X552544Y185803D02*
Y189278D01*
X553451Y190185D01*
X555260D01*
G01D02*
Y191968D01*
X555957Y192665D01*
X558834D01*
G01Y196665D02*
X551956D01*
X549985Y194694D01*
Y192490D01*
G01D02*
Y188362D01*
G01X552544Y183834D02*
X555740D01*
G01X552155Y209229D02*
X552877D01*
X553465Y208641D01*
Y203429D01*
X556030Y200864D01*
G01X552155Y213166D02*
X553841D01*
X554552Y212455D01*
X556119D01*
G01X552155Y211197D02*
X553608D01*
X556053Y208752D01*
Y207037D01*
G01X552155Y217103D02*
X554168D01*
X558929Y221864D01*
G01X542628Y266114D02*
Y264678D01*
X541853Y263903D01*
Y262685D01*
G01X540061Y269603D02*
Y268681D01*
X542628Y266114D01*
G01X540906Y284908D02*
Y282787D01*
X540101Y281982D01*
G01X545611Y345723D02*
Y343819D01*
X546233Y343197D01*
X565005D01*
X574079Y334123D01*
X582517D01*
X584679Y336285D01*
G01X545611Y350223D02*
Y348590D01*
X546112Y348089D01*
X566495D01*
X578193Y336391D01*
G01X545611Y359223D02*
Y360811D01*
X546358Y361558D01*
X552504D01*
X552593Y361469D01*
X581367D01*
X603359Y339477D01*
X682857D01*
G01X545611Y354723D02*
Y356311D01*
X546358Y357058D01*
X581558D01*
X602152Y336464D01*
X686367D01*
X689486Y339583D01*
G01X545611Y368223D02*
Y369811D01*
X546358Y370558D01*
X552504D01*
X554662Y368400D01*
X581500D01*
X598857Y351043D01*
X696945D01*
X743122Y304866D01*
X769067D01*
X780905Y293028D01*
X786461D01*
G01X545611Y363723D02*
Y365311D01*
X546358Y366058D01*
X580542D01*
X598057Y348543D01*
X696901D01*
X743078Y302366D01*
X768031D01*
X782976Y287421D01*
X790280D01*
G01X873262Y300030D02*
X873191Y300101D01*
X873180Y300091D01*
X871209D01*
X870400Y300900D01*
X818241D01*
X815099Y297758D01*
X781215D01*
X771859Y307114D01*
X743604D01*
X697518Y353200D01*
X601100D01*
X583800Y370500D01*
X558472D01*
X554003Y374969D01*
X552593D01*
X552504Y375058D01*
X546358D01*
X545611Y374311D01*
Y372723D01*
G01X542034Y392209D02*
X543520Y390723D01*
X545611D01*
G01X541706Y386223D02*
X545611D01*
G01X551620Y390723D02*
X548761D01*
G01X553563Y384987D02*
X552327Y386223D01*
X548761D01*
G01X872050Y302644D02*
X817531D01*
X814380Y299493D01*
X781934D01*
X772578Y308849D01*
X744323D01*
X698193Y354979D01*
X698192D01*
X697749Y355422D01*
X602578D01*
X585606Y372394D01*
X561078D01*
X554003Y379469D01*
X552593D01*
X552504Y379558D01*
X546358D01*
X545611Y378811D01*
Y377223D01*
G01X544770Y599650D02*
X540770D01*
G01Y596729D02*
Y599650D01*
G01X557751Y750851D02*
X556617Y749717D01*
X553958D01*
G01D02*
X549606D01*
X549054Y749165D01*
X545550D01*
X544627Y748242D01*
Y746514D01*
G01X553958Y744599D02*
X557847D01*
G01X553958D02*
X552578D01*
X550408Y742429D01*
Y740552D01*
X552402Y738558D01*
X552606D01*
G01X560256Y776099D02*
Y764089D01*
X547029Y750862D01*
X543817D01*
X541903Y748948D01*
Y743857D01*
X549686Y736074D01*
X559674D01*
X563200Y739600D01*
G01X539449Y779889D02*
Y775864D01*
X540424Y774889D01*
G01X539449Y782389D02*
Y779889D01*
G01X546606Y767474D02*
X547010D01*
X549661Y770125D01*
Y773848D01*
X548620Y774889D01*
X540424D01*
G01X544515Y789327D02*
Y793875D01*
G01X544741Y809649D02*
X548241D01*
X560788Y797102D01*
X571975D01*
G01X544878Y816309D02*
X571497D01*
X571975Y816787D01*
G01X554357Y834405D02*
Y822533D01*
X556741Y820149D01*
G01X542400Y844739D02*
Y843100D01*
X546100Y839400D01*
X552900D01*
X554357Y837943D01*
Y834405D01*
G01X573300Y829600D02*
Y835800D01*
X567000Y842100D01*
Y849700D01*
X562500Y854200D01*
X545400D01*
X542400Y851200D01*
Y847889D01*
G01X561134Y869291D02*
X559625D01*
X558621Y870295D01*
X553870D01*
G01Y880295D02*
X558622D01*
X562327Y884000D01*
X567827D01*
G01X548327Y905295D02*
X553870D01*
G01X559214Y897425D02*
Y898185D01*
X557104Y900295D01*
X553870D01*
G01X552923Y991956D02*
Y988813D01*
G01D02*
Y986106D01*
G01X547745Y1003349D02*
X545640D01*
X544719Y1004270D01*
Y1007522D01*
G01D02*
Y1008760D01*
X544219Y1009260D01*
X541766D01*
G01X554696Y1010822D02*
X554440D01*
X551485Y1007867D01*
Y1006648D01*
G01D02*
Y1003349D01*
G01X548523Y1021177D02*
X548144Y1021556D01*
Y1025227D01*
G01X548852Y1015166D02*
X550609D01*
X551085Y1014690D01*
Y1012690D01*
X550608Y1012213D01*
X548852D01*
G01Y1015166D02*
Y1018307D01*
G01D02*
Y1020848D01*
X548523Y1021177D01*
G01X544378Y1021048D02*
Y1017840D01*
X545094Y1017124D01*
Y1013678D01*
G01D02*
X543629Y1012213D01*
X541766D01*
G01X541228Y1021048D02*
Y1023092D01*
X541867Y1023731D01*
X545566D01*
G01X560573Y64722D02*
Y60513D01*
G01X563133Y64722D02*
X563433Y64422D01*
Y60438D01*
G01X565987Y81848D02*
Y82885D01*
X569114Y86012D01*
G01X560573Y81848D02*
Y85603D01*
X560701Y85731D01*
G01X564255Y86046D02*
X563133Y84924D01*
Y81848D01*
G01X561258Y91951D02*
Y94351D01*
G01X565207Y91879D02*
Y94279D01*
G01X569114Y86012D02*
Y88824D01*
G01X560701Y85731D02*
Y88244D01*
X561258Y88801D01*
G01X565207Y88729D02*
Y86998D01*
X564255Y86046D01*
G01X556394Y107921D02*
Y103621D01*
G01X570404Y113684D02*
Y110794D01*
X570394Y110784D01*
G01D02*
X568669Y109059D01*
Y107899D01*
G01X563883Y147754D02*
X568121D01*
X570694Y145177D01*
Y135400D01*
X570900Y135194D01*
Y133706D01*
X570694Y133500D01*
Y130898D01*
G01X568436Y121558D02*
Y123126D01*
X567279Y124283D01*
X564885D01*
G01D02*
X564917Y124315D01*
Y127525D01*
X564694Y127748D01*
G01X570404Y121558D02*
Y123785D01*
X569951Y124879D01*
G01D02*
Y127005D01*
X570694Y127748D01*
G01X560543Y157370D02*
Y148980D01*
X561772Y147754D01*
X563883D01*
G01X557584Y158194D02*
Y158383D01*
X564745Y165544D01*
X591748D01*
X599097Y158195D01*
X659945D01*
X659946Y158194D01*
G01X563883Y150904D02*
Y154865D01*
G01D02*
X568820D01*
G01D02*
X571664Y157709D01*
X578035D01*
X578535Y158209D01*
Y161958D01*
G01X558834Y176665D02*
Y180665D01*
G01D02*
X556611D01*
X555850Y179904D01*
G01Y178560D02*
Y179904D01*
G01X558834Y168665D02*
Y172665D01*
G01X555913D02*
X558834D01*
G01X555740Y183834D02*
X558003D01*
X558834Y184665D01*
G01X561984Y196665D02*
X564627D01*
G01X561984Y192665D02*
X564627D01*
G01X561984Y184665D02*
X564007D01*
X564740Y185398D01*
Y186778D01*
G01D02*
Y187934D01*
X564009Y188665D01*
X561984D01*
G01X562079Y208864D02*
X564659D01*
G01X556030Y200864D02*
X558929D01*
G01Y212864D02*
X558520Y212455D01*
X556119D01*
G01X558929Y204864D02*
Y208864D01*
G01X556053Y207037D02*
X557880Y208864D01*
X558929D01*
G01X558926Y225719D02*
Y226629D01*
X560928Y228631D01*
G01X558926Y225719D02*
Y221867D01*
X558929Y221864D01*
G01X573164Y242078D02*
X565892D01*
X563404Y244566D01*
Y255458D01*
X566826Y258880D01*
X617436D01*
G01X569938Y378317D02*
X570868Y379247D01*
X594072D01*
X611083Y362236D01*
X669399D01*
X678158Y370995D01*
Y424220D01*
X687315Y433377D01*
Y490754D01*
X698428Y501867D01*
X725867D01*
X730600Y506600D01*
X745736D01*
X748451Y503885D01*
X860729D01*
X885931Y529087D01*
Y534093D01*
G01X556334Y755432D02*
Y753492D01*
X556728Y753098D01*
X563436D01*
X564511Y752023D01*
Y750628D01*
X563600Y749717D01*
X561832D01*
G01X567445Y743122D02*
Y738419D01*
G01X561832Y744599D02*
X564592D01*
X565079Y744112D01*
Y738985D01*
X565645Y738419D01*
X567445D01*
G01X570595Y743122D02*
X575294D01*
X575295Y743123D01*
Y743494D01*
G01X571493Y763090D02*
X573872Y760711D01*
X640335D01*
X641909Y759137D01*
X653271D01*
G01X561212Y754992D02*
X560772Y755432D01*
X556334D01*
G01X564362Y754992D02*
Y757979D01*
G01D02*
X564432Y758049D01*
X568464D01*
G01X560263Y789327D02*
Y782207D01*
G01D02*
X560256Y782200D01*
Y779249D01*
G01X564200Y789327D02*
Y781992D01*
X567126Y779066D01*
G01D02*
X569492Y776700D01*
X572039D01*
G01X564923Y991956D02*
Y988813D01*
G01D02*
Y986106D01*
G01X560923D02*
Y988813D01*
G01D02*
Y991956D01*
G01X556923D02*
Y988813D01*
G01D02*
Y986106D01*
G01X568923Y991956D02*
Y988813D01*
G01D02*
Y986106D01*
G01X574508Y1204453D02*
X571680Y1207281D01*
G01D02*
X573524Y1209125D01*
X574232D01*
X575620Y1207737D01*
G01X568851Y1210110D02*
X566023Y1212938D01*
G01D02*
X567457Y1214372D01*
X569135D01*
G01X562841Y1216120D02*
X564890Y1218169D01*
G01X574515Y1228380D02*
X571102D01*
X569323Y1226601D01*
X566688D01*
G01X562688D02*
X566680Y1230593D01*
X579108D01*
X589558Y1234921D01*
X592634D01*
G01X564242Y1525110D02*
X564300Y1525052D01*
Y1523600D01*
X564600Y1523300D01*
X568200D01*
X571124Y1526224D01*
X572182D01*
G01X567324Y1528151D02*
Y1526623D01*
X566501Y1525800D01*
X564932D01*
X564242Y1525110D01*
G01X572849Y1518702D02*
X563298D01*
X558786Y1523214D01*
Y1534534D01*
G01X562786D02*
X561500Y1533248D01*
Y1523600D01*
X563638Y1521462D01*
X572432D01*
G01X571809Y1535426D02*
Y1533024D01*
X570796Y1532011D01*
Y1530309D01*
G01X567958Y1535390D02*
X571773D01*
X571809Y1535426D01*
G01X563968Y1541445D02*
X562786Y1540263D01*
Y1537684D01*
G01X557584Y1543411D02*
X558786Y1542209D01*
Y1537684D01*
G01X568279Y1538438D02*
X568417Y1538576D01*
X571809D01*
G01X571942Y1544210D02*
X571500Y1543768D01*
Y1542382D01*
X572507Y1541375D01*
G01X587438Y106495D02*
X591354D01*
X591420Y106561D01*
G01X587438Y102495D02*
Y106495D01*
G01X572669Y107899D02*
X576669D01*
G01X572372Y113684D02*
Y111534D01*
X573122Y110784D01*
X575394D01*
G01D02*
X576669Y109509D01*
Y107899D01*
G01X578748Y130903D02*
X578717Y130934D01*
Y134838D01*
G01X578748Y127753D02*
Y126313D01*
X579954Y125107D01*
G01X572372Y121558D02*
Y124163D01*
X572872Y124663D01*
X574973D01*
G01D02*
Y126008D01*
X574694Y126287D01*
Y127748D01*
G01X585338Y143762D02*
X588568D01*
G01X574795Y153296D02*
Y150265D01*
X576343Y148717D01*
X582468D01*
G01D02*
X584621D01*
X585338Y148000D01*
Y146912D01*
G01X572816Y136742D02*
Y138338D01*
X573316Y138838D01*
X576317D01*
G01X578717Y134838D02*
Y138838D01*
G01X576317D02*
X578717D01*
G01X587563Y225055D02*
Y229782D01*
X586789Y230556D01*
G01X578013Y232859D02*
Y232681D01*
X582048Y228646D01*
G01X583626Y225055D02*
Y227068D01*
X582048Y228646D01*
G01X586789Y230556D02*
Y232333D01*
X587415Y232959D01*
G01X580143Y242078D02*
X576314D01*
G01D02*
Y243230D01*
X577655Y244571D01*
G01D02*
Y247035D01*
X577912Y247292D01*
G01X572344Y252371D02*
Y248371D01*
G01X577912Y250245D02*
X576172D01*
X575035Y249108D01*
G01D02*
X574763D01*
X574026Y248371D01*
X572344D01*
G01X584998Y250245D02*
X589451D01*
X589805Y250599D01*
G01X584998Y253198D02*
Y256394D01*
G01D02*
X587530D01*
X590001Y253923D01*
Y250795D01*
X589805Y250599D01*
G01X892425Y529633D02*
X891129D01*
X863235Y501739D01*
X749340D01*
X744598Y496997D01*
X728298D01*
X725574Y499721D01*
X699317D01*
X689461Y489865D01*
Y432488D01*
X680304Y423331D01*
Y370106D01*
X670288Y360090D01*
X610194D01*
X593183Y377101D01*
X575875D01*
X573479Y374705D01*
G01X584321Y455656D02*
Y462090D01*
X587431Y465200D01*
X599690D01*
X603880Y461010D01*
Y460189D01*
X605262Y458807D01*
Y458711D01*
G01X584321Y452506D02*
X586030D01*
X587786Y450750D01*
X590181D01*
G01X584321Y452506D02*
Y448656D01*
G01X574504Y750309D02*
X573778Y749583D01*
Y747437D01*
G01X575295Y743494D02*
Y745920D01*
X573778Y747437D01*
G01X578271Y763556D02*
X642568D01*
X642987Y763137D01*
X653271D01*
G01X577638Y769772D02*
X579003Y771137D01*
X653271D01*
G01Y775137D02*
X578204D01*
G01X585912Y778470D02*
X652604D01*
X653271Y779137D01*
G01X583102Y767137D02*
X653271D01*
G01X572039Y780700D02*
X571984Y780755D01*
Y784507D01*
G01X575189Y780700D02*
X579444Y784955D01*
G01X575189Y776700D02*
Y777188D01*
X584200Y786199D01*
Y790791D01*
G01X587183Y785008D02*
X589054Y783137D01*
X653271D01*
G01X571975Y814819D02*
X576071D01*
X577741Y813149D01*
Y794928D01*
X571984Y789171D01*
Y784507D01*
G01X579444Y784955D02*
X582089Y787600D01*
X582100D01*
G01X584200Y790791D02*
Y791285D01*
X586060Y793145D01*
G01X584923Y991956D02*
Y988813D01*
G01D02*
Y986106D01*
G01X576923Y991956D02*
Y988813D01*
G01D02*
Y986106D01*
G01X580923Y991956D02*
Y988813D01*
G01D02*
Y986106D01*
G01X572923Y991956D02*
Y988813D01*
G01D02*
Y986106D01*
G01X593519Y1224472D02*
X593232D01*
X585827Y1217067D01*
G01X580171Y1222724D02*
X582999Y1219896D01*
G01X592885Y1229402D02*
X585615D01*
X583037Y1226824D01*
X578614D01*
X577342Y1225552D01*
G01X580169Y1222724D02*
X580171D01*
G01X586502Y1227300D02*
X583189Y1223987D01*
X581434D01*
X580171Y1222724D01*
G01X574515Y1228380D02*
X581493D01*
X583520Y1230407D01*
G01X585357Y1493687D02*
X581803D01*
G01X578859Y1497758D02*
X578930Y1497687D01*
X585357D01*
G01Y1501687D02*
X583140D01*
X582027Y1502800D01*
G01X585357Y1509687D02*
X581803D01*
G01X585290Y1514042D02*
Y1509754D01*
X585357Y1509687D01*
G01X581391Y1505724D02*
X577968D01*
X577931Y1505687D01*
G01X587809Y1535426D02*
Y1528389D01*
G01X587858Y1523890D02*
Y1528340D01*
X587809Y1528389D01*
G01X579809Y1535426D02*
Y1528163D01*
G01X579758Y1523790D02*
Y1528112D01*
X579809Y1528163D01*
G01X575809Y1535426D02*
Y1532912D01*
G01X587809Y1545854D02*
Y1538576D01*
G01X583809D02*
Y1541607D01*
G01X583742Y1544710D02*
Y1541674D01*
X583809Y1541607D01*
G01X577571Y1544013D02*
X577679D01*
X579809Y1541883D01*
Y1538576D01*
G01X571942Y1544210D02*
X572032Y1544300D01*
X573500D01*
X574479Y1543321D01*
X575809Y1540112D01*
Y1538576D01*
G01X583809Y1535426D02*
Y1533025D01*
G01X601437Y99961D02*
X596662D01*
X594497Y102126D01*
Y103411D01*
G01X591622Y97667D02*
X594891D01*
G01X601437Y97599D02*
X594959D01*
X594891Y97667D01*
G01X601437Y90512D02*
X605549D01*
X605687Y90650D01*
G01X601437Y88150D02*
X608534D01*
X610999Y90615D01*
G01X605437Y95236D02*
X601437D01*
G01Y92874D02*
X592524D01*
X590287Y95111D01*
G01X594497Y103411D02*
X591420D01*
G01Y106561D02*
X594656D01*
G01X591650Y232984D02*
Y231180D01*
X591044Y230574D01*
Y227824D01*
G01D02*
Y227724D01*
X589532Y226212D01*
Y225055D01*
G01X593351Y241681D02*
Y244297D01*
G01X590201Y241681D02*
X589560Y241040D01*
Y233636D01*
X590212Y232984D01*
X591650D01*
G01X602462Y458711D02*
X597873Y463300D01*
X591217D01*
X590181Y462264D01*
Y450750D01*
G01X606026Y455921D02*
X604032D01*
X603486Y455375D01*
G01D02*
X601098D01*
X597061Y459412D01*
X593921D01*
G01X653271Y787137D02*
X591858D01*
X588659Y790336D01*
G01X600923Y991956D02*
Y988813D01*
G01D02*
Y986106D01*
G01X588923Y991956D02*
Y988813D01*
G01D02*
Y986106D01*
G01X592923Y991956D02*
Y988813D01*
G01D02*
Y986106D01*
G01X596923D02*
Y988813D01*
G01D02*
Y991956D01*
G01X602165Y1090157D02*
X600295Y1088287D01*
G01X605905Y1090157D02*
X604035Y1088287D01*
G01X602165Y1101377D02*
X600295Y1099507D01*
G01X605905Y1101377D02*
X604035Y1099507D01*
G01X602165Y1108858D02*
X600295Y1106988D01*
G01X605905Y1108858D02*
X604035Y1106988D01*
G01X605905Y1123818D02*
X604035Y1121948D01*
G01X602165Y1123818D02*
X600295Y1121948D01*
G01X602165Y1116338D02*
X600295Y1114468D01*
G01X605905Y1116338D02*
X604035Y1114468D01*
G01X602165Y1138779D02*
X600295Y1136909D01*
G01X605905Y1138779D02*
X604035Y1136909D01*
G01X602165Y1131299D02*
X600295Y1129429D01*
G01X605905Y1131299D02*
X604035Y1129429D01*
G01X605905Y1149999D02*
X604035Y1148129D01*
G01X602165Y1149999D02*
X600295Y1148129D01*
G01X588656Y1214239D02*
X591484Y1211411D01*
X591485D01*
G01X594183Y1220068D02*
Y1219766D01*
X588656Y1214239D01*
G01X588507Y1493687D02*
X588536Y1493658D01*
G01X588859Y1490895D02*
Y1493335D01*
X588536Y1493658D01*
G01D02*
X594910D01*
G01X588507Y1497687D02*
X594781D01*
X594910Y1497558D01*
G01D02*
X593040Y1495688D01*
X590826D01*
G01X588507Y1509687D02*
Y1514141D01*
G01Y1501687D02*
X591487D01*
G01X595010Y1501458D02*
X594781Y1501687D01*
X591487D01*
G01X591106Y1505794D02*
Y1508938D01*
X591481Y1509313D01*
G01X591872Y1518071D02*
X591004Y1517203D01*
Y1513435D01*
X594256Y1510183D01*
Y1505794D01*
G01X613738Y1546507D02*
Y1545639D01*
X597499Y1529400D01*
X592448D01*
X591858Y1529990D01*
G01X595809Y1546214D02*
Y1538576D01*
G01X600242Y1538510D02*
X595875D01*
X595809Y1538576D01*
G01X591809D02*
Y1542407D01*
G01X595809Y1535426D02*
Y1532133D01*
G01X591858Y1529990D02*
Y1535377D01*
X591809Y1535426D01*
G01X619547Y92874D02*
X624278D01*
G01X615370Y95236D02*
X619547D01*
G01Y99961D02*
X615320D01*
G01X605147Y378600D02*
X608111D01*
G01X611261D02*
Y382600D01*
G01X638355Y382067D02*
X624765D01*
X624232Y382600D01*
X616015D01*
G01D02*
X611261D01*
G01X608111Y459600D02*
Y458038D01*
X608611Y457538D01*
X619668D01*
X622465Y460335D01*
X663779D01*
X668133Y455981D01*
X678461D01*
G01X605262Y458711D02*
X606151Y459600D01*
X608111D01*
G01X638355Y465177D02*
X616106D01*
G01X611261Y459600D02*
Y463600D01*
G01X616106Y465177D02*
X612838D01*
X611261Y463600D01*
G01X608199Y554555D02*
Y553355D01*
X608880Y552674D01*
X616130D01*
G01X604349Y554555D02*
X608199D01*
G01X616130Y552674D02*
X620011Y556555D01*
X638355D01*
G01X608231Y562567D02*
Y563717D01*
X609088Y564574D01*
X615865D01*
X616068Y564371D01*
G01X604349Y562555D02*
X608219D01*
X608231Y562567D01*
G01X616068Y564371D02*
X621346D01*
X624437Y561280D01*
X638355D01*
G01X608199Y558555D02*
Y559925D01*
X608699Y560425D01*
X612832D01*
X613886Y559371D01*
X616068D01*
G01X604349Y558555D02*
X608199D01*
G01X616068Y559371D02*
X618749D01*
X619203Y558917D01*
X638355D01*
G01X610629Y599588D02*
X614459D01*
X616128Y601257D01*
G01D02*
X622352D01*
X628024Y606929D01*
X638355D01*
G01Y592756D02*
X626119D01*
X624751Y591388D01*
X616106D01*
G01D02*
X615906Y591588D01*
X610629D01*
G01Y607588D02*
Y603632D01*
X610661Y603600D01*
G01X615306Y606190D02*
X612716Y603600D01*
X610661D01*
G01X638355Y604567D02*
X629271D01*
X621025Y596321D01*
X615284D01*
G01D02*
X613086D01*
X612353Y595588D01*
X610629D01*
G01X616132Y621005D02*
X614727Y619600D01*
X610661D01*
G01Y611600D02*
X613081D01*
X613555Y611126D01*
X616135D01*
G01D02*
X623381D01*
X623909Y611654D01*
X638355D01*
G01Y609291D02*
X626107D01*
X623006Y606190D01*
X615306D01*
G01X610661Y615600D02*
X612319D01*
X612788Y616069D01*
X615328D01*
G01D02*
X626393D01*
X628446Y614016D01*
X638355D01*
G01X615641Y637979D02*
X617789Y635831D01*
X621694D01*
X634060Y623465D01*
X638355D01*
G01Y616378D02*
X630232D01*
X625615Y620995D01*
X616142D01*
X616132Y621005D01*
G01X638355Y618740D02*
X631704D01*
X624494Y625950D01*
X615305D01*
G01D02*
X612955Y623600D01*
X610661D01*
G01X638355Y621102D02*
X632771D01*
X622987Y630886D01*
X616109D01*
G01D02*
X612823Y627600D01*
X610661D01*
G01X607511D02*
Y631421D01*
G01D02*
X605328Y633604D01*
Y664915D01*
X655713Y715300D01*
X721374D01*
X725187Y711487D01*
Y707389D01*
X723656Y705858D01*
G01X610661Y637969D02*
X615631D01*
X615641Y637979D01*
G01X610661Y641974D02*
Y637969D01*
G01X607511Y641974D02*
Y645211D01*
X610562Y648262D01*
G01X720985Y711658D02*
X718519Y714124D01*
X656730D01*
X607511Y664905D01*
Y654963D01*
X610562Y651912D01*
Y648262D01*
G01X616923Y991956D02*
Y988813D01*
G01D02*
Y986106D01*
G01X608923D02*
Y988813D01*
G01D02*
Y991956D01*
G01X604923D02*
Y988813D01*
G01D02*
Y986106D01*
G01X612923Y995106D02*
Y997860D01*
G01X617126Y1075196D02*
X615256Y1073326D01*
G01X609646Y1075196D02*
X607776Y1073326D01*
G01X620866Y1086417D02*
X618996Y1084547D01*
G01X620866Y1082677D02*
X618996Y1080807D01*
G01X617126Y1078936D02*
X615256Y1077066D01*
G01X613386Y1082677D02*
X611516Y1080807D01*
G01X613386Y1086417D02*
X611516Y1084547D01*
G01X609646Y1093897D02*
X607776Y1092027D01*
G01X609646Y1097637D02*
X607776Y1095767D01*
G01X617126Y1097637D02*
X615256Y1095767D01*
G01X620866Y1105117D02*
X618996Y1103247D01*
G01X617126Y1093897D02*
X615256Y1092027D01*
G01X613386Y1105117D02*
X611516Y1103247D01*
G01X620866Y1101377D02*
X618996Y1099507D01*
G01X613386Y1101377D02*
X611516Y1099507D01*
G01X613386Y1120078D02*
X611516Y1118208D01*
G01X609646Y1120078D02*
X607776Y1118208D01*
G01X613386Y1112598D02*
X611516Y1110728D01*
G01X620866Y1112598D02*
X618996Y1110728D01*
G01X609646Y1112598D02*
X607776Y1110728D01*
G01X613386Y1127558D02*
X611516Y1125688D01*
G01X609646Y1127558D02*
X607776Y1125688D01*
G01X609646Y1135039D02*
X607776Y1133169D01*
G01X640109Y98198D02*
X636109D01*
G01X624278Y92874D02*
Y95018D01*
X625672Y96412D01*
X634448D01*
X636109Y98073D01*
Y98198D01*
G01X634887Y265701D02*
X636215Y264373D01*
Y262685D01*
G01X638487Y269603D02*
Y267575D01*
X637791Y266879D01*
X636065D01*
X634887Y265701D01*
G01X635268Y284908D02*
X639268D01*
G01X638487Y277477D02*
Y279751D01*
X636522Y281716D01*
G01X639268Y284908D02*
Y283104D01*
X637880Y281716D01*
X636522D01*
G01X624606Y1075196D02*
X622736Y1073326D01*
G01X624606Y1078936D02*
X622736Y1077066D01*
G01X628346Y1086417D02*
X626476Y1084547D01*
G01X628346Y1082677D02*
X626476Y1080807D01*
G01X624606Y1093897D02*
X622736Y1092027D01*
G01X624606Y1097637D02*
X622736Y1095767D01*
G01X628346Y1105117D02*
X626476Y1103247D01*
G01X628346Y1116338D02*
X626476Y1114468D01*
G01X624606Y1112598D02*
X622736Y1110728D01*
G01X632086Y1116338D02*
X630216Y1114468D01*
G01X628346Y1149999D02*
X626476Y1148129D01*
G01X624606Y1146259D02*
X622736Y1144389D01*
G01X624606Y1149999D02*
X622736Y1148129D01*
G01X624606Y1153740D02*
X622736Y1151870D01*
G01X628346Y1157480D02*
X626476Y1155610D01*
G01X628346Y1153740D02*
X626476Y1151870D01*
G01X624606Y1157480D02*
X622736Y1155610D01*
G01X628346Y1161220D02*
X626476Y1159350D01*
G01X624606Y1161220D02*
X622736Y1159350D01*
G01X651010Y68581D02*
Y69564D01*
X654033Y72587D01*
X654205D01*
G01X651010Y80581D02*
Y79618D01*
X654041Y76587D01*
X654205D01*
G01X648655D02*
X651055D01*
G01X648655Y72615D02*
X648683Y72587D01*
X651055D01*
G01X650094Y100625D02*
X651460Y99259D01*
X655016D01*
G01X645613Y97475D02*
X643113D01*
G01X645613Y105087D02*
Y100625D01*
G01D02*
X650094D01*
G01X647748Y141247D02*
X650673D01*
G01X668092Y142648D02*
X666570D01*
X664222Y140300D01*
X654420D01*
X653473Y141247D01*
X650673D01*
G01X642367Y146461D02*
X642110Y146204D01*
Y143740D01*
G01X644598Y141247D02*
X640769D01*
G01X642110Y143740D02*
X640769Y142399D01*
Y141247D01*
G01X636799Y151540D02*
Y147540D01*
G01X642367Y149414D02*
X640627D01*
X639490Y148277D01*
G01D02*
X639218D01*
X638481Y147540D01*
X636799D01*
G01X654260Y152373D02*
X654254Y152367D01*
X649453D01*
G01X654260Y149768D02*
X653906Y149414D01*
X649453D01*
G01X652347Y188362D02*
Y192490D01*
G01D02*
Y193746D01*
X655266Y196665D01*
X661196D01*
G01X640215Y259535D02*
Y256303D01*
G01X639974Y265896D02*
Y264086D01*
X640215Y263845D01*
Y262685D01*
G01X644990Y266114D02*
Y264678D01*
X644215Y263903D01*
Y262685D01*
G01X642463Y281982D02*
X640455Y279974D01*
Y277477D01*
G01X639974Y265896D02*
Y267118D01*
X640455Y267599D01*
Y269603D01*
G01X644990Y266114D02*
X642423Y268681D01*
Y269603D01*
G01X643268Y284908D02*
Y282787D01*
X642463Y281982D01*
G01X638355Y554193D02*
X640865D01*
X648914Y562242D01*
Y575481D01*
X651149Y577716D01*
G01X638355Y549469D02*
X640304D01*
X642414Y547359D01*
Y545528D01*
G01X658064Y656311D02*
X656642D01*
X653492Y653161D01*
X652595D01*
G01X643933Y655720D02*
X646859D01*
X649275Y658136D01*
Y663348D01*
X650958Y665031D01*
Y668153D01*
G01D02*
Y672360D01*
G01X656650Y702277D02*
X653691D01*
X651602Y704366D01*
G01X657868Y710129D02*
X655939D01*
X652724Y706914D01*
Y705488D01*
X651602Y704366D01*
G01X647047Y1116338D02*
X645177Y1114468D01*
G01X643307Y1116338D02*
X641437Y1114468D01*
G01X650787Y1116338D02*
X648917Y1114468D01*
G01X654527Y1116338D02*
X652657Y1114468D01*
G01X650787Y1131299D02*
X648917Y1129429D01*
G01X650787Y1135039D02*
X648917Y1133169D01*
G01X650787Y1142519D02*
X648917Y1140649D01*
G01X654527Y1142519D02*
X652657Y1140649D01*
G01X654527Y1213582D02*
X652657Y1215452D01*
G01X654527Y1217322D02*
X652657Y1219192D01*
G01X643307Y1217322D02*
X641437Y1215452D01*
G01X647047Y1217322D02*
X648917Y1215452D01*
G01X647047Y1213582D02*
X645177Y1215452D01*
G01X662935Y64722D02*
Y60513D01*
G01Y64722D02*
Y72865D01*
X661033Y74767D01*
X656385D01*
X654205Y72587D01*
G01X665795Y60438D02*
Y64422D01*
X665495Y64722D01*
G01D02*
Y72967D01*
X661875Y76587D01*
X654205D01*
G01X668349Y81848D02*
Y82885D01*
X671476Y86012D01*
G01X663063Y85731D02*
X662935Y85603D01*
Y81848D01*
G01X666617Y86046D02*
X665495Y84924D01*
Y81848D01*
G01X663620Y91951D02*
Y94351D01*
G01X667569Y91879D02*
Y94279D01*
G01X663620Y88801D02*
X663063Y88244D01*
Y85731D01*
G01X667569Y88729D02*
Y86998D01*
X666617Y86046D01*
G01X654467Y112083D02*
Y112402D01*
X656553Y114488D01*
G01X658756Y107921D02*
Y103621D01*
G01X670798Y121558D02*
Y123126D01*
X669641Y124283D01*
X667247D01*
G01D02*
X667279Y124315D01*
Y125971D01*
X669056Y127748D01*
G01X659946Y158194D02*
Y148325D01*
X659446Y147825D01*
X654829D01*
X654260Y147256D01*
Y145768D01*
G01X662905Y157370D02*
Y148980D01*
X664134Y147754D01*
X666245D01*
G01D02*
X670483D01*
X673056Y145177D01*
Y135700D01*
X673200Y135556D01*
Y133644D01*
X673056Y133500D01*
Y130898D01*
G01X655160Y143518D02*
X657060D01*
X657410Y143868D01*
Y145768D01*
G01X668092Y139695D02*
X669544D01*
X670200Y140351D01*
Y144400D01*
X669700Y144900D01*
X666501D01*
X663766Y142165D01*
X655387D01*
X655160Y142392D01*
Y143518D01*
G01X659946Y158194D02*
X660505Y158753D01*
Y159006D01*
X667043Y165544D01*
X694110D01*
X701459Y158195D01*
X762307D01*
X762308Y158194D01*
G01X666245Y154865D02*
X671182D01*
G01X666245Y150904D02*
Y154865D01*
G01X654260Y152373D02*
Y149768D01*
G01X661196Y168665D02*
Y172665D01*
G01X654906Y179897D02*
Y176034D01*
X658275Y172665D01*
G01D02*
X661196D01*
G01Y176665D02*
Y180665D01*
G01X658212Y178560D02*
Y179904D01*
G01X661196Y180665D02*
X658973D01*
X658212Y179904D01*
G01X654906Y181866D02*
X656550D01*
X658212Y180204D01*
Y179904D01*
G01X661196Y192665D02*
X658557D01*
X657622Y191730D01*
Y190185D01*
G01D02*
X655813D01*
X654906Y189278D01*
Y185803D01*
G01Y183834D02*
X658102D01*
G01D02*
X660365D01*
X661196Y184665D01*
G01X664346Y196665D02*
X666989D01*
G01X664346Y192665D02*
X666989D01*
G01X664346Y184665D02*
X666369D01*
X667102Y185398D01*
Y186778D01*
G01D02*
Y187934D01*
X666371Y188665D01*
X664346D01*
G01X664441Y208864D02*
X667021D01*
G01X658392Y200864D02*
X661291D01*
G01X654517Y209229D02*
X655239D01*
X655827Y208641D01*
Y203429D01*
X658392Y200864D01*
G01X661291Y212864D02*
X660882Y212455D01*
X658481D01*
G01X654517Y213166D02*
X656203D01*
X656914Y212455D01*
X658481D01*
G01X661291Y204864D02*
Y208864D01*
G01X658415Y207037D02*
X660242Y208864D01*
X661291D01*
G01X654517Y211197D02*
X655970D01*
X658415Y208752D01*
Y207037D01*
G01X654517Y217103D02*
X656530D01*
X661291Y221864D01*
G01X661288Y225719D02*
Y221867D01*
X661291Y221864D01*
G01X663290Y228631D02*
X661288Y226629D01*
Y225719D01*
G01X675526Y242078D02*
X668254D01*
X665766Y244566D01*
Y255458D01*
X669188Y258880D01*
X719798D01*
G01X656466Y382067D02*
X661719D01*
X661761Y382109D01*
G01X656466Y465177D02*
X665043D01*
X667420Y462800D01*
X670680D01*
G01X656466Y551831D02*
X661612D01*
X661760Y551683D01*
G01X656466Y549469D02*
X670748D01*
G01X656466Y556555D02*
X662634D01*
X664591Y554598D01*
X670770D01*
G01X675511Y562800D02*
X665902D01*
X664522Y561420D01*
X661760D01*
G01D02*
X660420D01*
X660280Y561280D01*
X656466D01*
G01X675511Y558800D02*
X674211Y557500D01*
X665796D01*
X664379Y558917D01*
X661760D01*
G01D02*
X656466D01*
G01Y592756D02*
X662842D01*
X665586Y595500D01*
G01X656466Y621102D02*
X661984D01*
X663586Y619500D01*
X671086D01*
G01X656466Y611654D02*
X659889D01*
X660827Y612592D01*
G01X656466Y609291D02*
X659672D01*
X660453Y610072D01*
X666244D01*
G01X656466Y606929D02*
X660586D01*
G01X656466Y604567D02*
X665086D01*
G01X656466Y616378D02*
X660046D01*
X660546Y616878D01*
Y618400D01*
G01X656466Y614016D02*
X659481D01*
X660749Y615284D01*
X665147D01*
X666180Y616317D01*
G01X656466Y623465D02*
X667551D01*
X669486Y625400D01*
X671086D01*
G01X679061D02*
Y632637D01*
X665643Y646055D01*
G01D02*
Y655380D01*
X664712Y656311D01*
X662064D01*
G01X658233Y646449D02*
X662064Y650280D01*
Y653161D01*
G01X658064D02*
Y650119D01*
G01X662064Y656311D02*
X658064D01*
G01X658438Y682006D02*
X662097D01*
X664168Y684077D01*
G01D02*
Y686283D01*
X661988Y688463D01*
Y689694D01*
G01X715802Y706446D02*
X717617Y708261D01*
Y710843D01*
X715986Y712474D01*
X690593D01*
X677194Y699075D01*
X655570D01*
X654297Y697802D01*
Y687372D01*
X654698Y686971D01*
Y682006D01*
G01X665138Y689694D02*
X674416D01*
G01X661988D02*
X661768Y689914D01*
Y694797D01*
G01X659209D02*
Y691851D01*
G01Y702277D02*
Y706556D01*
X657868Y707897D01*
Y710129D01*
G01X656421Y763137D02*
X661346D01*
G01X656421Y759137D02*
Y763137D01*
G01X661346D02*
X666771D01*
G01X656421Y779137D02*
X661846D01*
G01X656421D02*
Y775137D01*
G01X661846Y779137D02*
X666771D01*
G01Y771137D02*
X661346D01*
G01X656421Y767137D02*
Y771137D01*
G01X661346D02*
X656421D01*
G01X666771Y787137D02*
X661346D01*
G01X656421Y783137D02*
Y787137D01*
G01X661346D02*
X656421D01*
G01X662008Y1116338D02*
X660138Y1114468D01*
G01X658268Y1116338D02*
X656398Y1114468D01*
G01X665748Y1116338D02*
X663878Y1114468D01*
G01X669488Y1116338D02*
X667618Y1114468D01*
G01X663878Y1211712D02*
X665748Y1213582D01*
G01X658268D02*
X656398Y1211712D01*
G01X658268Y1217322D02*
X656398Y1215452D01*
G01X665748Y1217322D02*
X663878Y1215452D01*
G01X669488Y1213582D02*
X667618Y1215452D01*
G01X660138Y1211712D02*
X662008Y1213582D01*
G01X671476Y86012D02*
Y88824D01*
G01X675031Y107899D02*
X679031D01*
G01X674734Y113684D02*
Y111534D01*
X675484Y110784D01*
X677756D01*
G01D02*
X679031Y109509D01*
Y107899D01*
G01X672766Y113684D02*
Y110794D01*
X672756Y110784D01*
G01D02*
X671031Y109059D01*
Y107899D01*
G01X681110Y127753D02*
Y126313D01*
X682316Y125107D01*
G01X681110Y130903D02*
X681079Y130934D01*
Y134838D01*
G01X674734Y121558D02*
Y124163D01*
X675234Y124663D01*
X677335D01*
G01D02*
Y126008D01*
X677056Y126287D01*
Y127748D01*
G01X672766Y121558D02*
Y123785D01*
X672313Y124879D01*
G01D02*
Y127005D01*
X673056Y127748D01*
G01X687700Y146912D02*
Y148000D01*
X686983Y148717D01*
X684830D01*
G01D02*
X678705D01*
X677157Y150265D01*
Y153296D01*
G01X681079Y134838D02*
Y138838D01*
G01D02*
X678679D01*
G01D02*
X675678D01*
X675178Y138338D01*
Y136742D01*
G01X671182Y154865D02*
X674026Y157709D01*
X680397D01*
X680897Y158209D01*
Y161958D01*
G01X680375Y232859D02*
Y232681D01*
X684410Y228646D01*
G01X685988Y225055D02*
Y227068D01*
X684410Y228646D01*
G01X682505Y242078D02*
X678676D01*
G01X680274Y247292D02*
X680017Y247035D01*
Y244571D01*
G01D02*
X678676Y243230D01*
Y242078D01*
G01X680274Y250245D02*
X678534D01*
X677397Y249108D01*
G01X674706Y252371D02*
Y248371D01*
G01X677397Y249108D02*
X677125D01*
X676388Y248371D01*
X674706D01*
G01X678461Y455981D02*
Y458800D01*
G01X675311D02*
Y462800D01*
G01X670680D02*
X675311D01*
G01X724362Y504731D02*
X721854D01*
X719902Y506683D01*
X715213D01*
X691896Y530000D01*
X682586D01*
G01X678661Y545800D02*
Y541000D01*
X679161Y540500D01*
X682086D01*
G01X675511Y545800D02*
Y549800D01*
G01X670748Y549469D02*
X673480D01*
X673811Y549800D01*
X675511D01*
G01X670770Y554598D02*
X674586D01*
X676821Y552363D01*
X681448D01*
X684111Y549700D01*
G01X687261Y557700D02*
Y561325D01*
X680586Y568000D01*
G01X671086Y619500D02*
X674011D01*
X675911Y621400D01*
G01X679061D02*
Y625400D01*
G01X671086D02*
X675911D01*
G01X674416Y689694D02*
X698706D01*
X708926Y679474D01*
Y675889D01*
G01X669921Y763137D02*
X674846D01*
G01D02*
X679345D01*
X680907Y764699D01*
X687146D01*
G01Y772377D02*
X684456D01*
X682632Y774201D01*
X678990Y782993D01*
X674846Y787137D01*
G01X675346Y779137D02*
X669921D01*
G01X687146Y769818D02*
X683525D01*
X681511Y771237D01*
X675346Y779137D01*
G01X687146Y767258D02*
X678725D01*
X674846Y771137D01*
G01D02*
X674583Y771400D01*
X670184D01*
X669921Y771137D01*
G01X674846Y787137D02*
X669921D01*
G01X684449Y1116338D02*
X682579Y1114468D01*
G01X680709Y1116338D02*
X678839Y1114468D01*
G01X676968Y1116338D02*
X675098Y1114468D01*
G01X684449Y1217322D02*
X686319Y1215452D01*
G01X673228Y1213582D02*
X671358Y1211712D01*
G01X673228Y1217322D02*
X675098Y1215452D01*
G01X703799Y99961D02*
X699024D01*
X696859Y102126D01*
Y103411D01*
G01X703799Y97599D02*
X697321D01*
X697253Y97667D01*
G01D02*
X693984D01*
G01X703799Y92874D02*
X694886D01*
X692649Y95111D01*
G01X696859Y103411D02*
X693782D01*
G01X689800Y102495D02*
Y106495D01*
G01X693782Y106561D02*
X697018D01*
G01X689800Y106495D02*
X693716D01*
X693782Y106561D01*
G01X687700Y143762D02*
X690930D01*
G01X689925Y225055D02*
Y229782D01*
X689151Y230556D01*
G01X694012Y232984D02*
Y231180D01*
X693406Y230574D01*
Y227824D01*
G01D02*
Y227724D01*
X691894Y226212D01*
Y225055D01*
G01X689777Y232959D02*
X689151Y232333D01*
Y230556D01*
G01X695713Y241681D02*
Y244297D01*
G01X692563Y241681D02*
X691922Y241040D01*
Y233636D01*
X692574Y232984D01*
X694012D01*
G01X687360Y253198D02*
X690504D01*
G01X692167Y250599D02*
X691813Y250245D01*
X687360D01*
G01X690504Y253198D02*
X692008D01*
X692363Y252843D01*
Y250795D01*
X692167Y250599D01*
G01X778502Y342319D02*
X780990D01*
X781490Y342819D01*
Y354861D01*
X779210Y357141D01*
X725786D01*
X712227Y370700D01*
X690156D01*
X687055Y373801D01*
Y376456D01*
G01D02*
Y378158D01*
X687775Y378878D01*
Y380718D01*
G01Y384718D02*
Y380718D01*
G01X690925Y384718D02*
X716642D01*
X716950Y384410D01*
X721810D01*
X721900Y384500D01*
G01X690925Y392718D02*
X700906D01*
X702046Y393858D01*
G01X690925Y396718D02*
Y392718D01*
G01Y388718D02*
X699155D01*
X699989Y387884D01*
X708305D01*
G01X690925Y380718D02*
X720615D01*
X721676Y379657D01*
X723404D01*
G01X687775Y388718D02*
Y389644D01*
X688642Y390511D01*
X704815D01*
X705800Y391496D01*
X723440D01*
G01X690925Y404718D02*
X713156D01*
X719291Y398583D01*
X723440D01*
G01X690925Y400718D02*
X709905D01*
G01X690925Y408718D02*
X712721D01*
X717105Y404334D01*
X717420D01*
G01X690925Y412718D02*
X699647D01*
X699685Y412756D01*
X715313D01*
X717105Y410964D01*
G01X687261Y549700D02*
Y553700D01*
G01D02*
Y557700D01*
G01X700364Y620788D02*
X697034D01*
X694798Y623024D01*
Y654998D01*
X698043Y658243D01*
X700383D01*
X700926Y657700D01*
X707449D01*
X711328Y653821D01*
G01X703117Y633786D02*
Y631449D01*
X700364Y628696D01*
G01D02*
Y623938D01*
G01X703188Y650671D02*
X699188D01*
G01X700164Y640872D02*
Y645900D01*
G01D02*
Y647895D01*
X699188Y648871D01*
Y650671D01*
G01X699789Y697094D02*
X703680D01*
G01X699789D02*
X693184D01*
X693163Y697073D01*
G01X699789Y702212D02*
X703600D01*
G01X688728Y703509D02*
X695340D01*
X696637Y702212D01*
X699789D01*
G01X704010Y709303D02*
X700803D01*
X699272Y707772D01*
G01X707663Y702212D02*
X709477D01*
X709902Y702637D01*
Y704430D01*
X708691Y705641D01*
X701403D01*
X699272Y707772D01*
G01X692356Y764614D02*
X689882Y762140D01*
X687146D01*
G01X691991Y759581D02*
X687146D01*
G01X692155Y778974D02*
X690676Y777495D01*
X687146D01*
G01X692221Y773449D02*
X690734Y774936D01*
X687146D01*
G01X697539Y1215452D02*
X695669Y1213582D01*
G01X701279Y1215452D02*
X699409Y1213582D01*
G01X703799Y90512D02*
X707911D01*
X708049Y90650D01*
G01X703799Y88150D02*
X710896D01*
X713361Y90615D01*
G01X717732Y95236D02*
X721909D01*
G01Y99961D02*
X717682D01*
G01X707799Y95236D02*
X703799D01*
G01X708305Y387884D02*
X714804D01*
X716054Y389134D01*
X727391D01*
G01X702046Y393858D02*
X727391D01*
G01X709905Y400718D02*
X712791D01*
X717288Y396221D01*
X727391D01*
G01X717420Y404334D02*
Y404019D01*
X720494Y400945D01*
X727391D01*
G01X717105Y410964D02*
X718837D01*
X720629Y412756D01*
X727391D01*
G01X706211Y453873D02*
Y449873D01*
G01Y445873D02*
Y443426D01*
X706681Y442956D01*
X709781D01*
G01X706211Y449873D02*
Y445873D01*
G01X709361Y453873D02*
X716847D01*
X719612Y451108D01*
G01X706211Y465874D02*
Y462859D01*
G01X709361Y458859D02*
X714833D01*
X715237Y458455D01*
X719051D01*
G01X709361Y462859D02*
Y458859D01*
G01X705396Y546712D02*
X702448D01*
G01X775746Y545912D02*
Y547424D01*
X775196Y547974D01*
X764189D01*
X761392Y545177D01*
X720078D01*
X716379Y548876D01*
X706448D01*
X705396Y547824D01*
Y546712D01*
G01X727391Y540335D02*
X717840D01*
X711463Y546712D01*
G01X708546D02*
Y542712D01*
G01X711463Y546712D02*
X708546D01*
G01X708364Y620788D02*
X713206D01*
G01D02*
X715600D01*
X718257Y623445D01*
X727391D01*
G01X704364Y623938D02*
Y626964D01*
X706070Y628670D01*
G01X708364Y623938D02*
X704364D01*
G01X706070Y628670D02*
Y633786D01*
G01X703117Y640872D02*
Y643255D01*
X704062Y644200D01*
X705212D01*
X706953Y645941D01*
G01D02*
X707188Y646176D01*
Y650671D01*
G01X711328Y653821D02*
X707188D01*
G01X703188D02*
X705156Y655789D01*
X705390D01*
G01X707669Y669913D02*
Y672917D01*
X708926Y674174D01*
Y675889D01*
G01X717214Y691609D02*
X711738D01*
G01D02*
X709863Y693484D01*
Y696352D01*
X709121Y697094D01*
X707663D01*
G01X707160Y709303D02*
X708455D01*
X710196Y707562D01*
G01D02*
Y709268D01*
X710877Y709949D01*
X713401D01*
G01D02*
Y706967D01*
X713382Y706948D01*
Y705312D01*
G01X707015Y728050D02*
Y738124D01*
X707063Y738172D01*
G01X726897Y750559D02*
X709482D01*
X707063Y748140D01*
Y738172D01*
G01X715607Y747977D02*
X722838D01*
X727131Y743684D01*
X729727D01*
G01X715607Y747977D02*
X713371D01*
X711450Y746056D01*
Y737919D01*
X714937Y734432D01*
G01X724771Y760137D02*
X716346D01*
G01D02*
X711784Y764699D01*
X709194D01*
G01Y767258D02*
X710847D01*
X713200Y766283D01*
X715346Y764137D01*
X719846D01*
G01X709194Y759581D02*
X711902D01*
X715346Y756137D01*
X719846D01*
G01X724771Y768137D02*
X724271Y768637D01*
X716346D01*
G01D02*
X715165Y769818D01*
X709194D01*
G01Y772377D02*
X714846D01*
X715106Y772637D01*
X719846D01*
G01X714370Y1116338D02*
X716240Y1118208D01*
G01X703149Y1112598D02*
X703150D01*
X705020Y1114468D01*
G01X710630Y1112598D02*
X712500Y1114468D01*
G01X714370Y1112598D02*
X716240Y1114468D01*
G01X703149Y1116338D02*
X703150D01*
X705020Y1118208D01*
G01X710630Y1116338D02*
X712500Y1118208D01*
G01X710630Y1217322D02*
X712500Y1215452D01*
G01X705019Y1215451D02*
X703149Y1217322D01*
G01X705019Y1211711D02*
X703149Y1213582D01*
G01X708760Y1211711D02*
X706890Y1213582D01*
G01X738471Y98198D02*
Y98073D01*
X736810Y96412D01*
X728034D01*
X726640Y95018D01*
Y92874D01*
G01D02*
X721909D01*
G01X721900Y384500D02*
X721990Y384410D01*
X727391D01*
G01X723404Y379657D02*
Y381157D01*
X724294Y382047D01*
X727391D01*
G01X723440Y391496D02*
X727391D01*
G01X723440Y398583D02*
X727391D01*
G01Y453681D02*
X722297D01*
X722097Y453881D01*
G01X719051Y458455D02*
X721463Y456043D01*
X727391D01*
G01X719612Y451108D02*
X721763Y448957D01*
X727391D01*
G01X720996Y442856D02*
X722372Y444232D01*
X727391D01*
G01Y446595D02*
X722097D01*
G01X720260Y696547D02*
X722473Y694334D01*
Y693718D01*
G01X720364Y691609D02*
X721348Y690625D01*
X724994D01*
G01D02*
Y693264D01*
X724540Y693718D01*
X722473D01*
G01X719846Y764137D02*
X724771D01*
G01X727921D02*
X740406D01*
X741992Y763480D01*
G01X743428Y772418D02*
X744265Y771581D01*
X745300Y769081D01*
Y761983D01*
X743014Y759697D01*
X728361D01*
X727921Y760137D01*
G01Y756137D02*
Y751583D01*
X726897Y750559D01*
G01X719846Y756137D02*
X724771D01*
G01X719846Y772637D02*
X724271D01*
X724771Y772137D01*
G01X742000Y768137D02*
X727921D01*
G01Y772137D02*
X729136Y773352D01*
X741993Y775909D01*
G01X729331Y1116338D02*
X731201Y1114468D01*
G01X733071Y1112598D02*
X734941Y1114468D01*
G01X725590Y1112598D02*
X727460Y1114468D01*
G01X718110Y1116338D02*
X719980Y1118208D01*
G01X718110Y1112598D02*
X719980Y1114468D01*
G01X718110Y1217322D02*
X719980Y1215452D01*
G01X731201Y1211712D02*
X729331Y1213582D01*
G01X734941Y1207972D02*
X733071Y1206102D01*
G01X725590Y1217322D02*
X725591D01*
X727461Y1215452D01*
G01X732170Y1625165D02*
X729600D01*
G01X732192Y1630030D02*
Y1625187D01*
X732170Y1625165D01*
G01X736155Y1622015D02*
X732170D01*
G01X733058Y1614451D02*
Y1617470D01*
X732268Y1618260D01*
G01D02*
X732170Y1618358D01*
Y1622015D01*
G01X732176Y1634485D02*
Y1630046D01*
X732192Y1630030D01*
G01X742471Y98198D02*
X738471D01*
G01X747975Y97475D02*
X745475D01*
G01X747975Y100625D02*
X752456D01*
G01X747975Y105087D02*
Y100625D01*
G01X753035Y141247D02*
X750110D01*
G01X746960D02*
X743131D01*
G01X744729Y146461D02*
X744472Y146204D01*
Y143740D01*
G01D02*
X743131Y142399D01*
Y141247D01*
G01X739161Y151540D02*
Y147540D01*
G01X744729Y149414D02*
X742989D01*
X741852Y148277D01*
G01D02*
X741580D01*
X740843Y147540D01*
X739161D01*
G01X742577Y259535D02*
Y256303D01*
G01X737249Y265701D02*
X738577Y264373D01*
Y262685D01*
G01X747352Y266114D02*
Y264678D01*
X746577Y263903D01*
Y262685D01*
G01X742336Y265896D02*
Y264086D01*
X742577Y263845D01*
Y262685D01*
G01X744825Y281982D02*
X742817Y279974D01*
Y277477D01*
G01X740849Y269603D02*
Y267575D01*
X740153Y266879D01*
X738427D01*
X737249Y265701D01*
G01X738884Y281716D02*
X740849Y279751D01*
Y277477D01*
G01X744785Y269603D02*
Y268681D01*
X747352Y266114D01*
G01X742817Y269603D02*
Y267599D01*
X742336Y267118D01*
Y265896D01*
G01X745630Y284908D02*
Y282787D01*
X744825Y281982D01*
G01X737630Y284908D02*
X741630D01*
G01X738884Y281716D02*
X740242D01*
X741630Y283104D01*
Y284908D01*
G01X747176Y317873D02*
X747214Y317911D01*
X751927D01*
G01X745502Y386772D02*
X751314D01*
X756086Y382000D01*
Y377912D01*
G01X745502Y391496D02*
X755086D01*
G01X745502Y384410D02*
X749606D01*
G01X745502Y382047D02*
X752785D01*
G01X745502Y389134D02*
X753452D01*
X756086Y386500D01*
G01X745502Y396221D02*
X754483D01*
X756174Y397912D01*
G01X745502Y393858D02*
X749444D01*
G01X745502Y400945D02*
X750531D01*
X753086Y403500D01*
G01X745502Y398583D02*
X751086D01*
G01X745502Y412756D02*
X751330D01*
X755086Y409000D01*
G01X745502Y444232D02*
X754271D01*
X754593Y443910D01*
X761662D01*
X761984Y444232D01*
X773027D01*
X776094Y441165D01*
G01X774099Y446595D02*
X763675D01*
X762370Y447900D01*
X754571D01*
X753266Y446595D01*
X745502D01*
G01Y451319D02*
X743597D01*
X742239Y449961D01*
X735599D01*
G01X745502Y448957D02*
X753391D01*
X753494Y449060D01*
X763510D01*
X763613Y448957D01*
X768460D01*
G01X739316Y458572D02*
X741088Y456800D01*
X742932D01*
X743689Y456043D01*
X745502D01*
G01Y540335D02*
X767751D01*
G01X767842Y622912D02*
X759625D01*
X759092Y623445D01*
X745502D01*
G01X740357Y736204D02*
X740393Y736240D01*
X747779D01*
X808465Y711102D01*
X822424Y697143D01*
X847301D01*
X855117Y704959D01*
Y709138D01*
X854616Y709639D01*
X852284D01*
G01X740357Y739944D02*
X744302D01*
X811776Y711995D01*
X822338Y701433D01*
X827620D01*
X828969Y702782D01*
X840111D01*
X841367Y704038D01*
Y709138D01*
X841868Y709639D01*
X843284D01*
G01X736811Y1112598D02*
X738681Y1114468D01*
G01X740551Y1112598D02*
X742421Y1114468D01*
G01X740551Y1138779D02*
X742421Y1136909D01*
G01X740551Y1142519D02*
X742421Y1140649D01*
G01X744291Y1149999D02*
X746161Y1148129D01*
G01X740551Y1146259D02*
X738681Y1144389D01*
G01X740551Y1149999D02*
X742421Y1148129D01*
G01X744291Y1146259D02*
X742421Y1144389D01*
G01X744291Y1142519D02*
X746161Y1140649D01*
G01X751772Y1138779D02*
X749902Y1140649D01*
G01X751772Y1153740D02*
X749902Y1155610D01*
G01X751772Y1146259D02*
X749902Y1148129D01*
G01X738681Y1200491D02*
X740551Y1198621D01*
G01X742421Y1204232D02*
X744291Y1206102D01*
G01X742421Y1211712D02*
X744291Y1213582D01*
G01X742421Y1215452D02*
X744291Y1217322D01*
G01X742421Y1207972D02*
X740551Y1209842D01*
G01X738681Y1215452D02*
X736811Y1217322D01*
G01X740551Y1206102D02*
X738681Y1207972D01*
G01X740551Y1213582D02*
X738681Y1211712D01*
G01X736702Y1431659D02*
X745638D01*
X748467Y1434488D01*
X765657D01*
X768910Y1437741D01*
G01X765713Y1437365D02*
Y1438041D01*
X758266Y1445488D01*
X751357D01*
X747528Y1441659D01*
G01X751140Y1586885D02*
Y1588091D01*
X749786Y1589445D01*
Y1590517D01*
G01X747140Y1586885D02*
X751140D01*
G01X749786Y1590517D02*
X749704Y1590599D01*
Y1594417D01*
G01X742224D02*
Y1595587D01*
X739945Y1597866D01*
X738775D01*
G01X742224Y1604731D02*
Y1607540D01*
X739358Y1610406D01*
Y1611892D01*
G01X736067D02*
X735975Y1611800D01*
Y1606600D01*
G01X749704Y1604731D02*
Y1608631D01*
G01D02*
X748924Y1609411D01*
Y1611793D01*
G01X738775Y1597866D02*
X737451Y1599190D01*
X735392D01*
G01X754862Y1592302D02*
Y1595919D01*
X751502Y1599279D01*
X747895D01*
X745964Y1601210D01*
Y1604731D01*
G01X739358Y1611892D02*
X736067D01*
G01X744924Y1611793D02*
X748924D01*
G01X748997Y1624485D02*
X752584Y1620898D01*
X753985D01*
G01X735342Y1630030D02*
Y1627421D01*
X737730Y1625033D01*
X743854D01*
X744188Y1624699D01*
G01X748997Y1621335D02*
X748985Y1621323D01*
X748137D01*
X744761Y1624699D01*
X744188D01*
G01X759036Y1622460D02*
X755043Y1618467D01*
X751865D01*
X748997Y1621335D01*
G01X752150Y1633809D02*
X752125Y1633784D01*
X747590D01*
G01D02*
X747580Y1633794D01*
X743331D01*
G01X765297Y60513D02*
Y64722D01*
G01D02*
Y68892D01*
X761627Y72562D01*
X756567D01*
G01D02*
X756370D01*
X753372Y69564D01*
Y68581D01*
G01Y80581D02*
Y79618D01*
X756403Y76587D01*
X756567D01*
G01D02*
X764237D01*
X767857Y72967D01*
Y64722D01*
G01X751017Y76587D02*
X753417D01*
G01X751017Y72615D02*
X751045Y72587D01*
X753417D01*
Y72562D01*
G01X765425Y85731D02*
X765297Y85603D01*
Y81848D01*
G01X765982Y91951D02*
Y94351D01*
G01Y88801D02*
X765425Y88244D01*
Y85731D01*
G01X752456Y100625D02*
X753822Y99259D01*
X757378D01*
G01X756829Y112083D02*
Y112402D01*
X758915Y114488D01*
G01X761118Y107921D02*
Y103621D01*
G01X753035Y141247D02*
X755835D01*
X756682Y140400D01*
X766684D01*
X768932Y142648D01*
X770454D01*
G01X762308Y158194D02*
Y148325D01*
X761808Y147825D01*
X757191D01*
X756622Y147256D01*
Y145768D01*
G01X765267Y157370D02*
Y148980D01*
X766496Y147754D01*
X768607D01*
G01X759772Y145768D02*
Y143868D01*
X759422Y143518D01*
X757522D01*
G01X770454Y139695D02*
X771906D01*
X772500Y140289D01*
Y144200D01*
X772000Y144700D01*
X768599D01*
X766064Y142165D01*
X757749D01*
X757522Y142392D01*
Y143518D01*
G01X762308Y158194D02*
X762867Y158753D01*
Y158966D01*
X769445Y165544D01*
X796472D01*
X803821Y158195D01*
X899573D01*
G01X751815Y149414D02*
X756268D01*
X756622Y149768D01*
G01X751815Y152367D02*
X756616D01*
X756622Y152373D01*
G01D02*
Y149768D01*
G01X763558Y168665D02*
Y172665D01*
G01X757268Y179897D02*
Y176034D01*
X760637Y172665D01*
G01D02*
X763558D01*
G01Y176665D02*
Y180665D01*
G01X760574Y178560D02*
Y179904D01*
G01X763558Y180665D02*
X761335D01*
X760574Y179904D01*
G01D02*
Y180204D01*
X758912Y181866D01*
X757268D01*
G01X754709Y188362D02*
Y192490D01*
G01D02*
X756567Y194348D01*
X758730D01*
X759384Y195002D01*
Y196620D01*
G01X763558Y196665D02*
Y192665D01*
G01X757268Y185803D02*
Y189278D01*
X758175Y190185D01*
X759984D01*
G01D02*
Y191730D01*
X760919Y192665D01*
X763558D01*
G01Y184665D02*
X762727Y183834D01*
X760464D01*
G01D02*
X757268D01*
G01X753182Y198671D02*
X755233Y196620D01*
X756234D01*
G01X766708Y196665D02*
Y198105D01*
X765976Y198837D01*
X757984D01*
X756281Y200540D01*
X751106D01*
X750606Y200040D01*
Y192361D01*
X750667Y192300D01*
G01X760754Y200864D02*
X763653D01*
G01X756879Y209229D02*
X757601D01*
X758189Y208641D01*
Y203429D01*
X760754Y200864D01*
G01X763653Y212864D02*
X763244Y212455D01*
X760843D01*
G01X756879Y213166D02*
X758565D01*
X759276Y212455D01*
X760843D01*
G01X763653Y204864D02*
Y208864D01*
G01X760777Y207037D02*
X762604Y208864D01*
X763653D01*
G01X756879Y211197D02*
X758332D01*
X760777Y208752D01*
Y207037D01*
G01X763653Y224536D02*
Y221864D01*
G01X756879Y217103D02*
X758892D01*
X763653Y221864D01*
G01X756919Y319290D02*
X753306D01*
X751927Y317911D01*
G01D02*
X753107Y316731D01*
X756919D01*
G01X769349Y321890D02*
X769308Y321849D01*
X764399D01*
G01Y319290D02*
X762595D01*
X762125Y319760D01*
Y322824D01*
X762800Y323499D01*
Y325308D01*
X761108Y327000D01*
X755883D01*
X752470Y330413D01*
Y348366D01*
X758065Y353961D01*
X759624D01*
G01X760371Y344878D02*
X755275D01*
X754805Y344408D01*
Y339559D01*
G01D02*
Y337606D01*
X756087Y336324D01*
X767714D01*
G01X759252Y1142519D02*
X761122Y1144389D01*
G01X759252Y1149999D02*
X761122Y1151869D01*
G01X755512Y1153740D02*
X753642Y1155610D01*
G01X762992Y1149999D02*
X764862Y1151869D01*
G01X762992Y1142519D02*
X764862Y1144389D01*
G01X765850Y1407617D02*
X783621D01*
X793548Y1397690D01*
G01X754354Y1417617D02*
X777266D01*
X778685Y1416198D01*
G01X768812Y1453306D02*
X766566D01*
X764973Y1451713D01*
Y1447410D01*
X765756Y1446627D01*
X767512D01*
G01X759802Y1595014D02*
Y1590864D01*
G01X763542Y1595014D02*
Y1590186D01*
G01X763145Y1586863D02*
X759216D01*
X759169Y1586910D01*
G01D02*
X755198D01*
X755187Y1586899D01*
G01D02*
X754862Y1587224D01*
Y1592302D01*
G01X767452Y1616917D02*
X765930D01*
X765430Y1616417D01*
Y1614352D01*
X764845Y1613767D01*
X763452D01*
G01X753985Y1620898D02*
Y1626259D01*
X757382Y1629656D01*
Y1630526D01*
X759036Y1632180D01*
Y1633090D01*
G01X752150Y1633809D02*
X753482Y1635141D01*
X757744D01*
X759036Y1633849D01*
Y1633090D01*
G01X773822Y1633300D02*
X771951Y1635171D01*
X767668D01*
X766516Y1634019D01*
Y1633090D01*
G01X767857Y64722D02*
X768157Y64422D01*
Y60438D01*
G01X773838Y86012D02*
X770711Y82885D01*
Y81848D01*
G01X768979Y86046D02*
X767857Y84924D01*
Y81848D01*
G01X769931Y91879D02*
Y94279D01*
G01X773838Y88824D02*
Y86012D01*
G01X769931Y88729D02*
Y86998D01*
X768979Y86046D01*
G01X773393Y107899D02*
Y109059D01*
X775118Y110784D01*
G01D02*
X775128Y110794D01*
Y113684D01*
G01X781393Y107899D02*
Y109509D01*
X780118Y110784D01*
G01X777096Y113684D02*
Y111534D01*
X777846Y110784D01*
X780118D01*
G01X777393Y107899D02*
X781393D01*
G01X775418Y130898D02*
Y133200D01*
X775700Y133482D01*
Y135000D01*
X775418Y135282D01*
Y145177D01*
X772845Y147754D01*
X768607D01*
G01X769418Y127748D02*
X769641Y127525D01*
Y124315D01*
X769609Y124283D01*
G01X773160Y121558D02*
Y123126D01*
X772003Y124283D01*
X769609D01*
G01X779418Y127748D02*
Y126287D01*
X779697Y126008D01*
Y124663D01*
G01X777096Y121558D02*
Y124163D01*
X777596Y124663D01*
X779697D01*
G01X775418Y127748D02*
X774675Y127005D01*
Y124879D01*
G01X775128Y121558D02*
Y123785D01*
X774675Y124879D01*
G01X779519Y153296D02*
Y150265D01*
X781067Y148717D01*
X787192D01*
G01X783441Y138838D02*
X781041D01*
G01D02*
X778040D01*
X777540Y138338D01*
Y136742D01*
G01X768607Y150904D02*
Y154865D01*
G01D02*
X773544D01*
G01D02*
X776388Y157709D01*
X782759D01*
X783259Y158209D01*
Y161958D01*
G01X766708Y192665D02*
X769351D01*
G01X766708Y188665D02*
X768733D01*
X769464Y187934D01*
Y186778D01*
G01D02*
Y185398D01*
X768731Y184665D01*
X766708D01*
G01X766803Y208864D02*
X769383D01*
G01X777888Y242078D02*
X770616D01*
X768128Y244566D01*
Y255458D01*
X771550Y258880D01*
X822160D01*
G01X782737Y232859D02*
Y232681D01*
X786772Y228646D01*
G01X784867Y242078D02*
X781038D01*
G01X782636Y247292D02*
X782379Y247035D01*
Y244571D01*
G01D02*
X781038Y243230D01*
Y242078D01*
G01X777068Y252371D02*
Y248371D01*
G01X782636Y250245D02*
X780896D01*
X779759Y249108D01*
G01D02*
X779487D01*
X778750Y248371D01*
X777068D01*
G01X769349Y318740D02*
Y314890D01*
G01X776513Y312849D02*
X774206D01*
X772165Y314890D01*
G01D02*
X769349D01*
G01Y321890D02*
Y324518D01*
G01X777360Y328844D02*
X773675D01*
X769349Y324518D01*
G01X769033Y342319D02*
X774502D01*
G01D02*
X778502D01*
G01X777360Y332584D02*
X772162D01*
G01X778502Y345469D02*
Y348015D01*
G01X772859Y347937D02*
Y345713D01*
X773103Y345469D01*
X774502D01*
G01X776094Y441165D02*
X777722Y440491D01*
X783904D01*
X784667Y441254D01*
Y442498D01*
G01X774099Y446595D02*
X776017D01*
X778015Y444597D01*
X784198D01*
X784699Y445098D01*
Y446510D01*
G01X768460Y448957D02*
X776771D01*
X777252Y448476D01*
X784199D01*
X784699Y448976D01*
Y450510D01*
G01X775746Y545912D02*
X778980Y542678D01*
X788313D01*
X795064Y549429D01*
Y552165D01*
X796000Y553101D01*
G01X772596Y545912D02*
Y541912D01*
G01X767751Y540335D02*
X771019D01*
X772596Y541912D01*
G01X781429Y545017D02*
X780371Y546075D01*
Y550137D01*
G01X789771Y551381D02*
X785559D01*
X784315Y550137D01*
X780371D01*
G01X778860Y626912D02*
X775746D01*
G01X772596D02*
Y622912D01*
G01X767842D02*
X772596D01*
G01X780265Y883294D02*
X775793D01*
X770545Y888542D01*
Y900475D01*
G01X792975Y923808D02*
X779908D01*
X770545Y914445D01*
Y900475D01*
G01X781479Y933808D02*
X773347D01*
X771976Y935179D01*
Y948299D01*
X776423Y952746D01*
X813323D01*
X824414Y941655D01*
Y939655D01*
G01X774212Y1149999D02*
X772342Y1148129D01*
G01X774212Y1157480D02*
X772342Y1155610D01*
G01X781693Y1153740D02*
X783563Y1151870D01*
G01X777953Y1153740D02*
X779823Y1151870D01*
G01X777953Y1146259D02*
X779823Y1144389D01*
G01X781693Y1146259D02*
X783563Y1144389D01*
G01X770472Y1157480D02*
X768602Y1155610D01*
G01X770472Y1142519D02*
X768602Y1140649D01*
G01X774212Y1142519D02*
X772342Y1140649D01*
G01X770472Y1149999D02*
X768602Y1148129D01*
G01X777953Y1161220D02*
X779823Y1159350D01*
G01X781693Y1161220D02*
X783563Y1159350D01*
G01X781693Y1176180D02*
X783563Y1174310D01*
G01X777953Y1176180D02*
X779823Y1174310D01*
G01X781693Y1183661D02*
X783563Y1181791D01*
G01X777953Y1183661D02*
X779823Y1181791D01*
G01X781693Y1191141D02*
X783563Y1189271D01*
G01X777953Y1191141D02*
X779823Y1189271D01*
G01X774707Y1449870D02*
Y1447042D01*
X775512Y1446237D01*
X777260D01*
G01X767512Y1449777D02*
X768460D01*
X770338Y1451655D01*
X772922D01*
X774707Y1449870D01*
G01X771635Y1454305D02*
Y1456745D01*
X772678Y1457788D01*
X777845Y1459928D01*
X779716D01*
X781578Y1458066D01*
G01D02*
X783620Y1460108D01*
G01X781124Y1583553D02*
X781110Y1583567D01*
Y1589422D01*
G01D02*
X777033D01*
G01X781110Y1592572D02*
Y1595254D01*
G01X767282Y1604660D02*
Y1609004D01*
X768361Y1610083D01*
G01D02*
X767452Y1610992D01*
Y1613767D01*
G01X781110Y1595254D02*
X781059Y1595305D01*
Y1598260D01*
G01X778500Y1605740D02*
Y1607541D01*
X777059Y1608982D01*
G01D02*
X775941Y1607864D01*
Y1605740D01*
G01X784046Y1600438D02*
X779093D01*
X778500Y1599845D01*
Y1598260D01*
G01X767452Y1616917D02*
X771383D01*
G01X778358Y1633276D02*
X778484Y1633150D01*
X786099D01*
X787885Y1631364D01*
G01X773822Y1633300D02*
X778334D01*
X778358Y1633276D01*
G01X796346Y97667D02*
X799615D01*
G01X806161Y92874D02*
X797248D01*
X795011Y95111D01*
G01X796144Y103411D02*
X799221D01*
G01X792162Y102495D02*
Y106495D01*
G01X796144Y106561D02*
X799380D01*
G01X792162Y106495D02*
X796078D01*
X796144Y106561D01*
G01X783472Y127753D02*
Y126313D01*
X784678Y125107D01*
G01X783472Y130903D02*
X783441Y130934D01*
Y134838D01*
G01X790062Y143762D02*
X793292D01*
G01X787192Y148717D02*
X789345D01*
X790062Y148000D01*
Y146912D01*
G01X783441Y134838D02*
Y138838D01*
G01X796374Y232984D02*
Y231180D01*
X795768Y230574D01*
Y227824D01*
G01D02*
Y227724D01*
X794256Y226212D01*
Y225055D01*
G01X792287D02*
Y229782D01*
X791513Y230556D01*
G01X788350Y225055D02*
Y227068D01*
X786772Y228646D01*
G01X798075Y241681D02*
Y244297D01*
G01X794925Y241681D02*
X794284Y241040D01*
Y233484D01*
X794784Y232984D01*
X796374D01*
G01X792139Y232959D02*
X791513Y232333D01*
Y230556D01*
G01X789722Y250245D02*
X794175D01*
X794529Y250599D01*
G01X789722Y253198D02*
Y256394D01*
G01D02*
X792254D01*
X794725Y253923D01*
Y250795D01*
X794529Y250599D01*
G01X795445Y356950D02*
X801417D01*
X807999Y350368D01*
X811902D01*
G01X788549Y442510D02*
X784679D01*
X784667Y442498D01*
G01X788549Y446510D02*
X784699D01*
G01X788549Y450510D02*
X784699D01*
G01X796000Y553101D02*
X798036Y555137D01*
X799371D01*
G01X793511Y560043D02*
X796055D01*
X797811Y558287D01*
X799371D01*
G01X809500Y887500D02*
Y883001D01*
X799793Y873294D01*
X791761D01*
G01X810500Y900000D02*
X803794Y893294D01*
X791761D01*
G01X792975Y943808D02*
X819139D01*
X822309Y940638D01*
Y938463D01*
X824272Y936500D01*
X826534D01*
X829617Y939583D01*
G01X840423Y962269D02*
X839359Y963333D01*
Y992094D01*
X832033Y999420D01*
X796103D01*
X788600Y1006923D01*
G01X798835Y1137129D02*
X797339D01*
X796338Y1138130D01*
G01X792277Y1173065D02*
X790987Y1171775D01*
Y1138100D01*
X791958Y1137129D01*
X793842D01*
G01X798835Y1140279D02*
Y1141313D01*
X800160Y1142638D01*
X809160D01*
X809188Y1142666D01*
X809632D01*
G01X800937Y1146071D02*
X799330D01*
X798792Y1146609D01*
X797160D01*
G01X799287Y1161400D02*
X796987D01*
X795787Y1160200D01*
Y1153249D01*
X795794Y1153242D01*
G01X798353D02*
Y1150166D01*
X797787Y1149600D01*
X796887D01*
X793842Y1146555D01*
Y1143384D01*
G01D02*
Y1140279D01*
G01X798542Y1181970D02*
X796900Y1180328D01*
Y1174300D01*
X798353Y1172847D01*
Y1172011D01*
G01D02*
Y1167808D01*
G01X798542Y1185120D02*
Y1188345D01*
G01X792382Y1191664D02*
X792564Y1191482D01*
Y1189669D01*
X793617Y1188616D01*
X795159D01*
G01X798324Y1195034D02*
Y1191974D01*
X801125Y1189173D01*
X825926D01*
X827856Y1187243D01*
Y1127637D01*
X825806Y1125587D01*
Y1123055D01*
X825336Y1122585D01*
X821250D01*
X820780Y1122115D01*
Y1120585D01*
X821250Y1120115D01*
X825336D01*
X825806Y1119645D01*
Y1118301D01*
X827856Y1116251D01*
G01X795418Y1203343D02*
X794533Y1202458D01*
Y1195766D01*
G01X798324Y1198184D02*
X796407Y1196267D01*
Y1194746D01*
X795159Y1193498D01*
Y1191766D01*
G01X798324Y1198184D02*
Y1200612D01*
X797404Y1201532D01*
Y1211899D01*
X796904Y1212399D01*
X795411D01*
G01D02*
X794889D01*
X794106Y1211616D01*
Y1210240D01*
X795418Y1208928D01*
Y1206493D01*
G01X796972Y1397753D02*
X796909Y1397690D01*
X793548D01*
G01X803222Y1443778D02*
Y1439418D01*
X801559Y1437755D01*
Y1434631D01*
X798601Y1431673D01*
G01X783324Y1427432D02*
Y1431432D01*
G01D02*
X787623D01*
X790754Y1434563D01*
Y1441399D01*
G01X787694Y1442749D02*
X790354Y1445409D01*
X791316D01*
X793287Y1447380D01*
X794316D01*
X795094Y1448158D01*
X795791D01*
G01X783324Y1435432D02*
X785312D01*
X787694Y1437814D01*
Y1442749D01*
G01X790361Y1447895D02*
X791380Y1448914D01*
X794075D01*
X795091Y1449930D01*
X795791D01*
G01X783324Y1439432D02*
X784682D01*
X785502Y1440252D01*
Y1443303D01*
X790094Y1447895D01*
X790361D01*
G01X795791Y1446386D02*
X795317D01*
X794927Y1445996D01*
X793837D01*
X790754Y1442913D01*
Y1441399D01*
G01X793994Y1441499D02*
X795628D01*
X797907Y1443778D01*
G01X794005Y1464178D02*
X798221D01*
X799679Y1462720D01*
Y1461396D01*
G01X790296Y1463459D02*
X791668Y1462087D01*
X797742D01*
X797907Y1461922D01*
Y1461396D01*
G01X783620Y1460108D02*
X785809Y1457919D01*
X788275D01*
X788698Y1458342D01*
X793835D01*
X795161Y1457016D01*
X795791D01*
G01X787038Y1460533D02*
X789223D01*
X789940Y1459816D01*
X794381D01*
X795409Y1458788D01*
X795791D01*
G01X797083Y1467883D02*
X798332Y1466634D01*
X798631D01*
X801450Y1463815D01*
Y1461396D01*
G01X787447Y1599611D02*
X784873D01*
X784046Y1600438D01*
G01X791610Y1599588D02*
X787470D01*
X787447Y1599611D01*
G01X787885Y1631364D02*
X789769Y1629480D01*
Y1623876D01*
G01X806161Y99961D02*
X801386D01*
X799221Y102126D01*
Y103411D01*
G01X806161Y97599D02*
X799683D01*
X799615Y97667D01*
G01X806161Y90512D02*
X810273D01*
X810411Y90650D01*
G01X806161Y88150D02*
X813258D01*
X815723Y90615D01*
G01X810161Y95236D02*
X806161D01*
G01X815052Y309368D02*
X822477D01*
G01X815052Y305368D02*
X817456D01*
G01X807052D02*
X809490D01*
G01D02*
X811902D01*
G01X807052Y309368D02*
X808230D01*
X809466Y310604D01*
G01D02*
X810702Y309368D01*
X811902D01*
G01X815052Y317368D02*
X819977D01*
G01X817100Y319600D02*
X816820D01*
X815052Y321368D01*
G01Y313368D02*
X817456D01*
G01X815052Y325368D02*
X816976D01*
X817696Y324648D01*
X819977D01*
G01X807052Y325368D02*
X809490D01*
G01D02*
X811902D01*
G01X807052Y317368D02*
X809490D01*
G01D02*
X811902D01*
G01Y313368D02*
X811440Y313830D01*
X809489D01*
G01D02*
X807514D01*
X807052Y313368D01*
G01X811902Y321368D02*
X809490D01*
G01D02*
X807052D01*
G01X815052Y329368D02*
X817213Y327207D01*
X825977D01*
G01X815052Y333368D02*
X818977D01*
X820196Y332149D01*
G01X807052Y337368D02*
X823477D01*
X828520Y332325D01*
X832961D01*
G01X807052Y329368D02*
X808143Y330459D01*
X809457D01*
G01D02*
X810811D01*
X811902Y329368D01*
G01Y333368D02*
X809490D01*
G01D02*
X807052D01*
G01X811902Y346368D02*
Y347904D01*
X812286Y348288D01*
X822404D01*
X822626Y348066D01*
G01X807052Y346368D02*
X811902D01*
G01X815052Y350368D02*
X824218D01*
X829485Y345101D01*
G01X815052Y350368D02*
Y354738D01*
X815049Y354741D01*
G01X804536Y448334D02*
X802136D01*
G01X810749Y443045D02*
X812126Y444422D01*
Y447488D01*
X812714Y448076D01*
X813876D01*
G01X807686Y444334D02*
X809460D01*
X810749Y443045D01*
G01X813876Y452012D02*
X811771D01*
X810453Y453330D01*
G01X807686Y452334D02*
X809457D01*
X810453Y453330D01*
G01X813876Y450044D02*
X812236D01*
X810406Y448214D01*
G01X807686Y448334D02*
X809118D01*
X809238Y448214D01*
X810406D01*
G01X828272Y535462D02*
X825359Y538375D01*
X821594D01*
X801682Y558287D01*
X799371D01*
G01D02*
Y562137D01*
G01X822151Y752283D02*
X819582Y749714D01*
X810850D01*
X810204Y749068D01*
Y728786D01*
X822938Y716052D01*
X824671D01*
X827284Y713439D01*
G01X813821Y735296D02*
X812910Y734385D01*
Y731730D01*
X813902Y730738D01*
G01X816988Y742502D02*
X815465Y740979D01*
X813678D01*
G01X813821Y738446D02*
Y740836D01*
X813678Y740979D01*
G01X813635Y762000D02*
Y770363D01*
X803500Y794832D01*
Y852001D01*
X808499Y857000D01*
X815000D01*
X816000Y858000D01*
X816037D01*
X816038Y858001D01*
Y859199D01*
G01X817365Y756827D02*
X815470Y758722D01*
Y760104D01*
X816085Y761589D01*
Y762253D01*
X815470Y763737D01*
Y771485D01*
X805300Y796038D01*
Y850900D01*
X809980Y855580D01*
X826568D01*
X828134Y857146D01*
Y859281D01*
G01X814069Y848569D02*
Y846361D01*
X811899Y844191D01*
Y840919D01*
G01Y836919D02*
Y840919D01*
G01X814069Y848569D02*
Y850896D01*
X815749Y852576D01*
X822916D01*
G01X814800Y876864D02*
X811507D01*
X810010Y875367D01*
Y870962D01*
X811279Y869693D01*
G01D02*
X813379D01*
X814516Y870830D01*
X816027D01*
G01X812249Y893419D02*
X809500Y890670D01*
Y887500D01*
G01X816749Y900919D02*
X815830Y900000D01*
X810500D01*
G01X814835Y1134729D02*
Y1137129D01*
G01X806835D02*
Y1134729D01*
G01X810835Y1137129D02*
Y1135415D01*
X812000Y1134250D01*
Y1131103D01*
X814966Y1128137D01*
X819026D01*
G01X809632Y1142666D02*
X809801Y1142835D01*
Y1146842D01*
G01X800913Y1153242D02*
Y1160674D01*
X800187Y1161400D01*
X799287D01*
G01X800913Y1153242D02*
Y1146095D01*
X800937Y1146071D01*
G01X818835Y1140279D02*
X814835D01*
G01X815215Y1146842D02*
Y1154655D01*
X817964Y1157404D01*
G01X814835Y1140279D02*
X815215Y1140659D01*
Y1146842D01*
G01X802835Y1140279D02*
X806835D01*
G01D02*
X810835D01*
G01D02*
X812655Y1142099D01*
Y1146842D01*
G01D02*
Y1156396D01*
X811507Y1157544D01*
G01X799287Y1161400D02*
Y1162500D01*
X800913Y1164126D01*
Y1167808D01*
G01X811501Y1175090D02*
Y1173978D01*
X811018Y1173495D01*
Y1171120D01*
G01D02*
Y1168768D01*
X810018Y1167768D01*
G01X812655Y1163968D02*
Y1166945D01*
X811832Y1167768D01*
X810018D01*
G01X816826Y1175138D02*
X815367D01*
X814867Y1174638D01*
Y1171120D01*
G01D02*
X815037Y1170950D01*
Y1167768D01*
G01D02*
X815215Y1167590D01*
Y1163968D01*
G01X811507Y1157544D02*
X809037D01*
X807288Y1159293D01*
Y1170540D01*
X807868Y1171120D01*
G01X802606Y1175026D02*
X803472Y1174160D01*
Y1167808D01*
G01X799020Y1175975D02*
X799519D01*
X800500Y1176956D01*
Y1184100D01*
X801450Y1185050D01*
X802558D01*
G01X814170Y1185205D02*
X811529D01*
G01Y1182055D02*
X807529D01*
G01X807501Y1178240D02*
X805713D01*
X805212Y1178741D01*
Y1180175D01*
G01D02*
Y1181255D01*
X806012Y1182055D01*
X807529D01*
G01X807501Y1175090D02*
X811501D01*
G01X805519Y1187215D02*
X807529Y1185205D01*
G01X802558Y1181900D02*
Y1175074D01*
X802606Y1175026D01*
G01X811489Y1203443D02*
Y1201047D01*
X811485Y1201043D01*
G01D02*
X811487Y1201041D01*
Y1198569D01*
G01X807489Y1201043D02*
Y1201151D01*
G01D02*
X807487Y1201149D01*
Y1198569D01*
G01X807489Y1201151D02*
Y1203443D01*
G01X830356Y1116251D02*
Y1187621D01*
X826879Y1191098D01*
X802794D01*
X800068Y1193824D01*
Y1202618D01*
X799230Y1203456D01*
G01X803604Y1203400D02*
Y1200662D01*
X804452Y1199814D01*
G01X802333Y1194936D02*
X804157Y1193112D01*
X804458D01*
G01X799230Y1206606D02*
X800194D01*
X801800Y1205000D01*
Y1198619D01*
X802333Y1198086D01*
G01X806610Y1221364D02*
X807558D01*
X809027Y1219895D01*
G01D02*
X811080Y1217842D01*
Y1217814D01*
G01X812302Y1223170D02*
X813909Y1221563D01*
Y1220643D01*
G01X803781Y1218537D02*
X806383D01*
X807020Y1217900D01*
G01D02*
X808252Y1216668D01*
Y1214986D01*
G01X799230Y1206606D02*
Y1211198D01*
X799730Y1211698D01*
X802054D01*
X802291Y1211461D01*
G01D02*
X803596Y1210156D01*
Y1206558D01*
X803604Y1206550D01*
G01X809439Y1224193D02*
X811279D01*
X812302Y1223170D01*
G01X812268Y1227022D02*
X813472Y1228226D01*
X817360D01*
G01X816738Y1223472D02*
Y1224427D01*
X815149Y1226016D01*
G01X806148Y1375208D02*
Y1372195D01*
X807876Y1370467D01*
X811204D01*
X874910Y1306761D01*
X919402D01*
X932433Y1293730D01*
X966818D01*
X984997Y1275551D01*
X993201Y1255743D01*
Y1211606D01*
X1014553Y1190254D01*
Y1099853D01*
X999149Y1084449D01*
Y1027704D01*
X996980Y1025535D01*
Y1022220D01*
X995772Y1019303D01*
Y1014181D01*
X994200Y1012609D01*
Y976677D01*
X985053Y967530D01*
Y926701D01*
X964053Y905701D01*
Y904004D01*
X964473Y902991D01*
X964974Y902490D01*
Y868125D01*
X965988Y867111D01*
X968672D01*
X978309Y857474D01*
Y854223D01*
X980832Y851700D01*
X990114D01*
X990457Y852043D01*
G01X806148Y1380758D02*
Y1383715D01*
G01Y1380758D02*
X810148D01*
G01X806318Y1387865D02*
Y1383885D01*
X806148Y1383715D01*
G01Y1377608D02*
Y1375208D01*
G01X810204Y1401661D02*
X810058Y1401515D01*
Y1397511D01*
G01X810204Y1401661D02*
Y1404769D01*
G01X812104Y1426483D02*
X806419Y1432168D01*
Y1436559D01*
G01X801450Y1443778D02*
Y1441603D01*
X800607Y1440760D01*
G01D02*
X799419Y1439572D01*
Y1436559D01*
G01X805569Y1441519D02*
X804994Y1442094D01*
Y1443778D01*
G01X803269Y1436559D02*
X805569Y1438859D01*
Y1441519D01*
G01X804994Y1461396D02*
Y1465347D01*
X805009Y1465362D01*
Y1469510D01*
G01X803222Y1461396D02*
Y1465011D01*
X802684Y1465549D01*
G01X805009Y1469510D02*
X807502D01*
X807576Y1469584D01*
G01X804930Y1476616D02*
Y1475508D01*
X807576Y1472862D01*
Y1469584D01*
G01X799901Y1469526D02*
X801895D01*
X802684Y1468737D01*
Y1465549D01*
G01X804919Y1489247D02*
Y1484354D01*
G01X840833Y98198D02*
Y98073D01*
X839172Y96412D01*
X830396D01*
X829002Y95018D01*
Y92874D01*
G01D02*
X824271D01*
G01X820094Y95236D02*
X824271D01*
G01Y99961D02*
X820044D01*
G01X822477Y309368D02*
X827520Y314411D01*
X832961D01*
G01X817456Y305368D02*
X820477D01*
X821977Y306868D01*
X823477D01*
X828461Y311852D01*
X832961D01*
G01X825977Y327207D02*
X832961D01*
G01X819977Y317368D02*
X822138Y319529D01*
X832961D01*
G01Y322088D02*
X819588D01*
X817100Y319600D01*
G01X817456Y313368D02*
X820476D01*
X824078Y316970D01*
X832961D01*
G01X819977Y324648D02*
X832961D01*
G01X822626Y348066D02*
Y341623D01*
X829365Y334884D01*
X832961D01*
G01X820196Y332149D02*
X822579Y329766D01*
X832961D01*
G01X829485Y345101D02*
Y338251D01*
X829900Y337836D01*
X832961D01*
G01X827535Y452309D02*
Y456309D01*
G01X821750Y452012D02*
X823900D01*
X824650Y452762D01*
Y455034D01*
G01X827535Y456309D02*
X825925D01*
X824650Y455034D01*
G01X827535Y448309D02*
X826375D01*
X824650Y450034D01*
G01D02*
X824640Y450044D01*
X821750D01*
G01X827284Y709639D02*
Y713439D01*
G01Y721262D02*
Y716589D01*
G01X829725Y727177D02*
Y725640D01*
X827284Y723199D01*
Y721262D01*
G01X835553Y835119D02*
X834900Y834466D01*
Y829600D01*
X835551Y828949D01*
Y825806D01*
X834454Y824709D01*
Y823342D01*
X835479Y822317D01*
X839383D01*
X843515Y818185D01*
Y780485D01*
X845000Y779000D01*
Y775500D01*
X840548Y771048D01*
Y765452D01*
X844500Y761500D01*
Y754500D01*
X841000Y751000D01*
X828500D01*
X827500Y750000D01*
G01X820138Y742502D02*
X819788Y742152D01*
Y739634D01*
G01X826484Y741151D02*
X830484D01*
G01X829725Y735051D02*
Y737991D01*
X830484Y738750D01*
G01D02*
Y741151D01*
G01X836701Y760720D02*
X833420D01*
X831200Y758500D01*
X830075D01*
G01D02*
Y756576D01*
X829499Y756000D01*
X824500D01*
G01X836701Y763280D02*
X832279D01*
X831499Y762500D01*
X830075D01*
G01X817584Y764219D02*
X817609Y764244D01*
X829257D01*
X830075Y763426D01*
Y762500D01*
G01X836701Y778720D02*
X833420D01*
X831200Y776500D01*
X830075D01*
G01D02*
Y774576D01*
X829499Y774000D01*
X824500D01*
G01X836701Y781280D02*
X832279D01*
X831499Y780500D01*
X830075D01*
G01D02*
Y781426D01*
X829001Y782500D01*
X824500D01*
G01X824342Y792315D02*
X828814D01*
X830075Y793576D01*
Y794500D01*
G01X836701Y796720D02*
X833420D01*
X831200Y794500D01*
X830075D01*
G01X824500Y800500D02*
X829001D01*
X830075Y799426D01*
Y798500D01*
G01X836701Y799280D02*
X832279D01*
X831499Y798500D01*
X830075D01*
G01Y812500D02*
X831200D01*
X833420Y814720D01*
X836701D01*
G01X818500Y810135D02*
X829634D01*
X830075Y810576D01*
Y812500D01*
G01Y816500D02*
X831499D01*
X832279Y817280D01*
X836701D01*
G01X817845Y817879D02*
X819209D01*
X820090Y818244D01*
X829257D01*
X830075Y817426D01*
Y816500D01*
G01X819159Y830038D02*
X815922D01*
X815863Y830097D01*
G01X818831Y836666D02*
Y835019D01*
X815863Y832051D01*
Y830097D01*
G01X833112Y829788D02*
X829946D01*
G01X833112Y836665D02*
X829304D01*
X827931Y838038D01*
Y840846D01*
X829757Y842672D01*
G01D02*
X830010Y842925D01*
Y848559D01*
X830102Y848651D01*
G01X816037Y845578D02*
X818831Y842784D01*
Y839816D01*
G01X818006Y848569D02*
Y847511D01*
X816073Y845578D01*
X816037D01*
G01X828134Y848651D02*
Y846432D01*
X827507Y845805D01*
X825329D01*
X822608Y848526D01*
G01X822916Y852576D02*
X825002D01*
X826165Y851413D01*
Y848651D01*
G01X819975Y859199D02*
X822297D01*
X823540Y857956D01*
G01X831654Y864494D02*
Y862454D01*
X830102Y860902D01*
Y859281D01*
G01X822938Y863298D02*
X821210Y861570D01*
X818562D01*
X818006Y861014D01*
Y859199D01*
G01X816027Y867680D02*
Y866450D01*
X816891Y865586D01*
X820650D01*
X822938Y863298D01*
G01X816038Y848569D02*
Y850455D01*
X816538Y850955D01*
X820615D01*
X822608Y848962D01*
Y848526D01*
G01X833194Y873561D02*
X831959D01*
X830063Y875457D01*
X829874D01*
X829363Y875968D01*
Y878504D01*
G01X827992Y874107D02*
X828880Y873219D01*
Y870439D01*
G01X826804Y878504D02*
Y875295D01*
X827992Y874107D01*
G01X819918Y885526D02*
Y889365D01*
G01D02*
Y890670D01*
X819629Y890959D01*
Y892555D01*
G01X823900Y882083D02*
X818631D01*
X817359Y883355D01*
Y885526D01*
G01X817884Y915425D02*
X821709Y911600D01*
X825075D01*
X825093Y911618D01*
X828909D01*
G01X832643Y896164D02*
Y898134D01*
X832277Y898500D01*
X830063D01*
G01X834925Y901500D02*
X834730Y901305D01*
X827615D01*
X824804Y898494D01*
Y898395D01*
G01X828909Y908468D02*
Y904334D01*
X829484Y903759D01*
G01X832909Y908468D02*
Y907184D01*
X829484Y903759D01*
G01X827409Y919218D02*
X824824D01*
X824212Y918606D01*
Y917898D01*
X825336Y916774D01*
G01X829848Y914211D02*
X831823D01*
X832909Y913125D01*
Y911618D01*
G01X831057Y916745D02*
Y917166D01*
X831409Y917518D01*
Y919218D01*
G01X827409Y922368D02*
X831409D01*
G01D02*
X834751D01*
G01X827409D02*
Y924166D01*
X829845Y926602D01*
X830913D01*
G01X826987Y926630D02*
X822690D01*
X818173Y931147D01*
X816519D01*
G01X830913Y929752D02*
X827015D01*
X826987Y929780D01*
G01X834829Y929752D02*
X830913D01*
G01X818835Y1137129D02*
X819449Y1136515D01*
Y1134534D01*
G01X822835Y1140279D02*
X818835D01*
G01X817964Y1157404D02*
X820804D01*
X825600Y1162200D01*
Y1172399D01*
X825099Y1172900D01*
X819797D01*
X818017Y1171120D01*
G01X818879Y1187310D02*
Y1187232D01*
X816848Y1185201D01*
G01Y1182051D02*
X820779D01*
X820816Y1182088D01*
G01D02*
X822809D01*
X823309Y1181588D01*
Y1180235D01*
G01D02*
Y1179038D01*
X822559Y1178288D01*
X820826D01*
G01Y1175138D02*
X816826D01*
G01X820816Y1185238D02*
X823516D01*
G01X815489Y1203443D02*
Y1201077D01*
X815455Y1201043D01*
G01D02*
X815487Y1201011D01*
Y1198569D01*
G01X819487D02*
Y1200817D01*
X819489Y1200819D01*
Y1201039D01*
G01D02*
Y1203443D01*
G01X823487Y1198569D02*
X823489Y1198571D01*
Y1200969D01*
G01D02*
Y1203443D01*
G01X817360Y1228226D02*
X817640D01*
X819566Y1226300D01*
G01X826204Y1444689D02*
Y1447820D01*
X822323Y1451701D01*
X821283D01*
G01X831129Y1444849D02*
X830969Y1444689D01*
X826204D01*
G01X831129Y1440849D02*
X830969Y1440689D01*
X826204D01*
G01D02*
X823745Y1443148D01*
Y1448296D01*
X822111Y1449930D01*
X821283D01*
G01Y1457016D02*
X824407D01*
X826365Y1458974D01*
G01D02*
X829303D01*
X831147Y1457130D01*
Y1454525D01*
G01X826219Y1455244D02*
X821283D01*
G01X831129Y1448849D02*
X828728D01*
X826341Y1451236D01*
G01D02*
X824104Y1453473D01*
X821283D01*
G01X844833Y98198D02*
X840833D01*
G01X844939Y259535D02*
Y256303D01*
G01X844698Y265896D02*
Y264086D01*
X844939Y263845D01*
Y262685D01*
G01X839611Y265701D02*
X840939Y264373D01*
Y262685D01*
G01X844698Y265896D02*
Y267118D01*
X845179Y267599D01*
Y269603D01*
G01X841246Y281716D02*
X843211Y279751D01*
Y277477D01*
G01X839611Y265701D02*
X840789Y266879D01*
X842515D01*
X843211Y267575D01*
Y269603D01*
G01X847147D02*
Y268681D01*
X849714Y266114D01*
G01X847187Y281982D02*
X845179Y279974D01*
Y277477D01*
G01X839992Y284908D02*
X843992D01*
G01D02*
Y283104D01*
X842604Y281716D01*
X841246D01*
G01X847992Y284908D02*
Y282787D01*
X847187Y281982D01*
G01X845435Y356172D02*
Y338936D01*
X838824Y332325D01*
X832961D01*
G01X845179Y473382D02*
X844873Y473076D01*
X842779D01*
G01X838076Y471543D02*
X841246D01*
X842779Y473076D01*
G01X842515Y461382D02*
X845179D01*
G01X838076Y467606D02*
X838330D01*
X840776Y465160D01*
Y463121D01*
X842515Y461382D01*
G01X845179Y469382D02*
Y465382D01*
G01X842916Y467009D02*
Y465747D01*
X843281Y465382D01*
X845179D01*
G01X838076Y469574D02*
X840351D01*
X842916Y467009D01*
G01X842476Y482382D02*
X845179D01*
G01X838076Y475480D02*
X839066D01*
X840589Y477003D01*
Y480495D01*
X842476Y482382D01*
G01X874649Y545296D02*
X836036Y506683D01*
X833269D01*
G01X845850Y710969D02*
X848376D01*
X849706Y709639D01*
X852284D01*
G01X843284D02*
X843622Y709301D01*
X844572D01*
X845784Y708089D01*
G01X843284Y713439D02*
Y709639D01*
G01X839290Y713419D02*
Y709619D01*
G01D02*
X836078D01*
G01X843284Y721262D02*
Y716589D01*
G01X836284Y721273D02*
Y718032D01*
X837747Y716569D01*
X839290D01*
G01X845725Y727177D02*
Y725640D01*
X843284Y723199D01*
Y721262D01*
G01X834843Y727177D02*
Y724627D01*
X836284Y723186D01*
Y721273D01*
G01X842484Y741151D02*
X846484D01*
G01X845725Y735051D02*
Y737991D01*
X846484Y738750D01*
G01D02*
Y741151D01*
G01X838484D02*
X834484D01*
G01X834843Y735051D02*
Y736881D01*
X836713Y738751D01*
G01D02*
X837983D01*
X838484Y739252D01*
Y741151D01*
G01X842734Y835459D02*
X841151D01*
X840564Y834872D01*
X837910D01*
X837115Y834077D01*
X836776Y833259D01*
Y831364D01*
X836839Y831301D01*
G01X833112Y829788D02*
Y833515D01*
G01X841417Y827459D02*
Y824183D01*
X843558Y822042D01*
X846764D01*
X848224Y823502D01*
G01X849215Y827686D02*
X848971D01*
X847227Y829430D01*
X843059D01*
X841417Y827788D01*
Y827459D01*
G01X861599Y836900D02*
Y830851D01*
X860203Y829455D01*
X849466D01*
X847363Y831558D01*
X845860D01*
G01X835215Y847719D02*
Y857747D01*
X833681Y859281D01*
X832071D01*
G01X843839Y847490D02*
X846239D01*
G01X843839Y843790D02*
X845232D01*
X847551Y841471D01*
X854846D01*
X856834Y843459D01*
G01X845932Y839292D02*
Y839272D01*
X847850Y837354D01*
X856203D01*
X856834Y837985D01*
Y839459D01*
G01X839391Y839953D02*
Y840633D01*
X840190Y841432D01*
X843792D01*
X845932Y839292D01*
G01X838194Y836962D02*
X840327D01*
X842657Y839292D01*
X842782D01*
G01X845860Y831558D02*
Y835435D01*
X845884Y835459D01*
G01X843439Y855395D02*
X845402Y857358D01*
X854935D01*
X856834Y855459D01*
G01X847138Y859459D02*
X853684D01*
G01X845884Y851459D02*
Y850143D01*
X846619Y849408D01*
X854783D01*
X856834Y851459D01*
G01X843312Y863413D02*
X845820D01*
G01X843574Y859423D02*
X841659Y861338D01*
X838637D01*
X837807Y860508D01*
X836496D01*
X836405Y860417D01*
G01X833194Y873561D02*
Y870753D01*
X832880Y870439D01*
G01X843343Y871459D02*
X845604D01*
X847476Y869587D01*
X849312D01*
X851184Y871459D01*
G01Y875459D02*
X849184Y873459D01*
X839149D01*
X838595Y874013D01*
X836311D01*
G01X843312Y867413D02*
X845820D01*
G01X832880Y867289D02*
X831654Y866063D01*
Y864494D01*
G01X845820Y875507D02*
X846148Y875179D01*
X848104D01*
X848384Y875459D01*
G01X851184Y879459D02*
X849324Y877599D01*
X844893D01*
X843033Y879459D01*
G01X835346Y891346D02*
Y892580D01*
X834912Y893014D01*
X832643D01*
G01X831922Y887166D02*
Y888164D01*
X833701Y889943D01*
X833943D01*
X835346Y891346D01*
G01X863792Y877798D02*
Y880228D01*
X861685Y885316D01*
X861154Y885847D01*
X847454D01*
X846973Y885366D01*
X845064D01*
X842940Y887490D01*
G01X841103Y892564D02*
X838457D01*
X836066Y894955D01*
G01X844253Y892564D02*
X845747D01*
X847098Y891213D01*
G01D02*
X848011Y890300D01*
X856942D01*
X858547Y891905D01*
X862096D01*
X865763Y888238D01*
Y884827D01*
X866121Y883962D01*
X867285Y882798D01*
X878508D01*
X879794Y881512D01*
G01X837276Y883459D02*
Y884483D01*
X835412Y886347D01*
Y888278D01*
X836497Y889363D01*
X838885D01*
X839790Y888458D01*
Y887490D01*
G01X850800Y883500D02*
Y882600D01*
X849600Y881400D01*
X845092D01*
X843033Y883459D01*
G01X841274Y914060D02*
Y913487D01*
X840909Y913122D01*
Y911618D01*
G01X836909D02*
Y914018D01*
G01X842000Y901575D02*
X846000D01*
G01X842000D02*
X838150D01*
X838075Y901500D01*
G01X858988Y898307D02*
X856698Y900597D01*
X849406D01*
X848428Y901575D01*
X846000D01*
G01X849600Y918028D02*
X847094Y915522D01*
Y914366D01*
X844946Y912218D01*
Y911618D01*
G01X871600Y898584D02*
X871584Y898600D01*
X862836D01*
X859253Y902183D01*
X851231D01*
X844946Y908468D01*
G01X840909D02*
X836909D01*
G01D02*
X832909D01*
G01X840909D02*
X841268D01*
X842984Y910184D01*
Y912862D01*
X845175Y915053D01*
Y926382D01*
X845395Y926602D01*
G01X841064Y919018D02*
X842875D01*
X843315Y918578D01*
Y916612D01*
G01X837235Y919018D02*
X836909Y918692D01*
Y916618D01*
G01X837235Y922168D02*
X837035Y922368D01*
X834751D01*
G01X841064Y922168D02*
X837235D01*
G01X833683Y939579D02*
Y935779D01*
G01X834829Y929752D02*
Y931672D01*
X833683Y932818D01*
Y935779D01*
G01X836243D02*
Y939579D01*
G01X845395Y929752D02*
X849173D01*
X849205Y929784D01*
G01X838829Y929752D02*
X845395D01*
G01X836243Y935779D02*
Y933342D01*
X838829Y930756D01*
Y929752D01*
G01X833683Y952905D02*
Y949105D01*
G01X832423Y959119D02*
X833683Y957859D01*
Y952905D01*
G01X836243D02*
Y949105D01*
G01X836423Y959119D02*
X836243Y958939D01*
Y952905D01*
G01X840423Y959119D02*
Y957047D01*
X842856Y954614D01*
Y949146D01*
G01D02*
X839598D01*
X839097Y949647D01*
Y952905D01*
G01X834279Y1440849D02*
X836704D01*
G01X834279Y1444849D02*
X836744D01*
G01X845319Y1444959D02*
X846319Y1443959D01*
X850377D01*
G01X845319Y1448959D02*
Y1448859D01*
X848158Y1446020D01*
X849005D01*
X850544Y1447559D01*
G01X845306Y1440859D02*
Y1438269D01*
G01D02*
X848770D01*
X852885Y1442384D01*
Y1444512D01*
X854072Y1445699D01*
X855812D01*
G01X834279Y1448849D02*
X836704D01*
G01X850744Y1461959D02*
X845319D01*
G01X842169D02*
X839744D01*
G01X850644Y1457359D02*
X848844D01*
X848244Y1457959D01*
X845319D01*
G01X855734Y80581D02*
Y79618D01*
X858765Y76587D01*
X858929D01*
G01D02*
X866599D01*
X870219Y72967D01*
Y64722D01*
G01X855734Y68581D02*
Y69564D01*
X858757Y72587D01*
X858929D01*
G01X867659Y64722D02*
Y72641D01*
X865533Y74767D01*
X861109D01*
X858929Y72587D01*
G01X853379Y76587D02*
X855779D01*
G01X853379Y72615D02*
X853407Y72587D01*
X855779D01*
G01X854818Y100625D02*
X856184Y99259D01*
X859740D01*
G01X850337Y97475D02*
X847837D01*
G01X859191Y112083D02*
Y112402D01*
X861277Y114488D01*
G01X863480Y107921D02*
Y103621D01*
G01X850337Y105087D02*
Y100625D01*
G01D02*
X854818D01*
G01X859630Y179897D02*
Y176034D01*
X862999Y172665D01*
G01D02*
X865920D01*
G01X862936Y178560D02*
Y179904D01*
G01X865920Y180665D02*
X863697D01*
X862936Y179904D01*
G01D02*
Y180204D01*
X861274Y181866D01*
X859630D01*
G01X865920Y196665D02*
X861791D01*
X861746Y196620D01*
G01X857071Y188362D02*
Y192490D01*
G01D02*
X859197Y194616D01*
X860913D01*
X861746Y195449D01*
Y196620D01*
G01X865920Y184665D02*
X865089Y183834D01*
X862826D01*
G01D02*
X859630D01*
G01Y185803D02*
Y189278D01*
X860537Y190185D01*
X862346D01*
G01D02*
Y191730D01*
X863281Y192665D01*
X865920D01*
G01X858596Y196620D02*
X854575D01*
X853029Y195074D01*
Y192300D01*
G01X866015Y212864D02*
X865606Y212455D01*
X863205D01*
G01X859241Y213166D02*
X860927D01*
X861638Y212455D01*
X863205D01*
G01X863116Y200864D02*
X866015D01*
G01X859241Y209229D02*
X859963D01*
X860551Y208641D01*
Y203429D01*
X863116Y200864D01*
G01X863139Y207037D02*
X864966Y208864D01*
X866015D01*
G01X859241Y211197D02*
X860694D01*
X863139Y208752D01*
Y207037D01*
G01X859241Y217103D02*
X861254D01*
X866015Y221864D01*
G01X849714Y266114D02*
Y264678D01*
X848939Y263903D01*
Y262685D01*
G01X855993Y308900D02*
X858945D01*
X862477Y305368D01*
X869924D01*
G01X872402Y309368D02*
X863430D01*
G01D02*
X860946Y311852D01*
X855993D01*
G01Y314411D02*
X859977D01*
X861020Y313368D01*
X869924D01*
G01X872402Y317368D02*
X870334D01*
X869936Y316970D01*
X863430D01*
G01D02*
X855993D01*
G01Y319529D02*
X865638D01*
X867477Y321368D01*
X869924D01*
G01X872402Y325368D02*
X863977D01*
X863114Y324505D01*
G01D02*
X860697Y322088D01*
X855993D01*
G01Y324648D02*
X859379D01*
X861521Y326790D01*
X865800D01*
X867726Y328716D01*
X868918D01*
X868924Y328722D01*
X869924D01*
G01X855993Y327207D02*
X860107D01*
X863040Y330140D01*
G01X855993Y334884D02*
X859983D01*
X863040Y337941D01*
X866331D01*
X868242Y339852D01*
Y344850D01*
X869448Y346056D01*
X872866D01*
X874005Y344917D01*
G01X855993Y332325D02*
X859926D01*
X863501Y335900D01*
X867000D01*
X870000Y338900D01*
Y342378D01*
X870413Y342791D01*
G01X869924Y333722D02*
X863907D01*
X859951Y329766D01*
X855993D01*
G01X863040Y330140D02*
X864457Y331557D01*
X870591D01*
X872402Y333368D01*
G01X858586Y390575D02*
Y393000D01*
X859267Y393681D01*
Y397014D01*
G01X858586Y390575D02*
X860086D01*
X860771Y389890D01*
Y383185D01*
X860586Y383000D01*
G01D02*
X859086D01*
X858586Y382500D01*
Y380075D01*
G01X861235Y394000D02*
Y392426D01*
X863086Y390575D01*
G01X854086D02*
X855462D01*
X856086Y389951D01*
Y384000D01*
X854086Y382000D01*
Y380075D01*
G01Y390575D02*
Y392999D01*
G01D02*
X857298Y396211D01*
Y397014D01*
G01X864086Y384000D02*
Y386425D01*
X863086Y387425D01*
G01Y380075D02*
X864086Y381075D01*
Y384000D01*
G01X861235Y397014D02*
Y394000D01*
G01X863204Y397014D02*
Y396382D01*
X864586Y395000D01*
X867086D01*
X867586Y394500D01*
Y393000D01*
G01X850732Y469382D02*
X848329D01*
G01X850732D02*
X852692Y471342D01*
Y476143D01*
X855852Y479303D01*
X863879D01*
G01X1061342Y610269D02*
X1059492D01*
X1054661Y615100D01*
Y643339D01*
X1040900Y657100D01*
X947600D01*
X943600Y653100D01*
X870301D01*
X865895Y657506D01*
X853982D01*
G01X1061496Y612786D02*
X1059813D01*
X1056600Y615999D01*
Y644634D01*
X1042065Y659169D01*
X946679D01*
X942500Y654990D01*
X871525D01*
X867174Y659341D01*
X861064D01*
X860594Y659811D01*
Y661530D01*
X860124Y662000D01*
X858594D01*
X858124Y661530D01*
Y659811D01*
X857654Y659341D01*
X856124D01*
X855654Y659811D01*
Y661530D01*
X855184Y662000D01*
X853654D01*
X853184Y661530D01*
Y659811D01*
X852714Y659341D01*
X850029D01*
X848444Y657756D01*
G01X859441Y678015D02*
X859661Y677795D01*
X909265D01*
G01X859838Y692710D02*
X855646D01*
G01X863836Y701170D02*
Y705170D01*
G01X859838Y688970D02*
X864029D01*
G01X849680Y689039D02*
X855577D01*
X855646Y688970D01*
X859838D01*
G01X852284Y713439D02*
Y709639D01*
G01X867455Y710611D02*
Y708963D01*
X863836Y705344D01*
Y705170D01*
G01X860686Y709170D02*
X858628D01*
X858002Y708544D01*
Y707244D01*
G01D02*
Y705794D01*
X858626Y705170D01*
X860686D01*
G01X863836Y709170D02*
Y713170D01*
G01D02*
Y716424D01*
X865331Y717919D01*
G01X852284Y721273D02*
Y716589D01*
G01X850843Y727177D02*
Y724627D01*
X852284Y723186D01*
Y721273D01*
G01X863636Y722670D02*
Y726011D01*
X865012Y727387D01*
G01X860486Y722670D02*
X857986D01*
G01X854484Y741151D02*
X850484D01*
G01X854484D02*
Y738633D01*
G01D02*
X853543Y737692D01*
X851867D01*
X850843Y736668D01*
Y735051D01*
G01X854299Y758161D02*
X856839D01*
X859000Y756000D01*
G01D02*
X861425D01*
G01X854299Y763280D02*
X856780D01*
X857500Y764000D01*
X859000D01*
G01D02*
X861425D01*
G01X854299Y760720D02*
X856780D01*
X857500Y760000D01*
X859000D01*
G01D02*
X861425D01*
G01X854299Y776161D02*
X856839D01*
X859000Y774000D01*
G01D02*
X861425D01*
G01Y782000D02*
X860000D01*
X859000Y781000D01*
G01D02*
X857780D01*
X857500Y781280D01*
X854299D01*
G01Y778720D02*
X856780D01*
X857500Y778000D01*
X859000D01*
G01D02*
X861425D01*
G01X854299Y794161D02*
X856839D01*
X859000Y792000D01*
G01D02*
X861425D01*
G01Y796000D02*
X859000D01*
G01D02*
X857500D01*
X856780Y796720D01*
X854299D01*
G01X859000Y810000D02*
X861425D01*
G01X854299Y812161D02*
X856839D01*
X859000Y810000D01*
G01Y814000D02*
X861425D01*
G01X854299Y814720D02*
X856780D01*
X857500Y814000D01*
X859000D01*
G01X854299Y799280D02*
X856780D01*
X857500Y800000D01*
X859000D01*
G01D02*
X861425D01*
G01X867876Y836956D02*
X869301Y835531D01*
Y826759D01*
X869085Y826543D01*
X862576D01*
X861651Y827468D01*
X856906D01*
G01X853756D02*
X853538Y827686D01*
X849215D01*
G01X856803Y831469D02*
Y835428D01*
X856834Y835459D01*
G01X859000Y818000D02*
X861425D01*
G01X854299Y817280D02*
X856780D01*
X857500Y818000D01*
X859000D01*
G01X853684Y839459D02*
X851184D01*
G01X853684Y835459D02*
X851184D01*
G01X848384Y843459D02*
X850320Y845395D01*
X852600D01*
X853684Y844311D01*
Y843459D01*
G01X856834Y847459D02*
X857955D01*
X859224Y848728D01*
X859165D01*
G01X861832Y846197D02*
X865224D01*
X866747Y847720D01*
X869071D01*
X876077Y854726D01*
X881354D01*
X882944Y856316D01*
G01X861832Y846197D02*
X859094Y843459D01*
X856834D01*
G01X851239Y847459D02*
X853684D01*
G01X856834Y839459D02*
X858278Y840903D01*
X861260D01*
X864044Y843687D01*
X866371D01*
X867858Y845174D01*
G01X864760Y840928D02*
X863123Y839291D01*
X859941D01*
X858694Y838044D01*
Y837319D01*
X856834Y835459D01*
G01X879794Y840568D02*
X875157D01*
X874062Y839473D01*
X866836D01*
X864263Y836900D01*
X861599D01*
G01X867179Y855265D02*
X866943Y855501D01*
X856876D01*
X856834Y855459D01*
G01X851184Y851459D02*
X853684D01*
G01Y863459D02*
Y862183D01*
X853089Y861588D01*
X850255D01*
X848384Y863459D01*
G01X856834Y851459D02*
X858516Y853141D01*
X861663D01*
G01D02*
X865196D01*
X865908Y852429D01*
X867681D01*
X873157Y857905D01*
X881384D01*
X882944Y859465D01*
G01X859603Y863570D02*
X858831Y862798D01*
X857495D01*
X856834Y863459D01*
G01X859603Y863570D02*
X860706Y862467D01*
X862776D01*
G01D02*
X866916D01*
X867716Y862798D01*
X878287D01*
X878470Y862615D01*
X879794D01*
G01X859165Y848728D02*
X859334Y848897D01*
X864579D01*
X865567Y849885D01*
G01X848384Y851459D02*
Y852691D01*
X849038Y853345D01*
X852694D01*
X853684Y854335D01*
Y855459D01*
G01X859461Y859459D02*
X856834D01*
G01X868123Y860298D02*
X865046Y857221D01*
X861699D01*
X859461Y859459D01*
G01X856834Y883459D02*
X857876Y881900D01*
X860100D01*
X860748Y881252D01*
X861372Y879746D01*
Y877315D01*
X861699Y876525D01*
X862846Y875378D01*
X862873D01*
X862953Y875298D01*
X868123D01*
G01X863726Y872719D02*
X862082D01*
X859647Y875154D01*
X858940Y876861D01*
X857827Y877974D01*
X856834Y879459D01*
G01X879794Y872064D02*
X879550Y871820D01*
X870024D01*
X869126Y872718D01*
X867280D01*
X867279Y872719D01*
X867121D01*
X867120Y872718D01*
X863727D01*
X863726Y872719D01*
G01X851184Y871459D02*
X853684D01*
G01X851184Y875459D02*
X853684D01*
G01X868123Y870298D02*
X861079D01*
X857481Y873896D01*
X856834Y875459D01*
G01Y871459D02*
X860634Y867659D01*
X863091D01*
G01D02*
X863092Y867658D01*
X869101D01*
X869659Y867100D01*
X878458D01*
X879794Y865764D01*
G01X863792Y877798D02*
X870557D01*
X871122Y878363D01*
X879794D01*
G01X848384Y867459D02*
X850255Y865588D01*
X851949D01*
X853684Y867323D01*
Y867459D01*
G01X859463Y866125D02*
X858168D01*
X856834Y867459D01*
G01X868123Y865298D02*
X868122Y865299D01*
X860289D01*
X859463Y866125D01*
G01X851184Y879459D02*
X853684D01*
G01X848792Y896472D02*
Y895808D01*
X851641Y892959D01*
X853684D01*
G01X856834D02*
Y894795D01*
X857849Y895810D01*
X863241D01*
X868123Y890928D01*
Y885298D01*
G01X856834Y887759D02*
X859260Y890185D01*
X861383D01*
X864043Y887525D01*
Y884485D01*
X864340Y883766D01*
X864342Y883762D01*
X864663Y882986D01*
X867351Y880298D01*
X868123D01*
G01X853684Y887759D02*
X853084Y888359D01*
X850900D01*
G01X853684Y883459D02*
X853525Y883300D01*
X851000D01*
X850800Y883500D01*
G01X860628Y909514D02*
X856628D01*
G01X879664Y901568D02*
X876432D01*
X875800Y902200D01*
X865997D01*
X862040Y906157D01*
X858349D01*
X856628Y907878D01*
Y909514D01*
G01X848628D02*
X852628D01*
G01X879147Y896530D02*
X877571D01*
X873401Y900700D01*
X864476D01*
X861230Y903946D01*
X856560D01*
X852628Y907878D01*
Y909514D01*
G01X849205Y926634D02*
Y924129D01*
G01X850377Y1443959D02*
X854086Y1447668D01*
X855862D01*
G01X850544Y1447559D02*
X852621Y1449636D01*
X855862D01*
G01X855812Y1459479D02*
X855612D01*
X853132Y1461959D01*
X850744D01*
G01X855862Y1457510D02*
X853514D01*
G01X855862Y1455542D02*
X852461D01*
X850644Y1457359D01*
G01X870219Y64722D02*
X870519Y64422D01*
Y60438D01*
G01X867659Y64722D02*
Y60513D01*
G01X876200Y86012D02*
X873073Y82885D01*
Y81848D01*
G01X867787Y85731D02*
X867659Y85603D01*
Y81848D01*
G01X871341Y86046D02*
X870219Y84924D01*
Y81848D01*
G01X872293Y91879D02*
Y94279D01*
G01X868344Y91951D02*
Y94351D01*
G01X876200Y88824D02*
Y86012D01*
G01X868344Y88801D02*
X867787Y88244D01*
Y85731D01*
G01X872293Y88729D02*
Y86998D01*
X871341Y86046D01*
G01X865920Y168665D02*
Y172665D01*
G01Y176665D02*
Y180665D01*
G01X874531Y197350D02*
X878500D01*
G01X869070Y196665D02*
X871713D01*
G01X874531Y197350D02*
X873846Y196665D01*
X871713D01*
G01Y192665D02*
X869070D01*
G01X943183Y281652D02*
X940679Y284156D01*
X894096D01*
X876988Y267048D01*
Y245082D01*
X880452Y241618D01*
Y195524D01*
X877593Y192665D01*
X871713D01*
G01X869070Y184665D02*
X871093D01*
X871826Y185398D01*
Y186778D01*
G01D02*
Y187934D01*
X871095Y188665D01*
X869070D01*
G01X945018Y276051D02*
X945400Y276433D01*
Y282599D01*
X941982Y286017D01*
X893325D01*
X875127Y267819D01*
Y244311D01*
X878500Y240938D01*
Y200500D01*
G01X871745Y208864D02*
X869165D01*
G01X866015Y204864D02*
Y208864D01*
G01Y224536D02*
Y221864D01*
G01X879740Y257134D02*
X880086Y257480D01*
X897004D01*
G01X879740Y260284D02*
Y261979D01*
X880448Y262687D01*
X883118D01*
G01X869924Y305368D02*
X872402D01*
G01X880402D02*
X877977D01*
G01D02*
X875552D01*
G01X880402Y309368D02*
X877977D01*
G01D02*
X875552D01*
G01Y313368D02*
X877977D01*
G01D02*
X880402D01*
G01Y325368D02*
X877977D01*
G01D02*
X875552D01*
G01Y317368D02*
X877977D01*
G01D02*
X880402D01*
G01Y321368D02*
X877977D01*
G01D02*
X875552D01*
G01X869924Y313368D02*
X872402D01*
G01X869924Y321368D02*
X872402D01*
G01X880402Y341342D02*
X878953Y342791D01*
X870413D01*
G01X880402Y337342D02*
X875659D01*
G01D02*
Y336152D01*
X874794Y335287D01*
X871489D01*
X869924Y333722D01*
G01X880402Y333368D02*
X877977D01*
G01D02*
X875552D01*
G01X880402Y329368D02*
X877977D01*
G01D02*
X875552D01*
G01X869924Y328722D02*
X871756D01*
X872402Y329368D01*
G01X874005Y344917D02*
X875144Y346056D01*
X879688D01*
X880402Y345342D01*
G01X868086Y373750D02*
Y376925D01*
G01X880736Y388855D02*
X876736D01*
G01X877909Y391731D02*
X876736Y390558D01*
Y388855D01*
G01X876755Y397073D02*
Y392885D01*
X877909Y391731D01*
G01X878724Y397073D02*
Y394066D01*
X881691Y391099D01*
X882925D01*
G01X872736Y391754D02*
Y388855D01*
G01X874787Y397073D02*
Y393805D01*
X872736Y391754D01*
G01X867586Y393000D02*
Y390575D01*
G01Y387425D02*
Y385000D01*
G01X868586Y398500D02*
X869586Y397500D01*
Y383000D01*
X868086Y381500D01*
Y380075D01*
G01X865763Y399573D02*
X867513D01*
X868586Y398500D01*
G01X867029Y483303D02*
Y479303D01*
G01X872911Y480350D02*
X870501D01*
X869454Y479303D01*
G01D02*
X867029D01*
G01Y491303D02*
Y487303D01*
G01X872911Y483303D02*
X870954D01*
X869954Y484303D01*
Y487303D01*
G01D02*
X867029D01*
G01X879997Y483303D02*
X885379D01*
X885879Y483803D01*
Y486303D01*
G01X882954Y486256D02*
X879997D01*
G01X872643Y554703D02*
Y558703D01*
G01X872488Y549771D02*
X879970D01*
X880138Y549603D01*
G01D02*
X883949Y553414D01*
Y554863D01*
X885339Y556253D01*
Y559355D01*
X888081Y562097D01*
X895586D01*
G01X876949Y571419D02*
X881814D01*
G01X872643Y570703D02*
X874789D01*
X875505Y571419D01*
X876949D01*
G01X884732Y570435D02*
X883800D01*
X882228Y568863D01*
X879449D01*
G01D02*
X877289Y566703D01*
X872643D01*
G01Y558703D02*
Y562703D01*
G01X879449D02*
X872643D01*
G01X887193Y564037D02*
Y563429D01*
X886467Y562703D01*
X879449D01*
G01X872643Y586828D02*
Y582828D01*
G01X879055D02*
X872643D01*
G01X879055D02*
X880622Y581261D01*
X882904D01*
G01X872643Y578703D02*
X875290D01*
G01X872643D02*
Y574703D01*
G01X875290Y578703D02*
X876519D01*
X880694Y574528D01*
X882004D01*
X882466Y574066D01*
G01X877339Y574408D02*
X878830Y572917D01*
X881510D01*
G01X881836Y698970D02*
Y700315D01*
X880268Y701883D01*
X876106D01*
X874382Y700159D01*
Y683728D01*
X875887Y682223D01*
G01D02*
X878510Y679600D01*
X883888D01*
X888691Y684403D01*
G01X869970Y704561D02*
X867772D01*
X865700Y702489D01*
Y690817D01*
X866530Y689987D01*
Y686542D01*
X867842Y685230D01*
X869484D01*
G01X878686Y698970D02*
X876286D01*
G01X867455Y710611D02*
X870321D01*
G01X865331Y717919D02*
X866952Y716298D01*
Y714754D01*
X868536Y713170D01*
X870321D01*
G01X877727Y722060D02*
Y715803D01*
X877801Y715729D01*
G01X882765Y713846D02*
X880882Y715729D01*
X877801D01*
G01Y713170D02*
X874751D01*
X873495Y711914D01*
Y706453D01*
X871603Y704561D01*
X869970D01*
G01X865012Y727387D02*
X867780Y724619D01*
X870727D01*
G01X879875Y753612D02*
X877469Y756018D01*
Y761332D01*
G01X870017Y757313D02*
X872350Y759646D01*
Y761332D01*
G01X873728Y752692D02*
X874909Y753873D01*
Y761332D01*
G01X892040Y784511D02*
X882763Y780668D01*
X880028Y777933D01*
Y775898D01*
G01X870000Y780000D02*
X873992D01*
X874909Y779083D01*
Y775898D01*
G01X879887Y784719D02*
X877469Y782301D01*
Y775898D01*
G01X876402Y797415D02*
X876303Y797316D01*
Y794227D01*
G01X887916Y806465D02*
X887365D01*
X885848Y804948D01*
Y798615D01*
X886553Y797910D01*
Y795404D01*
X885002Y793853D01*
X882946D01*
X879384Y797415D01*
X876402D01*
G01X879916Y808965D02*
Y813465D01*
G01X875916Y806465D02*
X875596D01*
X874047Y808014D01*
Y811596D01*
X875916Y813465D01*
G01X879190Y821364D02*
X877804Y819978D01*
Y813965D01*
X877304Y813465D01*
X875916D01*
G01X879916Y816615D02*
Y816797D01*
X884190Y821071D01*
Y821364D01*
G01X884518Y835804D02*
X879878Y831164D01*
Y822052D01*
X879190Y821364D01*
G01X867858Y845174D02*
X869174D01*
X877352Y853352D01*
X879608D01*
X879794Y853166D01*
G01X867876Y836956D02*
X876372D01*
X878416Y839000D01*
X881376D01*
X882944Y840568D01*
G01X864760Y840928D02*
X865628Y841796D01*
X872692D01*
X873808Y842912D01*
X877681D01*
X878436Y842157D01*
X881384D01*
X882944Y843717D01*
G01X878220Y848442D02*
X879794Y846868D01*
Y846867D01*
G01X878220Y845293D02*
X879794Y843719D01*
Y843717D01*
G01Y837418D02*
X878220Y835844D01*
G01Y851592D02*
X879794Y850018D01*
Y850016D01*
G01Y859465D02*
X879649Y859320D01*
X871234D01*
X867179Y855265D01*
G01X865567Y849885D02*
X868442D01*
X874873Y856316D01*
X879794D01*
G01X868123Y860298D02*
X868865Y861040D01*
X884518D01*
X886093Y862615D01*
G01X868123Y875298D02*
X868283Y875138D01*
X870462D01*
X871360Y874240D01*
X878560D01*
X879147Y873653D01*
X879564D01*
X879578Y873639D01*
X881369D01*
X882944Y872064D01*
G01X868123Y870298D02*
X869021Y869400D01*
X879308D01*
X879794Y868914D01*
G01X868123Y865298D02*
X868821Y864600D01*
X878648D01*
X879058Y864190D01*
X881369D01*
X882944Y862615D01*
G01X868123Y880298D02*
X878526D01*
X878886Y879938D01*
X881369D01*
X882944Y878363D01*
G01X879794Y875213D02*
X879087D01*
X877800Y876500D01*
G01X868123Y885298D02*
X879158D01*
X879794Y884662D01*
G01X879147Y896530D02*
Y894676D01*
X881578Y892245D01*
X885113D01*
X887668Y889690D01*
Y883087D01*
X889243Y881512D01*
G01X879664Y901568D02*
X881637Y899595D01*
Y895554D01*
X883447Y893744D01*
X885198D01*
X889243Y889699D01*
Y884662D01*
G01X872628Y909514D02*
Y907878D01*
X873806Y906700D01*
X880727D01*
X886654Y900773D01*
G01X876628Y909514D02*
X872628D01*
G01X864628D02*
Y907878D01*
X867906Y904600D01*
X880299D01*
X884154Y900745D01*
Y896438D01*
G01X868628Y909514D02*
X864628D01*
G01X886428Y944635D02*
X886069Y944276D01*
X879740D01*
G01X870209Y949384D02*
X875317Y944276D01*
X879740D01*
G01X956017Y770300D02*
X964900Y779183D01*
Y801100D01*
X960700Y805300D01*
Y820200D01*
X964100Y823600D01*
Y832800D01*
X965680Y834380D01*
Y858121D01*
X961654Y862147D01*
Y901112D01*
X960619Y902147D01*
Y907719D01*
X979800Y926900D01*
Y968400D01*
X991966Y980566D01*
Y1012080D01*
X992480Y1013322D01*
X994052Y1014894D01*
Y1019646D01*
X995260Y1022563D01*
Y1026248D01*
X997429Y1028417D01*
Y1085163D01*
X1012788Y1100522D01*
Y1189250D01*
X991051Y1210987D01*
Y1255228D01*
X983166Y1274264D01*
X965965Y1291465D01*
X931781D01*
X918646Y1304600D01*
X874800D01*
X872600Y1302400D01*
Y1300833D01*
G01X957500Y780800D02*
X963100Y786400D01*
Y800354D01*
X958900Y804554D01*
Y820946D01*
X961900Y823946D01*
Y833800D01*
X963960Y835860D01*
Y856839D01*
X959934Y860865D01*
Y896368D01*
X958899Y897403D01*
Y908890D01*
X978000Y927991D01*
Y969146D01*
X990246Y981392D01*
Y1012794D01*
X990760Y1014035D01*
X992332Y1015607D01*
Y1019990D01*
X993540Y1022906D01*
Y1026962D01*
X995709Y1029131D01*
Y1085877D01*
X1010988Y1101156D01*
Y1188504D01*
X989251Y1210241D01*
Y1254637D01*
X981477Y1273407D01*
X965219Y1289665D01*
X931035D01*
X917900Y1302800D01*
X883800D01*
X877800Y1296800D01*
X874133D01*
X872600Y1298333D01*
G01X873480Y1449636D02*
X877159D01*
X878954Y1447841D01*
Y1446432D01*
G01D02*
X880527Y1444859D01*
X883669D01*
G01X873480Y1453573D02*
X875744D01*
G01X878244Y1451605D02*
X873480D01*
G01X883669Y1460859D02*
X882123D01*
X878244Y1456980D01*
Y1451605D01*
G01X873530Y1459479D02*
X874426D01*
X874997Y1460050D01*
Y1468112D01*
X878244Y1471359D01*
G01X878245Y1465859D02*
Y1459259D01*
X874528Y1455542D01*
X873480D01*
G01X883669Y1472859D02*
X879744D01*
X878244Y1471359D01*
G01X883669Y1468859D02*
X881245D01*
X878245Y1465859D01*
G01X896960Y141247D02*
X893131D01*
G01X894729Y146461D02*
X894472Y146204D01*
Y143740D01*
G01D02*
X893131Y142399D01*
Y141247D01*
G01X889161Y151540D02*
Y147540D01*
G01X894729Y149414D02*
X892989D01*
X891852Y148277D01*
G01D02*
X891580D01*
X890843Y147540D01*
X889161D01*
G01X903297Y240945D02*
X893641D01*
X891383Y243203D01*
G01X903297Y243307D02*
X896034D01*
G01X903297Y255118D02*
X885884D01*
G01X903297Y248032D02*
X897218D01*
X895064Y250186D01*
G01X903297Y262205D02*
X898349D01*
X897004Y260860D01*
X892484D01*
G01X903297Y250394D02*
X897781D01*
X895979Y252196D01*
X889674D01*
X887148Y249670D01*
G01X903297Y264567D02*
X897025D01*
X896356Y265236D01*
X895140D01*
G01X883552Y341342D02*
X885972D01*
X886167Y341537D01*
X888312D01*
G01X888812Y357372D02*
Y342037D01*
X888312Y341537D01*
G01X898869Y351114D02*
Y347181D01*
X893225Y341537D01*
X891462D01*
G01X883552Y345342D02*
Y357276D01*
G01X880736Y385705D02*
Y383125D01*
G01X884736Y388855D02*
Y390599D01*
X884236Y391099D01*
X882925D01*
G01X897736Y388855D02*
X893736D01*
G01X890553Y392038D02*
X893736Y388855D01*
G01X882661Y397073D02*
Y395888D01*
X883634Y394915D01*
X887676D01*
X890553Y392038D01*
G01X885879Y486303D02*
X883001D01*
X882954Y486256D01*
G01X900972Y564037D02*
Y563028D01*
X901305Y562695D01*
Y558749D01*
X900617Y558061D01*
X896628D01*
X883274Y544707D01*
Y540283D01*
X882195Y539204D01*
G01X892425Y529633D02*
Y531293D01*
X889431Y534287D01*
Y536493D01*
G01X885931Y534093D02*
Y536493D01*
G01X899530Y530753D02*
X896695D01*
X895575Y529633D01*
G01X892931Y539643D02*
X896431D01*
G01X905114Y551773D02*
Y549211D01*
X900506Y544603D01*
Y543718D01*
X896431Y539643D01*
G01X889414Y544911D02*
Y543126D01*
X885931Y539643D01*
G01X903925Y562548D02*
Y558342D01*
X900107Y554524D01*
X897351Y547871D01*
X894694Y545214D01*
X891502D01*
X891199Y544911D01*
X889414D01*
G01X897689Y544660D02*
X896166Y543137D01*
X892715D01*
X889431Y539853D01*
Y539643D01*
G01X902941Y564037D02*
Y558917D01*
X901006Y556982D01*
X897714D01*
X885556Y544824D01*
Y543664D01*
G01X887939Y558338D02*
X890369Y560768D01*
X895875D01*
X896204Y561097D01*
G01X893536Y558394D02*
X894842Y559700D01*
X896128D01*
G01X891933Y612593D02*
X895933D01*
G01Y609696D02*
Y612593D01*
G01Y609696D02*
X897949Y607680D01*
Y603495D01*
X901246Y600198D01*
Y597054D01*
X901600Y596700D01*
G01X881836Y682219D02*
Y686970D01*
G01Y694970D02*
Y698970D01*
G01Y694970D02*
X883060D01*
X884768Y696678D01*
X884903D01*
G01D02*
X889303D01*
G01X902236Y689332D02*
X900008Y691560D01*
X895751D01*
G01Y694119D02*
X902023D01*
X902236Y694332D01*
G01X881836Y686970D02*
Y690970D01*
G01X884911Y690279D02*
X883630Y691560D01*
X882426D01*
X881836Y690970D01*
G01X884911Y690279D02*
X885743D01*
X887024Y691560D01*
X889303D01*
G01X883686Y718570D02*
X884073Y718183D01*
Y715154D01*
X882765Y713846D01*
G01X882098Y741565D02*
Y740277D01*
X883575Y738800D01*
X887700D01*
X898400Y728100D01*
X930051D01*
X934880Y732929D01*
X942729D01*
X954065Y744265D01*
Y749665D01*
X954900Y750500D01*
X957500D01*
X973900Y734100D01*
X1107800D01*
X1137100Y704800D01*
X1150000D01*
X1155146Y699654D01*
Y699491D01*
G01X884976Y740891D02*
X887385D01*
X898936Y729340D01*
X929141D01*
X933948Y734147D01*
X942075D01*
X952847Y744919D01*
Y750347D01*
X954389Y751889D01*
X957773D01*
X974345Y735317D01*
X1108183D01*
X1137500Y706000D01*
X1154044D01*
X1157646Y702398D01*
Y699491D01*
G01X881637Y744154D02*
X882360D01*
X883628Y742886D01*
X887106D01*
X890647Y739345D01*
Y739343D01*
X899490Y730500D01*
X928399D01*
X933399Y735500D01*
X941714D01*
X951677Y745463D01*
Y750877D01*
X953859Y753059D01*
X958217D01*
X974825Y736451D01*
X1109149D01*
X1138395Y707205D01*
X1154443D01*
X1157698Y703950D01*
Y704075D01*
X1160146Y701627D01*
Y699491D01*
G01X893324Y722710D02*
Y726236D01*
X891527Y728033D01*
G01D02*
X888785Y725291D01*
Y724719D01*
X886836Y722770D01*
G01X883686D02*
Y718570D01*
G01X884463Y744757D02*
X886839D01*
X891795Y739801D01*
Y739799D01*
X899794Y731800D01*
X927999D01*
X932899Y736700D01*
X941100D01*
X950500Y746100D01*
Y751400D01*
X953300Y754200D01*
X958680D01*
X975080Y737800D01*
X1109400D01*
X1138700Y708500D01*
X1155773D01*
X1162946Y701327D01*
Y699791D01*
X1162646Y699491D01*
G01X892728Y792851D02*
X893706Y793829D01*
X900946Y796828D01*
X901226D01*
G01X892728Y789701D02*
X891305D01*
X889763Y788159D01*
G01X887916Y813465D02*
Y811959D01*
X889805Y810070D01*
Y806965D01*
X889305Y806465D01*
X887916D01*
G01X895050Y828548D02*
X893776Y827274D01*
Y806965D01*
X893276Y806465D01*
X891916D01*
G01X895916Y808965D02*
Y813465D01*
G01X889190Y821364D02*
X888665Y820097D01*
X885872Y817304D01*
Y807471D01*
X884866Y806465D01*
X883916D01*
G01Y808965D02*
Y813465D01*
G01X899916Y803315D02*
X898484D01*
X895829Y800660D01*
G01X891916Y803315D02*
Y799605D01*
G01X883916Y803315D02*
Y800815D01*
G01X890326Y828548D02*
X890919Y827955D01*
Y825007D01*
X891690Y824236D01*
Y820389D01*
X887916Y816615D01*
G01X890326Y828548D02*
Y829710D01*
X893100Y832484D01*
Y833864D01*
G01X895916Y816615D02*
Y818090D01*
X896690Y818864D01*
Y824430D01*
X896190Y824930D01*
X896161D01*
G01D02*
X897652Y826421D01*
Y830224D01*
X897117Y830759D01*
Y838993D01*
X898692Y840568D01*
G01X890817Y835193D02*
X891300Y834026D01*
Y833067D01*
X888154Y829921D01*
Y827652D01*
X889063Y826743D01*
Y821491D01*
X889190Y821364D01*
G01X887668Y834281D02*
X882051Y828664D01*
Y823503D01*
X884190Y821364D01*
G01X886664Y825717D02*
X884809Y827572D01*
Y829010D01*
X889268Y833469D01*
Y837393D01*
X889243Y837418D01*
G01X886664Y825717D02*
Y820359D01*
X883916Y817611D01*
Y816615D01*
G01X882944Y837418D02*
X881370Y835844D01*
G01X895542Y846867D02*
X893968Y845293D01*
G01X895542Y843717D02*
X893968Y842143D01*
G01X886093Y837418D02*
Y835318D01*
G01X895542Y840568D02*
X893968Y838994D01*
G01X892392Y843717D02*
X890818Y842143D01*
G01X895542Y837418D02*
X895540D01*
X893968Y835846D01*
G01X889243Y846867D02*
X887669Y845293D01*
G01X892392Y846867D02*
X890818Y845293D01*
G01X886093Y846867D02*
X884519Y845293D01*
G01X882944Y846867D02*
X881370Y845293D01*
G01X886093Y843717D02*
X884519Y842143D01*
G01X889243Y843717D02*
X887669Y842143D01*
G01X886093Y850016D02*
X884519Y848442D01*
G01X889243Y862615D02*
X887669Y864189D01*
G01X886093Y856316D02*
X884519Y854742D01*
G01X886093Y853166D02*
X884519Y851592D01*
G01X889243Y850016D02*
X887669Y848442D01*
G01X886093Y859465D02*
X884519Y857891D01*
G01X895542Y850016D02*
X893968Y848442D01*
G01X889243Y859465D02*
X887669Y857891D01*
G01X892392Y853166D02*
X890818Y851592D01*
G01X895542Y853166D02*
X893967Y851591D01*
G01X882944Y853166D02*
X881370Y851592D01*
G01X882944Y850016D02*
X881370Y848442D01*
G01X892392Y850016D02*
X890818Y848442D01*
G01X882944Y865764D02*
X881370Y867338D01*
G01X886093Y872064D02*
X884519Y873638D01*
G01X889243Y872064D02*
X887669Y873638D01*
G01X886093Y875213D02*
X884519Y876787D01*
G01X892392Y878363D02*
X890818Y879937D01*
G01X882944Y875213D02*
X881370Y876787D01*
G01X889243Y878363D02*
X887669Y879937D01*
G01X886093Y865764D02*
X884519Y867338D01*
G01X892392Y872064D02*
X890818Y873638D01*
G01X895542Y875213D02*
X893968Y876787D01*
G01X895542Y878363D02*
X893968Y879937D01*
G01X892392Y875213D02*
X890818Y876787D01*
G01X886093Y878363D02*
X884519Y879937D01*
G01X886093Y868914D02*
X884519Y870488D01*
G01X882944Y868914D02*
X881370Y870488D01*
G01X894154Y896438D02*
Y906352D01*
X892628Y907878D01*
Y909514D01*
G01X894154Y896438D02*
Y894262D01*
X897117Y891299D01*
Y883087D01*
X898692Y881512D01*
G01X896654Y903807D02*
X896516Y903669D01*
Y894100D01*
X898692Y891924D01*
Y884662D01*
G01X882944Y881512D02*
X881370Y883086D01*
G01X884628Y909514D02*
Y907348D01*
X889154Y902822D01*
Y896438D01*
G01D02*
X889491Y895625D01*
X893967Y891149D01*
Y883087D01*
X895542Y881512D01*
G01X891654Y900773D02*
Y895046D01*
X895542Y891158D01*
Y884662D01*
G01X884585Y886354D02*
X884533Y886302D01*
Y883072D01*
X886093Y881512D01*
G01X886654Y900773D02*
Y895456D01*
X892392Y889718D01*
Y884662D01*
G01X884154Y896438D02*
Y896372D01*
X890817Y889709D01*
Y883087D01*
X892392Y881512D01*
G01X885126Y889742D02*
X886400Y888468D01*
Y884969D01*
X886093Y884662D01*
G01X882944D02*
X881370Y886236D01*
G01X880628Y909514D02*
X884628D01*
G01X888628D02*
X891654Y906488D01*
Y900773D01*
G01X892628Y912664D02*
Y915242D01*
G01X888628Y912664D02*
Y915242D01*
G01X896553Y918042D02*
X896591Y918080D01*
X896628D01*
Y912664D01*
G01X896074Y940895D02*
X900983D01*
G01X891367Y941126D02*
Y940032D01*
X893861Y937538D01*
X904057D01*
G01X906128Y959165D02*
X901179D01*
X890389Y948375D01*
X886428D01*
G01X889445Y1219561D02*
X891201D01*
X892532Y1220112D01*
G01D02*
X895026Y1222606D01*
Y1222712D01*
G01X889445Y1221530D02*
X890377D01*
X894106Y1225259D01*
X897169D01*
G01X886819Y1444859D02*
X889244D01*
G01X892616Y1446517D02*
X893767Y1447668D01*
X897862D01*
G01X886819Y1448859D02*
X888465D01*
X890807Y1446517D01*
X892616D01*
G01X892244Y1440859D02*
X886819D01*
G01X892244D02*
X897084Y1445699D01*
X897812D01*
G01Y1459479D02*
Y1461891D01*
X892101Y1467602D01*
G01X897862Y1457510D02*
X895244D01*
G01X897862Y1449636D02*
X892244D01*
G01X886794Y1452663D02*
Y1452271D01*
X889429Y1449636D01*
X892244D01*
G01X893919Y1462132D02*
Y1463529D01*
X892589Y1464859D01*
X886819D01*
G01X897862Y1455542D02*
X894322D01*
X893338Y1456526D01*
Y1461551D01*
X893919Y1462132D01*
G01X892101Y1467602D02*
X891774Y1467929D01*
Y1473017D01*
X887932Y1476859D01*
X886819D01*
G01X883669D02*
X881244D01*
G01X886819Y1468859D02*
X889244D01*
G01X900110Y141247D02*
X903035D01*
G01X920454Y142648D02*
X918932D01*
X916784Y140500D01*
X906582D01*
X905835Y141247D01*
X903035D01*
G01X912308Y158194D02*
Y148325D01*
X911808Y147825D01*
X907191D01*
X906622Y147256D01*
Y145768D01*
G01X909772D02*
Y143868D01*
X909422Y143518D01*
X907522D01*
G01D02*
Y142392D01*
X907749Y142165D01*
X916164D01*
X918799Y144800D01*
X922000D01*
X922500Y144300D01*
Y140289D01*
X921906Y139695D01*
X920454D01*
G01X912308Y158194D02*
X912307Y158195D01*
X899573D01*
G01X1014520Y158245D02*
X999945D01*
X998900Y157200D01*
X954816D01*
X946472Y165544D01*
X919245D01*
X912867Y159166D01*
Y158753D01*
X912308Y158194D01*
G01X901815Y149414D02*
X906268D01*
X906622Y149768D01*
G01X901815Y152367D02*
X906616D01*
X906622Y152373D01*
G01D02*
Y149768D01*
G01X903297Y257480D02*
X897004D01*
G01X910492Y309471D02*
X911352D01*
X912125Y308698D01*
X914393D01*
X915653Y307438D01*
G01X910492Y312621D02*
X911352D01*
X912031Y313300D01*
X913615D01*
X915930Y310985D01*
X916992D01*
G01X911845Y363254D02*
X909589D01*
X905563Y359228D01*
Y355342D01*
X905483Y355262D01*
G01D02*
X904590Y354369D01*
X902335D01*
G01X905000Y362158D02*
Y361034D01*
X902335Y358369D01*
G01X911845Y367191D02*
X906161D01*
G01D02*
X904933Y365963D01*
Y364967D01*
X902335Y362369D01*
G01X911845Y365222D02*
X908064D01*
X905000Y362158D01*
G01X911072Y381332D02*
X910646Y380906D01*
Y376084D01*
G01D02*
X911676Y375054D01*
X916839D01*
X917406Y374487D01*
Y372752D01*
G01X902335Y370369D02*
Y366369D01*
G01Y374369D02*
Y370369D01*
G01X911845Y369160D02*
X909708D01*
X906344Y372524D01*
G01D02*
X904767Y370947D01*
Y368801D01*
X902335Y366369D01*
G01X897736Y385705D02*
Y383125D01*
G01X911630Y533706D02*
X912232D01*
X915612Y537086D01*
Y542537D01*
X915156Y543639D01*
X913728Y545067D01*
Y547348D01*
G01X905894Y561842D02*
X905918Y561818D01*
Y555563D01*
X905114Y554759D01*
Y551773D01*
G01X913728Y550495D02*
Y553776D01*
X910710Y556794D01*
Y560424D01*
X910511Y560905D01*
G01X899931Y539643D02*
X903431D01*
G01D02*
Y542515D01*
X903710Y542794D01*
Y544382D01*
G01X906878Y564037D02*
Y562284D01*
X906988Y562174D01*
Y559294D01*
X907474Y558808D01*
Y548909D01*
X905037Y546472D01*
Y545709D01*
X903710Y544382D01*
G01X897689Y544660D02*
X902400Y549371D01*
Y555003D01*
X904909Y557512D01*
Y564037D01*
G01X914296Y558143D02*
X911966Y560473D01*
X910815Y563252D01*
Y564037D01*
G01X916733Y575356D02*
X918024D01*
X918431Y575763D01*
X920870D01*
G01X916725Y573387D02*
X917764D01*
X920544Y570607D01*
G01X923599Y581578D02*
X918971D01*
X917319Y583230D01*
X916733D01*
G01X913998Y597103D02*
X912783Y595888D01*
Y594549D01*
G01X913998Y597103D02*
X913843Y597258D01*
X912046D01*
X910815Y596027D01*
Y594549D01*
G01X906886Y683770D02*
X902349D01*
X901716Y684403D01*
X897291D01*
G01X906886Y687770D02*
Y683770D01*
G01X910036D02*
X912462D01*
G01X909265Y677795D02*
X912469D01*
X913266Y676998D01*
X919325D01*
X920122Y677795D01*
X921418D01*
G01X906886Y691770D02*
X904674D01*
X902236Y689332D01*
G01X906886Y691770D02*
Y687770D01*
G01X902236Y694332D02*
X903674Y695770D01*
X906886D01*
G01X907324Y713510D02*
Y716414D01*
X907686Y716776D01*
Y718970D01*
G01X920875Y704111D02*
X914365D01*
X912015Y706461D01*
Y712972D01*
X913247Y714204D01*
G01X901198Y718970D02*
Y721386D01*
X903543Y723731D01*
X906457D01*
G01D02*
X907686Y722502D01*
Y718970D01*
G01X901226Y796828D02*
X901396Y796998D01*
X903819Y798002D01*
X905500Y799683D01*
Y802699D01*
X904884Y803315D01*
X903916D01*
G01X911416Y806465D02*
X911426Y806475D01*
X915706D01*
X915716Y806465D01*
G01X903916D02*
X905946Y808495D01*
X906700Y810316D01*
Y815613D01*
X905698Y816615D01*
X903916D01*
G01X899916Y808965D02*
Y813465D01*
G01X901690Y825699D02*
X901680Y825689D01*
Y809797D01*
X902000Y809477D01*
Y807501D01*
X900964Y806465D01*
X899916D01*
G01X911290Y837418D02*
X910829Y836305D01*
X907884Y833360D01*
Y829866D01*
G01X908140Y837418D02*
X907471Y835804D01*
X904953Y833286D01*
Y822127D01*
X904940Y822114D01*
Y821364D01*
G01D02*
Y819433D01*
X903916Y818409D01*
Y816615D01*
G01X909416D02*
Y819109D01*
X908378Y820147D01*
Y825308D01*
G01D02*
X912000Y828930D01*
Y835355D01*
X912880Y836235D01*
Y838978D01*
X911290Y840568D01*
G01X899916Y816615D02*
X899190Y817341D01*
Y821269D01*
G01D02*
Y821364D01*
X899078Y821476D01*
Y832182D01*
X903431Y836535D01*
Y838978D01*
X901841Y840568D01*
G01X904991Y837418D02*
Y836290D01*
X901690Y832989D01*
Y825699D01*
G01X901841Y837418D02*
X900267Y838992D01*
G01X898692Y843717D02*
X897118Y842143D01*
G01X904991Y843717D02*
X906565Y842143D01*
G01X901841Y846867D02*
X900267Y845293D01*
G01X901841Y843717D02*
X900267Y842143D01*
G01X898692Y846867D02*
X897118Y845293D01*
G01X904991Y846867D02*
X906565Y845293D01*
G01X898692Y837418D02*
X900266Y835844D01*
G01X908140Y850016D02*
X909714Y848442D01*
G01X908140Y853166D02*
X909714Y851592D01*
G01X904154Y896438D02*
Y894021D01*
X903416Y893283D01*
Y879938D01*
X901841Y878363D01*
G01X898692D02*
X897118Y879937D01*
G01X911290Y878363D02*
X912864Y879937D01*
G01X908140Y878363D02*
X909714Y879937D01*
G01X904991Y878363D02*
X906565Y879937D01*
G01X911290Y875213D02*
X912864Y876787D01*
G01X907300Y909525D02*
X904154Y906379D01*
Y896438D01*
G01X901841Y881512D02*
X900266Y883087D01*
Y891934D01*
X897789Y894411D01*
Y897808D01*
X899103Y899122D01*
Y899321D01*
G01X901654Y903844D02*
Y895892D01*
X901841Y895705D01*
Y884662D01*
G01X908140Y881512D02*
X909715Y883087D01*
Y890279D01*
X914154Y894718D01*
Y896438D01*
G01X911654Y900773D02*
Y895102D01*
X908140Y891588D01*
Y884662D01*
G01X911290D02*
Y889605D01*
X916654Y894969D01*
Y900773D01*
G01X904991Y881512D02*
X906566Y883087D01*
Y891862D01*
X909154Y894450D01*
Y896438D01*
G01D02*
Y902419D01*
X911200Y904465D01*
Y906125D01*
X914500Y909425D01*
G01X906654Y900773D02*
Y894096D01*
X904991Y892433D01*
Y884662D01*
G01X911290Y881512D02*
X912865Y883087D01*
Y888535D01*
X919154Y894824D01*
Y896438D01*
G01X896654Y903807D02*
Y907852D01*
X896628Y907878D01*
Y909514D01*
G01X899103Y899321D02*
X899154Y899372D01*
Y906404D01*
X900200Y907450D01*
Y909525D01*
G01X903700D02*
X901654Y907479D01*
Y903844D01*
G01X912628Y915242D02*
X910900Y913514D01*
Y912575D01*
G01X918100Y909425D02*
X918028D01*
X911654Y903051D01*
Y900773D01*
G01X910900Y909425D02*
X909075Y907600D01*
X907901D01*
X906654Y906353D01*
Y900773D01*
G01X900200Y912675D02*
X900628Y913103D01*
Y915242D01*
G01X904838Y918042D02*
X902700Y915904D01*
Y913675D01*
X903700Y912675D01*
G01X907300D02*
Y913914D01*
X908628Y915242D01*
G01X912628D02*
X914488Y917102D01*
Y919054D01*
X912628Y920914D01*
Y922551D01*
G01X900983Y940895D02*
X901190Y940688D01*
X904057D01*
G01X906128Y959165D02*
X923635D01*
X929741Y965271D01*
Y967006D01*
G01X911199Y1084659D02*
Y1088659D01*
G01X904909Y1092685D02*
X906344D01*
X908799Y1090230D01*
Y1088659D01*
G01D02*
X911199D01*
G01Y1076659D02*
Y1080659D01*
G01D02*
X911103D01*
X908278Y1083484D01*
G01X904909Y1090716D02*
X905951D01*
X906821Y1089846D01*
Y1084941D01*
X908278Y1083484D01*
G01X904909Y1094653D02*
X907805D01*
X908799Y1093659D01*
G01D02*
X909799Y1092659D01*
X911199D01*
G01X904909Y1096622D02*
X906323D01*
X906823Y1097122D01*
Y1100159D01*
X907323Y1100659D01*
X908799D01*
G01D02*
X911199D01*
G01X902350Y1099181D02*
Y1104330D01*
X902353Y1104333D01*
G01D02*
X905590D01*
X905916Y1104659D01*
X911199D01*
G01X901392Y1207823D02*
X903959D01*
G01X908852Y1228083D02*
X907745D01*
X906309Y1226647D01*
G01X908852Y1228083D02*
X912726D01*
G01Y1224933D02*
Y1222115D01*
X913784Y1221057D01*
G01X909077Y1232724D02*
X909838Y1233485D01*
Y1275242D01*
X913254Y1278658D01*
X962102D01*
X972203Y1268557D01*
Y1230436D01*
X968344Y1226577D01*
X966018D01*
X962153Y1222712D01*
G01X909077Y1232724D02*
Y1232376D01*
X902638Y1225937D01*
X901401D01*
X898176Y1222712D01*
G01X927393Y107899D02*
X931393D01*
G01X927096Y113684D02*
Y111534D01*
X927846Y110784D01*
X930118D01*
G01X925128Y113684D02*
Y110794D01*
X925118Y110784D01*
G01D02*
X923393Y109059D01*
Y107899D01*
G01X925418Y130898D02*
Y133400D01*
X925600Y133582D01*
Y135300D01*
X925418Y135482D01*
Y145177D01*
X922845Y147754D01*
X918607D01*
G01X925128Y121558D02*
Y123785D01*
X924675Y124879D01*
G01D02*
Y127005D01*
X925418Y127748D01*
G01X927096Y121558D02*
Y124163D01*
X927596Y124663D01*
X929697D01*
G01X923160Y121558D02*
Y123126D01*
X922003Y124283D01*
X919609D01*
G01D02*
X919641Y124315D01*
Y125971D01*
X921418Y127748D01*
G01X915267Y157370D02*
Y148980D01*
X916496Y147754D01*
X918607D01*
G01X927540Y136742D02*
Y138338D01*
X928040Y138838D01*
X931041D01*
G01X918607Y150904D02*
Y154865D01*
G01X933259Y161958D02*
Y158209D01*
X932759Y157709D01*
X926388D01*
X923544Y154865D01*
G01D02*
X918607D01*
G01X1021826Y186778D02*
X1025200Y183404D01*
Y168800D01*
X1022500Y166100D01*
X1019900D01*
X1013739Y159939D01*
X999124D01*
X998006Y158821D01*
X956547D01*
X947393Y167975D01*
X916453D01*
G01X916770Y304585D02*
Y306321D01*
X915653Y307438D01*
G01X916992Y310985D02*
Y309265D01*
X917734Y308523D01*
Y307301D01*
X918634Y306401D01*
X921234D01*
X922054Y307221D01*
X936359D01*
X937567Y306013D01*
G01X919920Y304585D02*
X923732D01*
G01D02*
X924402Y305255D01*
X927577D01*
G01X921343Y376888D02*
Y372752D01*
G01X915437D02*
X913288D01*
G01X916330Y377748D02*
X917836Y376242D01*
X918493D01*
X919375Y375360D01*
Y372752D01*
G01X923072Y381332D02*
Y378935D01*
X923311Y378696D01*
Y372752D01*
G01X919072Y381332D02*
Y379285D01*
X921343Y377014D01*
Y376888D01*
G01X915072Y381332D02*
Y379006D01*
X916330Y377748D01*
G01X927072Y381332D02*
X923072D01*
G01X931072D02*
X927072D01*
G01X935924Y447942D02*
X931726D01*
X931237Y447453D01*
X927596D01*
G01D02*
X926481Y448568D01*
X924412D01*
G01X933161Y451442D02*
X931381D01*
X928349Y454474D01*
X924511D01*
G01X920999Y472367D02*
Y470302D01*
X921973Y469328D01*
G01X924999Y472367D02*
X920999D01*
G01X921973Y469328D02*
X920967Y468322D01*
Y465891D01*
G01X924999Y475517D02*
Y477948D01*
G01X950953Y317947D02*
X964519Y331513D01*
Y378716D01*
X945742Y397493D01*
Y475142D01*
X935613Y485271D01*
X920301D01*
X916925Y488647D01*
Y495158D01*
X918196Y496429D01*
X927295D01*
G01X937567Y306013D02*
X945372D01*
X966924Y327565D01*
Y378490D01*
X947382Y398032D01*
Y492456D01*
X933409Y506429D01*
X915799D01*
G01X917250Y554695D02*
X915698Y556247D01*
Y556741D01*
X914296Y558143D01*
G01X913728Y550495D02*
Y547348D01*
G01X917811D02*
X917250Y547909D01*
Y551545D01*
G01X919976Y540006D02*
X923459D01*
X923959Y540506D01*
Y543775D01*
X923409Y544325D01*
X917811D01*
G01D02*
Y547348D01*
G01X926077Y573578D02*
X923515D01*
X920544Y570607D01*
G01X926077Y569578D02*
X923453D01*
G01X926077Y565578D02*
Y569578D01*
G01X915244Y570435D02*
X917242D01*
X919544Y568133D01*
X922008D01*
X923453Y569578D01*
G01X926077Y557641D02*
Y561578D01*
G01X923642D02*
X926077D01*
G01X923642D02*
X916754Y568466D01*
X915244D01*
G01X920870Y575763D02*
X924262D01*
X926077Y577578D01*
G01X923599Y581578D02*
X926077D01*
G01X921217Y589216D02*
X920093D01*
X919909Y589400D01*
X918400D01*
X917151Y588151D01*
X915244D01*
G01X925418Y680945D02*
X921418D01*
G01X919328Y685622D02*
Y683035D01*
X921418Y680945D01*
G01X928672Y703241D02*
Y696883D01*
G01X924932Y687237D02*
X920943D01*
X919328Y685622D01*
G01X913247Y714204D02*
Y715456D01*
X918361Y720570D01*
G01X924025Y704111D02*
X925633D01*
X926503Y703241D01*
X928672D01*
G01X915198Y709770D02*
X921061D01*
G01X925061D02*
X929822D01*
G01X921061D02*
X925061D01*
G01Y712920D02*
Y718670D01*
X926961Y720570D01*
G01D02*
Y723797D01*
G01X915716Y806465D02*
Y808541D01*
X913716Y810541D01*
Y811954D01*
G01D02*
X915377Y813615D01*
Y832651D01*
X914549Y834649D01*
Y837309D01*
X914440Y837418D01*
G01X923790Y806465D02*
X919664D01*
G01D02*
Y808835D01*
X917803Y810696D01*
Y811365D01*
G01D02*
X918927Y812489D01*
Y833374D01*
X916409Y835892D01*
X916015Y836844D01*
Y838993D01*
X914440Y840568D01*
G01X927916Y817015D02*
Y814615D01*
G01Y800909D02*
Y803315D01*
G01Y811465D02*
X926798D01*
X925228Y813035D01*
Y816934D01*
G01X927916Y806465D02*
Y811465D01*
G01X931916D02*
X930354D01*
X929854Y811965D01*
Y818817D01*
X927662Y821009D01*
G01X923888Y837418D02*
Y835812D01*
X927302Y832398D01*
Y827158D01*
X927662Y826798D01*
Y821009D01*
G01X925302Y825658D02*
Y819629D01*
X927916Y817015D01*
G01X920739Y840568D02*
X922314Y838993D01*
Y835790D01*
X922812Y834588D01*
X925302Y832098D01*
Y825658D01*
G01X922431Y821308D02*
Y818875D01*
X921790Y818234D01*
Y816615D01*
G01X920739Y837418D02*
X920900Y837257D01*
Y834000D01*
X922431Y832469D01*
Y821308D01*
G01X914440Y843717D02*
X916014Y842143D01*
G01X917589Y846867D02*
X919163Y845293D01*
G01X920739Y843717D02*
X922313Y842143D01*
G01X914440Y846867D02*
X916014Y845293D01*
G01X917589Y837418D02*
X919163Y835844D01*
G01X917589Y840568D02*
X919163Y838994D01*
G01X917589Y843717D02*
X919163Y842143D01*
G01X927038Y853166D02*
X927785Y852419D01*
X931948D01*
X932647Y853118D01*
X933773D01*
X934590Y853935D01*
Y858701D01*
X936279Y862779D01*
X936974Y863474D01*
X939000D01*
G01X946482Y869624D02*
X942916Y866058D01*
X937466D01*
X935688Y864280D01*
X933470Y858926D01*
Y856712D01*
X931460Y854702D01*
X927407D01*
X927342Y854729D01*
X925475D01*
X923888Y856316D01*
G01X926066Y848441D02*
X928123D01*
G01X920739Y862615D02*
X922313Y864189D01*
G01X920739Y859465D02*
X922313Y857891D01*
G01X928612Y864189D02*
X927038Y862615D01*
G01X917589D02*
X919163Y864189D01*
G01X923888Y862615D02*
X925462Y864189D01*
G01X923888Y872064D02*
X925462Y873638D01*
G01X920739Y875213D02*
X922313Y876787D01*
G01X928612Y870488D02*
X927038Y868914D01*
G01X923888D02*
X925462Y870488D01*
G01X914440Y872064D02*
X916014Y873638D01*
G01X920739Y872064D02*
X922313Y873638D01*
G01X914440Y875213D02*
X916014Y876787D01*
G01X928612Y873638D02*
X927038Y872064D01*
G01X923888Y875213D02*
X925462Y876787D01*
G01X928612D02*
X927038Y875213D01*
G01X928612Y879937D02*
X927038Y878363D01*
G01X914440D02*
X916014Y879937D01*
G01X920739Y878363D02*
X922313Y879937D01*
G01X917589Y878363D02*
X919163Y879937D01*
G01X923888Y878363D02*
X925462Y879937D01*
G01X927038Y865764D02*
X930300Y869026D01*
Y878924D01*
X931634Y880258D01*
X938072D01*
X939309Y879021D01*
G01X917589Y872064D02*
X919163Y873638D01*
G01X917589Y868914D02*
X919163Y870488D01*
G01X920739Y868914D02*
X922313Y870488D01*
G01X917589Y875213D02*
X919163Y876787D01*
G01X920739Y865764D02*
X922313Y867338D01*
G01X917589Y865764D02*
X919163Y867338D01*
G01X923888Y865764D02*
X925462Y867338D01*
G01X920739Y881512D02*
X922313Y883086D01*
G01X920739Y884662D02*
X922313Y886236D01*
G01X923888Y884662D02*
X925462Y886236D01*
G01X917589Y881512D02*
X919163Y883086D01*
G01X928612Y886236D02*
X927038Y884662D01*
G01X923888Y881512D02*
X925462Y883086D01*
G01X940628Y909514D02*
X933339Y902225D01*
X928760D01*
X927785Y903200D01*
X925742D01*
X924154Y901612D01*
Y896438D01*
G01D02*
Y894660D01*
X916015Y886521D01*
Y883087D01*
X914440Y881512D01*
G01X914154Y896438D02*
Y902454D01*
X921214Y909514D01*
X924628D01*
G01X921654Y900773D02*
Y894490D01*
X914440Y887276D01*
Y884662D01*
G01X926654Y900773D02*
Y893727D01*
X917589Y884662D01*
G01X919154Y896438D02*
Y904154D01*
X920700Y905700D01*
X926836D01*
X928968Y907832D01*
X930946D01*
X932628Y909514D01*
G01X928612Y883086D02*
X927038Y881512D01*
G01X924628Y915242D02*
Y912664D01*
G01X920628Y915242D02*
Y915103D01*
X918100Y912575D01*
G01X928628Y915242D02*
Y912664D01*
G01X916628Y915242D02*
X914500Y913114D01*
Y912575D01*
G01X916654Y900773D02*
Y903354D01*
X920400Y907100D01*
X926214D01*
X928628Y909514D01*
G01X936628D02*
X933826Y906712D01*
X929432D01*
X927120Y904400D01*
X925281D01*
X921654Y900773D01*
G01X944628Y909514D02*
X943925Y908811D01*
X942865D01*
X934827Y900773D01*
X926654D01*
G01X924628Y922551D02*
Y920914D01*
X926488Y919054D01*
Y917102D01*
X924628Y915242D01*
G01X920628Y922551D02*
Y920914D01*
X922488Y919054D01*
Y917102D01*
X920628Y915242D01*
G01X928628D02*
X930488Y917102D01*
Y919054D01*
X928628Y920914D01*
Y922551D01*
G01X916628D02*
Y920914D01*
X918488Y919054D01*
Y917102D01*
X916628Y915242D01*
G01X916875Y1098643D02*
X915733Y1099785D01*
X915223D01*
X914349Y1100659D01*
G01Y1104659D02*
X916749D01*
G01Y1092664D02*
X914354D01*
X914349Y1092659D01*
G01Y1096659D02*
X916749Y1094259D01*
Y1092664D01*
G01X930754Y1310564D02*
X921400Y1319918D01*
Y1355754D01*
X927193Y1361547D01*
G01X915480Y1449636D02*
X917176D01*
X917640Y1449172D01*
Y1444336D01*
X918483Y1443493D01*
X920235D01*
G01X922265Y1449536D02*
X920393D01*
X919422Y1448565D01*
Y1445732D01*
X920235Y1444919D01*
Y1443493D01*
G01X925415Y1449536D02*
X922571Y1446692D01*
X921498D01*
G01X917744Y1453573D02*
X919480D01*
X920188Y1454281D01*
X921868D01*
G01X920244Y1451605D02*
X915480D01*
G01X920244D02*
X923051D01*
X925697Y1454251D01*
G01X921629Y1468100D02*
Y1463235D01*
G01D02*
X919528Y1461134D01*
Y1460342D01*
X917204Y1458018D01*
Y1456634D01*
X916112Y1455542D01*
X915480D01*
G01X921868Y1457431D02*
X920490D01*
X919285Y1456226D01*
G01X921653Y1476971D02*
X919589Y1474907D01*
Y1464606D01*
X917727Y1462744D01*
Y1460416D01*
X916790Y1459479D01*
X915530D01*
G01X924779Y1468100D02*
X927077Y1470398D01*
Y1476472D01*
X925435Y1478114D01*
G01X921653Y1472100D02*
Y1476971D01*
G01X956161Y92874D02*
X947248D01*
X945011Y95111D01*
G01X942162Y102495D02*
Y106495D01*
G01D02*
X946078D01*
X946144Y106561D01*
G01X930118Y110784D02*
X931393Y109509D01*
Y107899D01*
G01X933472Y130903D02*
X933441Y130934D01*
Y134838D01*
G01X933472Y127753D02*
Y126313D01*
X934678Y125107D01*
G01X929697Y124663D02*
Y126008D01*
X929418Y126287D01*
Y127748D01*
G01X940062Y143762D02*
X943292D01*
G01X940062Y146912D02*
Y148000D01*
X939345Y148717D01*
X937192D01*
G01D02*
X931067D01*
X929519Y150265D01*
Y153296D01*
G01X933441Y134838D02*
Y138838D01*
G01X931041D02*
X933441D01*
G01X946234Y213390D02*
Y212630D01*
X944922Y211318D01*
Y210226D01*
G01X942953D02*
Y214953D01*
X942179Y215727D01*
G01X939016Y210226D02*
Y212239D01*
X937438Y213817D01*
G01X945591Y226852D02*
X944950Y226211D01*
Y218863D01*
X945658Y218155D01*
X947040D01*
G01X942805Y218130D02*
X942179Y217504D01*
Y215727D01*
G01X938125Y236819D02*
X942521D01*
X942568Y236866D01*
G01X943111Y242721D02*
Y240981D01*
X944248Y239844D01*
G01D02*
X942568Y238164D01*
Y236866D01*
G01X940158Y249807D02*
X936962D01*
G01X943111D02*
Y254260D01*
X942757Y254614D01*
G01X936962Y249807D02*
Y252339D01*
X939433Y254810D01*
X942561D01*
X942757Y254614D01*
G01X930841Y357348D02*
X931948D01*
X934128Y355168D01*
G01D02*
X936131Y353165D01*
X937134Y352749D01*
X938602Y351281D01*
G01X944238Y360828D02*
Y358340D01*
X944739Y357839D01*
X947827D01*
X948452Y358464D01*
Y360607D01*
G01X941685Y360828D02*
X940241D01*
X939801Y360388D01*
X935575D01*
X934677Y361286D01*
X930841D01*
G01X941685Y360828D02*
X944238D01*
G01X936175Y364823D02*
X932387Y363254D01*
X930841D01*
G01X936175Y364823D02*
X938470D01*
X938657Y364636D01*
G01Y367786D02*
X942431D01*
X942437Y367780D01*
G01X955144Y365725D02*
X952584Y368285D01*
X943985D01*
X943480Y367780D01*
X942437D01*
G01X929947Y376821D02*
X931072Y377946D01*
Y381332D01*
G01X939074Y440942D02*
X941872D01*
G01X935924D02*
Y444442D01*
G01D02*
Y447942D01*
G01X933161Y451442D02*
X935924D01*
G01X942572Y527726D02*
X939992D01*
G01X942572Y544726D02*
X939992D01*
G01X944290Y625311D02*
X941859D01*
G01X932412Y696883D02*
Y695459D01*
X935680Y692191D01*
X949306D01*
X953692Y696577D01*
G01X932117Y802470D02*
X933201Y801386D01*
Y798297D01*
G01D02*
X933175Y798271D01*
X930781D01*
G01X943475Y798194D02*
X947466D01*
X949609Y796051D01*
G01X931916Y811465D02*
X932117Y811264D01*
Y806210D01*
G01X938357Y804886D02*
Y808856D01*
G01X944552Y864862D02*
X942916D01*
X941528Y863474D01*
X939000D01*
G01X944489Y883146D02*
X943434D01*
X939309Y879021D01*
G01X936628Y915242D02*
Y912664D01*
G01X947029Y915242D02*
X944628Y912841D01*
Y912664D01*
G01X940628Y915242D02*
Y912664D01*
G01X932628Y915242D02*
Y912664D01*
G01X936628Y922551D02*
Y920914D01*
X938488Y919054D01*
Y917102D01*
X936628Y915242D01*
G01X944628Y922551D02*
Y917643D01*
X947029Y915242D01*
G01X940628Y922551D02*
Y915242D01*
G01X932628Y922551D02*
Y920914D01*
X934488Y919054D01*
Y917102D01*
X932628Y915242D01*
G01X929741Y967006D02*
Y980988D01*
X937571Y988818D01*
X945671D01*
G01X956161Y99961D02*
X951386D01*
X949221Y102126D01*
Y103411D01*
G01X946346Y97667D02*
X949615D01*
G01X956161Y97599D02*
X949683D01*
X949615Y97667D01*
G01X956161Y88150D02*
X963258D01*
X965723Y90615D01*
G01X956161Y90512D02*
X960273D01*
X960411Y90650D01*
G01X960161Y95236D02*
X956161D01*
G01X949221Y103411D02*
X946144D01*
G01Y106561D02*
X949380D01*
G01X947040Y218155D02*
Y216351D01*
X946234Y215545D01*
Y213390D01*
G01X948741Y226852D02*
Y229468D01*
G01X951278Y237973D02*
X958159D01*
X963715Y243529D01*
Y255701D01*
X966894Y258880D01*
X972160D01*
G01X951278Y244952D02*
Y241123D01*
G01X946064Y242721D02*
X946321Y242464D01*
X948785D01*
G01D02*
X950126Y241123D01*
X951278D01*
G01X947664Y316739D02*
X949745D01*
X950953Y317947D01*
G01X1126622Y506256D02*
X1124272Y508606D01*
X1060351D01*
X1045765Y494020D01*
Y468866D01*
X1012199Y435300D01*
X967499D01*
X953900Y448899D01*
Y469909D01*
X954485Y470494D01*
X955816D01*
G01X962816Y448494D02*
X960528D01*
X959816Y449206D01*
Y454376D01*
G01X955816Y473419D02*
Y470494D01*
G01X959816Y467344D02*
X955816D01*
G01X956863Y461462D02*
Y463872D01*
X955816Y464919D01*
G01D02*
Y467344D01*
G01X959816Y461462D02*
Y463419D01*
X960816Y464419D01*
X963816D01*
G01X958124Y492354D02*
Y491723D01*
X956441Y490040D01*
X956171D01*
X955553Y489422D01*
Y487982D01*
G01X958736Y482165D02*
X955553Y478982D01*
G01X962327Y489743D02*
X961385D01*
X959513Y487871D01*
Y482942D01*
X958736Y482165D01*
G01X952403Y491982D02*
X949823D01*
G01X955553D02*
Y495982D01*
G01X959600Y496486D02*
X960437Y495649D01*
X962327D01*
G01X955553Y495982D02*
X959096D01*
X959600Y496486D01*
G01X962327Y493680D02*
X959903D01*
X958577Y492354D01*
X958124D01*
G01X957977Y500202D02*
X955773D01*
X955553Y499982D01*
G01X962327Y497617D02*
X962124D01*
X959539Y500202D01*
X957977D01*
G01X945722Y527726D02*
Y531726D01*
G01X948905Y534909D02*
X945722Y531726D01*
G01X952496Y536487D02*
X950483D01*
X948905Y534909D01*
G01X945722Y544726D02*
Y548726D01*
G01X948598Y546553D02*
Y548057D01*
X947929Y548726D01*
X945722D01*
G01X952496Y542393D02*
X951043D01*
X948598Y544838D01*
Y546553D01*
G01X945722Y552726D02*
X948621D01*
G01X952496Y544361D02*
X951774D01*
X951186Y544949D01*
Y550161D01*
X948621Y552726D01*
G01X945722Y540726D02*
X946886D01*
X947295Y541135D01*
X948532D01*
G01X952496Y540424D02*
X950684D01*
X949973Y541135D01*
X948532D01*
G01X947440Y621311D02*
X949505D01*
X950479Y622285D01*
G01X947440Y625311D02*
Y621311D01*
G01X950479Y622285D02*
X951485Y621279D01*
X953916D01*
G01X953692Y696577D02*
Y701116D01*
X953551Y701257D01*
G01X947556Y705200D02*
Y707075D01*
X946086Y708545D01*
Y712147D01*
G01X955950Y734178D02*
X954834D01*
X953181Y732525D01*
X949185D01*
X948546Y731886D01*
Y716222D01*
X946086Y713762D01*
Y712147D01*
G01X953551Y704407D02*
X957551D01*
G01X954023Y711157D02*
X954554Y710626D01*
Y708376D01*
X956023Y706907D01*
G01D02*
X956107D01*
X957551Y705463D01*
Y704407D01*
G01X961503Y720803D02*
Y724557D01*
X962003Y725057D01*
X963869D01*
G01X959950Y728463D02*
X963950D01*
G01X955950Y731613D02*
Y734178D01*
G01X957763Y720803D02*
Y725336D01*
G01D02*
X955950Y727149D01*
Y728463D01*
G01X959950Y731613D02*
Y734178D01*
G01X957579Y744168D02*
X962152Y739595D01*
X963905D01*
X978810Y724690D01*
Y717243D01*
X979539Y716514D01*
X983712D01*
G01X1168485Y767435D02*
Y763985D01*
X1156399Y751899D01*
X1120081D01*
X1088923Y745701D01*
X1030018Y739900D01*
X976100D01*
X953837Y762163D01*
Y763025D01*
G01X949453Y782467D02*
Y780957D01*
X950699Y779711D01*
G01X949609Y796051D02*
Y792505D01*
G01X949378Y786366D02*
X946970D01*
G01X957487Y798553D02*
X953621Y802419D01*
X950109D01*
X949609Y801919D01*
Y799233D01*
G01X956239Y829577D02*
X957428Y830766D01*
X958095D01*
X958682Y831353D01*
G01X955712Y833988D02*
X958167D01*
X958682Y834503D01*
G01X947639Y883146D02*
Y881591D01*
X948624Y880606D01*
X951223D01*
X952311Y879518D01*
Y877763D01*
X953240Y876834D01*
G01X946482Y869624D02*
X949049Y872191D01*
X955828D01*
X956273Y871746D01*
Y870278D01*
G01X947639Y883146D02*
X949276D01*
X949334Y883088D01*
X952370D01*
X952404Y883054D01*
X954033D01*
X954124Y883145D01*
G01X958567Y930244D02*
Y927654D01*
G01X954676Y944423D02*
Y938981D01*
X951863Y936168D01*
G01X950567Y933394D02*
X954567D01*
G01X951863Y936168D02*
X953016D01*
X954676Y934508D01*
Y933503D01*
X954567Y933394D01*
G01X958567D02*
X957235Y934726D01*
Y936398D01*
G01D02*
Y944423D01*
G01X962329Y936229D02*
Y938536D01*
X959794Y941071D01*
Y944423D01*
G01X957671Y977921D02*
X959794Y975798D01*
Y967455D01*
G01X953671Y982191D02*
Y976593D01*
X957235Y973029D01*
Y967455D01*
G01X949671Y977921D02*
X954676Y972916D01*
Y967455D01*
G01X945671Y982191D02*
Y977735D01*
X952117Y971289D01*
Y967455D01*
G01X949671Y988818D02*
Y991564D01*
G01X961671Y985668D02*
X957671Y981668D01*
Y977921D01*
G01Y985668D02*
X961671D01*
G01X953671D02*
Y982191D01*
G01X949671Y985668D02*
Y977921D01*
G01X945671Y985668D02*
Y982191D01*
G01X953422Y1219561D02*
X955178D01*
X956509Y1220112D01*
G01X959003Y1222712D02*
Y1222606D01*
X956509Y1220112D01*
G01X953422Y1221530D02*
X954354D01*
X958083Y1225259D01*
X961146D01*
G01X974271Y92874D02*
X979002D01*
G01X970094Y95236D02*
X974271D01*
G01Y99961D02*
X970044D01*
G01X976763Y320273D02*
Y319671D01*
X980143Y316291D01*
X985567D01*
X986716Y316767D01*
X988124Y318175D01*
X990405D01*
G01X978031Y343112D02*
X975631D01*
G01X978031Y346612D02*
X975631D01*
G01X966694Y427599D02*
X971721Y422572D01*
Y407762D01*
G01X968348Y402369D02*
X970736D01*
X974522Y406155D01*
Y423308D01*
X968462Y429368D01*
G01X991392Y409230D02*
Y410621D01*
X971826Y430187D01*
G01X977327Y451557D02*
Y448505D01*
X974893Y446071D01*
X972030D01*
G01D02*
X971932Y445973D01*
Y443069D01*
G01X962769Y454376D02*
Y451419D01*
G01D02*
X962816Y451372D01*
Y448494D01*
G01X975932Y443069D02*
X979932D01*
G01X976397Y470634D02*
Y473045D01*
G01X972397Y467404D02*
Y465004D01*
G01D02*
X975359Y462042D01*
Y459431D01*
G01X967816Y467344D02*
X963816D01*
G01Y464419D02*
Y467344D01*
G01X977327Y459431D02*
Y462371D01*
G01D02*
X976397Y463301D01*
Y467484D01*
G01X973857Y599650D02*
Y594976D01*
X978032Y590801D01*
G01X973857Y602800D02*
Y605443D01*
G01X971865Y636236D02*
Y632038D01*
X972354Y631549D01*
Y627908D01*
G01X975365Y636236D02*
X971865D01*
G01X978865D02*
X975365D01*
G01X972354Y627908D02*
X971239Y626793D01*
Y624724D01*
G01X965333Y624823D02*
Y628661D01*
X968365Y631693D01*
Y633473D01*
G01D02*
Y636236D01*
G01X973712Y716514D02*
X972792Y715594D01*
Y710988D01*
G01D02*
Y708434D01*
X985843Y695383D01*
X1001191D01*
G01X963869Y725057D02*
X963950Y725138D01*
Y728463D01*
G01Y731613D02*
Y734178D01*
G01X973450Y747280D02*
X974094Y747924D01*
X982090Y751236D01*
X988191D01*
X991571Y747856D01*
X1026608D01*
X1071934Y752320D01*
X1110921Y760075D01*
X1151988D01*
X1156485Y764572D01*
Y767567D01*
G01X1002751Y757169D02*
X984666D01*
X972500Y769335D01*
Y816000D01*
X970700Y817800D01*
Y830999D01*
X967400Y834299D01*
Y859799D01*
X963374Y863825D01*
Y901826D01*
X963116Y902084D01*
X962453Y903685D01*
Y906853D01*
X983227Y927627D01*
Y968565D01*
G01X973516Y827907D02*
X973510Y831799D01*
G01D02*
Y834991D01*
G01X978880Y869552D02*
X977558D01*
X976815Y870295D01*
X972833D01*
G01X992441Y870398D02*
X990461Y872378D01*
X986986Y873817D01*
X978587D01*
X977109Y875295D01*
X972833D01*
G01Y905295D02*
X967552D01*
X966813Y904556D01*
G01X964280Y927777D02*
X964303Y927800D01*
Y928508D01*
X962567Y930244D01*
G01X962329Y936229D02*
Y933632D01*
X962567Y933394D01*
G01X962746Y967455D02*
Y979266D01*
X965671Y982191D01*
G01D02*
Y985668D01*
G01X975176Y1076659D02*
Y1080659D01*
G01X968886Y1090716D02*
X969928D01*
X970798Y1089846D01*
Y1084941D01*
X972255Y1083484D01*
G01D02*
X975080Y1080659D01*
X975176D01*
G01Y1084659D02*
Y1088659D01*
G01X968886Y1092685D02*
X970321D01*
X972776Y1090230D01*
Y1088659D01*
G01D02*
X975176D01*
G01Y1092659D02*
X973776D01*
X972776Y1093659D01*
G01X968886Y1094653D02*
X971782D01*
X972776Y1093659D01*
G01X966327Y1099181D02*
Y1104330D01*
X966330Y1104333D01*
G01D02*
X969567D01*
X969893Y1104659D01*
X975176D01*
G01Y1100659D02*
X972776D01*
G01X968886Y1096622D02*
X970300D01*
X970800Y1097122D01*
Y1100159D01*
X971300Y1100659D01*
X972776D01*
G01X967936Y1207823D02*
X965369D01*
G01X972512Y1381496D02*
X980139D01*
G01X985448Y1398271D02*
Y1375241D01*
X981957Y1371750D01*
X979350D01*
X977478Y1373622D01*
X972512D01*
G01Y1377559D02*
X980203D01*
G01X972512Y1385434D02*
X979330D01*
X979996Y1386100D01*
G01X972512Y1397245D02*
X980047D01*
G01X972512Y1389370D02*
X980092D01*
G01X972512Y1393308D02*
X980139D01*
G01X980166Y1373622D02*
X982858Y1376314D01*
Y1397533D01*
X979209Y1401182D01*
X972512D01*
G01X994833Y98198D02*
X990833D01*
G01X979002Y92874D02*
Y95018D01*
X980396Y96412D01*
X989172D01*
X990833Y98073D01*
Y98198D01*
G01X991523Y151540D02*
Y147540D01*
G01X994214Y148277D02*
X993942D01*
X993205Y147540D01*
X991523D01*
G01X989611Y265701D02*
X990939Y264373D01*
Y262685D01*
G01X991246Y281716D02*
X993211Y279751D01*
Y277477D01*
G01Y269603D02*
Y267575D01*
X992515Y266879D01*
X990789D01*
X989611Y265701D01*
G01X989992Y284908D02*
X993992D01*
G01D02*
Y283104D01*
X992604Y281716D01*
X991246D01*
G01X987517Y314092D02*
Y308260D01*
X986943Y307686D01*
X983563D01*
X983063Y308186D01*
Y311927D01*
G01X988192Y327561D02*
X983611D01*
X982700Y328472D01*
G01X988192Y327561D02*
X990240D01*
X993372Y324429D01*
X995779D01*
X996265Y324915D01*
X1005231D01*
X1005341Y325025D01*
X1007094D01*
G01X994830Y326789D02*
X993012D01*
X988404Y331397D01*
X986775D01*
X982700Y335472D01*
G01X990405Y318175D02*
X993552D01*
G01X1005605Y322072D02*
X1003481Y321193D01*
X1000447D01*
X997429Y318175D01*
X993552D01*
G01X990405Y314092D02*
X990966Y314653D01*
X994602D01*
G01X990405Y314092D02*
X987517D01*
G01X982700Y331972D02*
Y328472D01*
G01Y338972D02*
Y335472D01*
G01X1007094Y328962D02*
X1001974D01*
X1000039Y330897D01*
Y335173D01*
X991350Y343862D01*
X989630D01*
G01X981181Y343112D02*
X982270D01*
X983717Y341665D01*
G01D02*
X986194Y339188D01*
Y336905D01*
X993199Y329900D01*
X997663D01*
X1000569Y326994D01*
X1007094D01*
G01X983956Y346652D02*
X988271Y342337D01*
Y337429D01*
X993904Y331796D01*
X997581D01*
X1001399Y327978D01*
X1005100D01*
G01X1007094Y334868D02*
X1005123D01*
X1003978Y336013D01*
Y341503D01*
X1002496Y342985D01*
Y344204D01*
X996800Y349900D01*
X994940D01*
X993026Y351814D01*
Y353813D01*
G01X981719Y352217D02*
X990906D01*
X994464Y348659D01*
X996441D01*
X1000738Y344362D01*
Y342745D01*
X1002850Y340633D01*
Y335466D01*
X1005417Y332899D01*
X1007094D01*
G01X992045Y361009D02*
Y359441D01*
X993963Y357523D01*
X1001443D01*
G01X988045Y355812D02*
Y361009D01*
G01Y355812D02*
X995089D01*
X998901Y352000D01*
X1002300D01*
X1005093Y349207D01*
Y345155D01*
X1005538Y344710D01*
X1007094D01*
G01Y330931D02*
X1006231D01*
X1005898Y330598D01*
X1001806D01*
X1001118Y331286D01*
Y337009D01*
X988631Y349496D01*
G01X981181Y346612D02*
X983916D01*
X983956Y346652D01*
G01X986373Y370467D02*
X992719D01*
X997640Y365546D01*
X998736D01*
X1006853Y357429D01*
X1012606D01*
X1015460Y354575D01*
Y347171D01*
G01X980045Y361009D02*
X984045D01*
G01D02*
X988045D01*
G01X979295Y451557D02*
Y448560D01*
X979910Y447945D01*
Y445603D01*
G01D02*
X979932Y445581D01*
Y443069D01*
G01X979295Y459431D02*
Y461146D01*
X981843Y463694D01*
Y464818D01*
G01D02*
Y466038D01*
X980397Y467484D01*
G01X978032Y590801D02*
X982160D01*
G01X993857Y599650D02*
Y597282D01*
X993357Y596782D01*
X991907D01*
G01X989857Y599650D02*
X993857D01*
G01X991907Y596782D02*
X990187D01*
X988656Y595251D01*
Y593360D01*
G01X997857Y596729D02*
X994488Y593360D01*
X990625D01*
G01X984719D02*
Y594108D01*
X983977Y594850D01*
X980137D01*
X977857Y597130D01*
G01D02*
Y599650D01*
G01X985857D02*
X986688Y598819D01*
Y596089D01*
G01D02*
Y593360D01*
G01X977857Y602800D02*
Y605443D01*
G01X981857Y602800D02*
X985857D01*
G01X981857D02*
Y605637D01*
G01X978865Y639386D02*
Y642184D01*
G01X983712Y716514D02*
X982800Y715602D01*
Y707900D01*
X985317Y705383D01*
X989695D01*
G01X987461Y745796D02*
X1026307D01*
X1086804Y751754D01*
X1114419Y757247D01*
X1150699D01*
X1154518Y758829D01*
X1158525Y762836D01*
X1160485Y767567D01*
G01X981876Y745179D02*
X984555Y742500D01*
X1023577D01*
X1090405Y749082D01*
X1118787Y754727D01*
X1154836D01*
X1164485Y764376D01*
Y767567D01*
G01X987394Y787490D02*
X986514Y788370D01*
X984896D01*
X981667Y785141D01*
Y770398D01*
X985978Y766087D01*
X989678D01*
X991990Y768399D01*
G01D02*
X995990D01*
G01X984357Y777555D02*
Y770606D01*
X986564Y768399D01*
X987990D01*
G01X990699Y778630D02*
Y783295D01*
G01X987990Y771549D02*
Y774005D01*
G01D02*
X989539Y775554D01*
X990619D01*
X993258Y778193D01*
Y783295D01*
G01X998376D02*
Y786568D01*
X995291Y789653D01*
X993451D01*
G01D02*
X990699Y786901D01*
Y783295D01*
G01X993258Y800206D02*
X992278Y799226D01*
Y790826D01*
X993451Y789653D01*
G01X1000935Y806295D02*
Y800389D01*
X999520Y798974D01*
X994490D01*
X993258Y800206D01*
G01Y806295D02*
Y800206D01*
G01X981628Y825159D02*
X982300Y824487D01*
Y821200D01*
G01D02*
X984427Y823327D01*
X1007266D01*
X1015602Y831663D01*
X1021913D01*
X1028060Y837810D01*
X1032634D01*
X1046320Y851496D01*
Y863500D01*
X1058155Y875335D01*
Y887635D01*
G01X978978Y817618D02*
X982501D01*
X986705Y821822D01*
X1007110D01*
X1010699Y818233D01*
Y816975D01*
G01X984778Y829159D02*
X987702D01*
G01X984778D02*
Y825159D01*
G01X987702Y829159D02*
X989703Y831160D01*
Y834191D01*
X993836Y838324D01*
X995234D01*
G01X984778Y833159D02*
Y837159D01*
G01X987703D02*
X984778D01*
G01X995234Y840292D02*
X990836D01*
X987703Y837159D01*
G01X990457Y852043D02*
X999388D01*
X1002950Y855605D01*
X1028150D01*
X1029913Y853842D01*
G01X1005230Y1028377D02*
X1001407D01*
X998100Y1025070D01*
Y1021995D01*
X996892Y1019077D01*
Y1013716D01*
X995772Y1012596D01*
Y976304D01*
X988114Y968646D01*
Y926951D01*
X994529Y920536D01*
Y893524D01*
X991840Y890835D01*
Y881087D01*
X996159Y876768D01*
Y865720D01*
X993221Y862782D01*
X983812D01*
X979612Y858582D01*
Y855712D01*
X981441Y853883D01*
X983269D01*
G01X1037934Y847222D02*
Y851831D01*
X1032352Y857413D01*
X1001968D01*
X1000692Y856137D01*
X982896D01*
X982733Y856300D01*
X981700D01*
G01X983897Y1100302D02*
X992269Y1091930D01*
Y1030559D01*
X990100Y1028390D01*
Y1023596D01*
X988884Y1020659D01*
X988240Y1020015D01*
G01X983860Y1104622D02*
X986007Y1102475D01*
X988890D01*
X993989Y1097376D01*
Y1029845D01*
X991820Y1027676D01*
Y1023251D01*
X989876Y1018559D01*
X988240Y1016923D01*
G01Y1023968D02*
X988380Y1024108D01*
Y1029104D01*
X990549Y1031273D01*
Y1088362D01*
X986247Y1092664D01*
X980726D01*
G01X980852Y1098643D02*
X979710Y1099785D01*
X979200D01*
X978326Y1100659D01*
G01X983897Y1100302D02*
X982238Y1098643D01*
X980852D01*
G01X980726Y1104659D02*
X978326D01*
G01X983860Y1104622D02*
X983823Y1104659D01*
X980726D01*
G01X978326Y1092659D02*
X978331Y1092664D01*
X980726D01*
G01D02*
Y1094259D01*
X978326Y1096659D01*
G01X986645Y1108465D02*
X987010Y1108100D01*
Y1104622D01*
G01X987047Y1100302D02*
X989513Y1097836D01*
Y1097683D01*
G01X990501Y1320756D02*
X1013160D01*
X1017329Y1316587D01*
G01X1003379Y72615D02*
X1003407Y72587D01*
X1005779D01*
G01X1003379Y76587D02*
X1005779D01*
G01X1005734Y80581D02*
Y79618D01*
X1008765Y76587D01*
X1008929D01*
G01D02*
X1016599D01*
X1020219Y72967D01*
Y64722D01*
G01X1005734Y68581D02*
Y69564D01*
X1008757Y72587D01*
X1008929D01*
G01X1017659Y64722D02*
Y72741D01*
X1015633Y74767D01*
X1011109D01*
X1008929Y72587D01*
G01X1004818Y100625D02*
X1006184Y99259D01*
X1009740D01*
G01X1000337Y97475D02*
X997837D01*
G01X1009191Y112083D02*
Y112402D01*
X1011277Y114488D01*
G01X1000337Y100625D02*
X1004818D01*
G01X1000337Y105087D02*
Y100625D01*
G01X1005397Y141247D02*
X1002472D01*
G01X1022816Y142648D02*
X1021448D01*
X1019200Y140400D01*
X1009044D01*
X1008197Y141247D01*
X1005397D01*
G01X1014520Y158245D02*
Y148325D01*
X1014020Y147825D01*
X1009553D01*
X1008984Y147256D01*
Y145768D01*
G01X1009884Y143518D02*
X1011784D01*
X1012134Y143868D01*
Y145768D01*
G01X1022816Y139695D02*
X1024268D01*
X1025000Y140427D01*
Y144050D01*
X1024250Y144800D01*
X1021201D01*
X1018566Y142165D01*
X1010111D01*
X1009884Y142392D01*
Y143518D01*
G01X999322Y141247D02*
X995493D01*
G01X997091Y146461D02*
X996834Y146204D01*
Y143740D01*
G01D02*
X995493Y142399D01*
Y141247D01*
G01X997091Y149414D02*
X995351D01*
X994214Y148277D01*
G01X1004177Y149414D02*
X1008630D01*
X1008984Y149768D01*
G01X1004177Y152367D02*
X1008978D01*
X1008984Y152373D01*
G01D02*
Y149768D01*
G01X1009630Y179897D02*
Y176034D01*
X1012999Y172665D01*
G01X1012936Y179904D02*
Y180204D01*
X1011274Y181866D01*
X1009630D01*
G01X1008596Y196620D02*
X1007349D01*
X1003029Y192300D01*
G01X1009630Y185803D02*
Y189278D01*
X1010537Y190185D01*
X1012346D01*
G01X1007071Y188362D02*
Y192490D01*
G01D02*
X1009003Y194422D01*
X1012098D01*
X1012536Y194860D01*
X1014115D01*
X1015920Y196665D01*
G01X1009630Y183834D02*
X1012826D01*
G01X1009241Y211197D02*
X1010694D01*
X1013139Y208752D01*
Y207037D01*
G01X1009241Y209229D02*
X1009963D01*
X1010551Y208641D01*
Y203429D01*
X1013116Y200864D01*
G01X1009241Y213166D02*
X1010927D01*
X1011638Y212455D01*
X1013205D01*
G01X1009241Y217103D02*
X1011254D01*
X1016015Y221864D01*
G01X994939Y259535D02*
Y256303D01*
G01X999714Y266114D02*
Y264678D01*
X998939Y263903D01*
Y262685D01*
G01X994698Y265896D02*
Y264086D01*
X994939Y263845D01*
Y262685D01*
G01X997147Y269603D02*
Y268681D01*
X999714Y266114D01*
G01X997187Y281982D02*
X995179Y279974D01*
Y277477D01*
G01Y269603D02*
Y267599D01*
X994698Y267118D01*
Y265896D01*
G01X997992Y284908D02*
Y282787D01*
X997187Y281982D01*
G01X1000698Y305826D02*
X1004635D01*
G01X1011523Y316659D02*
Y315149D01*
X1008787Y312413D01*
X1005374D01*
X1002580Y309619D01*
G01D02*
X1004635Y307564D01*
Y305826D01*
G01X1008635D02*
X1012635D01*
G01X1004899Y326009D02*
X1004875Y325985D01*
X998620D01*
X997816Y326789D01*
X994830D01*
G01X997752Y314653D02*
X1001105Y318006D01*
G01D02*
X1002687Y319588D01*
X1006309Y321088D01*
X1007094D01*
G01X1005547Y335852D02*
X1005041Y336358D01*
Y342065D01*
X1003894Y343212D01*
Y348305D01*
X1001385Y350814D01*
X997986D01*
X996668Y352132D01*
X996024D01*
G01X1001443Y357523D02*
X1009254Y349712D01*
X1011883D01*
X1013492Y348103D01*
Y347171D01*
G01X996045Y361009D02*
X1001387D01*
X1008120Y354276D01*
X1011862D01*
G01X1001857Y599650D02*
X997857D01*
G01Y596729D02*
Y599650D01*
G01X1007990Y768399D02*
Y765899D01*
G01D02*
X1010245D01*
X1016320Y771974D01*
G01Y754546D02*
X1008150D01*
X1003030Y759666D01*
X1000551D01*
X995990Y764227D01*
Y768399D01*
G01X999990D02*
Y764566D01*
G01X1003494Y783295D02*
Y780745D01*
X1005467Y778772D01*
X1010651D01*
X1012695Y776728D01*
G01D02*
X1007990Y772023D01*
Y771549D01*
G01X1003990D02*
X1000840Y768399D01*
X999990D01*
G01X995990Y771549D02*
X995817Y771722D01*
Y777599D01*
X997051Y778833D01*
G01D02*
X995817Y780067D01*
Y783295D01*
G01X999990Y771549D02*
Y774671D01*
G01D02*
Y776974D01*
X1000935Y777919D01*
Y783295D01*
G01X998376Y810970D02*
Y806295D01*
G01X1010699Y816975D02*
Y816751D01*
X1008226Y814278D01*
X1007152D01*
X1006699Y813825D01*
G01X1006054Y810969D02*
X1006053Y810968D01*
Y806295D01*
G01X994051Y813768D02*
Y810871D01*
G01D02*
X995317D01*
X995817Y810371D01*
Y806295D01*
G01X1010699Y803454D02*
X1009118Y801873D01*
X1004456D01*
X1003494Y802835D01*
Y806295D01*
G01X1002699Y813825D02*
X996981D01*
X996385Y814421D01*
Y816141D01*
G01D02*
X995608Y816918D01*
X994051D01*
G01X1007440Y838324D02*
X1008808D01*
X1009473Y837659D01*
X1012703D01*
G01X1005413Y905295D02*
X1010629D01*
G01X1035185Y862793D02*
Y862921D01*
X1040359Y868095D01*
Y888589D01*
X1004953Y923995D01*
G01X1037685Y862789D02*
X1043239Y868343D01*
Y889492D01*
X1008935Y923796D01*
Y924007D01*
G01X1010009Y991956D02*
Y989319D01*
X1009564Y988874D01*
G01D02*
X1010009Y988429D01*
Y986106D01*
G01X998872Y1004541D02*
X997392D01*
X996892Y1005041D01*
Y1011713D01*
X997392Y1012213D01*
X998852D01*
G01X1004831Y1003349D02*
X1002726D01*
X1001805Y1004270D01*
Y1007522D01*
G01D02*
Y1008760D01*
X1001305Y1009260D01*
X998852D01*
G01X1008571Y1003349D02*
Y1006648D01*
G01D02*
Y1007844D01*
X1011549Y1010822D01*
X1011782D01*
G01X1002180Y1013678D02*
X1000715Y1012213D01*
X998852D01*
G01X1000248Y1021336D02*
X1002180Y1019404D01*
Y1013678D01*
G01X1000248Y1024486D02*
X1001897D01*
X1002652Y1023731D01*
G01X1005609Y1021177D02*
X1005230Y1021556D01*
Y1025227D01*
G01X1005938Y1015166D02*
X1007695D01*
X1008171Y1014690D01*
Y1012690D01*
X1007694Y1012213D01*
X1005938D01*
G01X1005609Y1021177D02*
X1005938Y1020848D01*
Y1018307D01*
G01D02*
Y1015166D01*
G01X1005814Y1351584D02*
X1005602Y1351796D01*
Y1369315D01*
X1007026Y1370739D01*
X1012163D01*
X1014058Y1368844D01*
G01X1037883Y1351940D02*
X1033874D01*
X1032593Y1350659D01*
Y1343345D01*
X1031137Y1341889D01*
X1015316D01*
X1013246Y1343959D01*
Y1345747D01*
X1013872Y1346373D01*
Y1348946D01*
X1011234Y1351584D01*
X1005814D01*
G01X1010917Y1368835D02*
X1007850D01*
G01X1020219Y64722D02*
X1020519Y64422D01*
Y60438D01*
G01X1017659Y64722D02*
Y60513D01*
G01X1026200Y86012D02*
X1023073Y82885D01*
Y81848D01*
G01X1017787Y85731D02*
X1017659Y85603D01*
Y81848D01*
G01X1021341Y86046D02*
X1020219Y84924D01*
Y81848D01*
G01X1022293Y91879D02*
Y94279D01*
G01X1018344Y91951D02*
Y94351D01*
G01X1026200Y88824D02*
Y86012D01*
G01X1018344Y88801D02*
X1017787Y88244D01*
Y85731D01*
G01X1022293Y88729D02*
Y86998D01*
X1021341Y86046D01*
G01X1013480Y107921D02*
Y103621D01*
G01X1025755Y107899D02*
Y109059D01*
X1027480Y110784D01*
G01X1025522Y121558D02*
Y123126D01*
X1024365Y124283D01*
X1021971D01*
G01D02*
X1022003Y124315D01*
Y127525D01*
X1021780Y127748D01*
G01X1017629Y157370D02*
Y148980D01*
X1018858Y147754D01*
X1020969D01*
G01X1027780Y130898D02*
X1027900Y131018D01*
Y145057D01*
X1025207Y147754D01*
X1020969D01*
G01Y150904D02*
Y154865D01*
G01D02*
X1025906D01*
G01D02*
X1028750Y157709D01*
X1035121D01*
X1035621Y158209D01*
Y161958D01*
G01X1014520Y158245D02*
X1020461Y164186D01*
X1024068D01*
X1025426Y165544D01*
X1048834D01*
X1056183Y158195D01*
X1113399D01*
X1113400Y158194D01*
X1117032D01*
G01X1015920Y176665D02*
Y180665D01*
G01X1012936Y178560D02*
Y179904D01*
G01D02*
X1013697Y180665D01*
X1015920D01*
G01Y168665D02*
Y172665D01*
G01X1012999D02*
X1015920D01*
G01X1012346Y190185D02*
Y191730D01*
X1013281Y192665D01*
X1015920D01*
G01X1012826Y183834D02*
X1015089D01*
X1015920Y184665D01*
G01X1011746Y196620D02*
Y198127D01*
X1010291Y199582D01*
G01X1019070Y196665D02*
X1021713D01*
G01X1021826Y186778D02*
Y185398D01*
X1021093Y184665D01*
X1019070D01*
G01Y188665D02*
X1021095D01*
X1021826Y187934D01*
Y186778D01*
G01X1019070Y192665D02*
X1021713D01*
G01X1016015Y204864D02*
Y208864D01*
G01X1013139Y207037D02*
X1014966Y208864D01*
X1016015D01*
G01X1013116Y200864D02*
X1016015D01*
G01Y212864D02*
X1015606Y212455D01*
X1013205D01*
G01X1019165Y208864D02*
X1021745D01*
G01X1016012Y225719D02*
Y221867D01*
X1016015Y221864D01*
G01X1018014Y228631D02*
X1016012Y226629D01*
Y225719D01*
G01X1030250Y242078D02*
X1022978D01*
X1020490Y244566D01*
Y255458D01*
X1023912Y258880D01*
X1074522D01*
G01X1097976Y340477D02*
Y326976D01*
X1063518Y292518D01*
X1024860D01*
X1022604Y290262D01*
G01X1025418Y310476D02*
Y307666D01*
X1025749Y307335D01*
Y305826D01*
G01X1025418Y310476D02*
Y312723D01*
X1026287Y313592D01*
Y315170D01*
G01X1018820Y311772D02*
Y307641D01*
X1020635Y305826D01*
G01X1016635D02*
Y308388D01*
X1013664Y311359D01*
G01X1016444Y314139D02*
X1013664Y311359D01*
G01X1012635Y305826D02*
Y306926D01*
X1010499Y309062D01*
G01D02*
Y311668D01*
X1013492Y314661D01*
Y316659D01*
G01X1018413Y313879D02*
X1018820Y313472D01*
Y311772D01*
G01X1025885Y352848D02*
X1042901D01*
X1046204Y356151D01*
X1055129D01*
G01X1025885Y352848D02*
X1024318Y351281D01*
Y348999D01*
G01X1014476Y349254D02*
Y351662D01*
X1011862Y354276D01*
G01X1016444Y349172D02*
Y351356D01*
X1019119Y354031D01*
X1021799D01*
X1024075Y356307D01*
X1042194D01*
X1047063Y361176D01*
G01X1030635Y754546D02*
X1022297D01*
X1019316Y751565D01*
X1018015D01*
G01D02*
Y753215D01*
X1019346Y754546D01*
X1019470D01*
G01X1016320Y775974D02*
Y771974D01*
G01X1030635Y774546D02*
X1024318D01*
X1022890Y775974D01*
Y777784D01*
X1021558Y779116D01*
X1017679D01*
X1017664Y779101D01*
G01D02*
Y777537D01*
X1019227Y775974D01*
X1019470D01*
G01X1030635Y804546D02*
X1025024D01*
X1023218Y802740D01*
Y798925D01*
X1022585Y798292D01*
X1018269D01*
X1018071Y798490D01*
G01D02*
Y801889D01*
X1018922Y802740D01*
G01X1016320Y818974D02*
Y815083D01*
X1016283Y815046D01*
G01D02*
X1015347D01*
X1013821Y813520D01*
G01X1014781Y810319D02*
X1012976Y808514D01*
Y806602D01*
X1014286Y805292D01*
X1018324D01*
X1018922Y805890D01*
G01X1030635Y814546D02*
X1023020D01*
X1020571Y812097D01*
X1017955D01*
G01D02*
Y813755D01*
X1019246Y815046D01*
X1019433D01*
G01X1010699Y813825D02*
Y803454D01*
G01X1015128Y837659D02*
Y833659D01*
G01X1012703Y837659D02*
X1015128D01*
G01X1017800Y867065D02*
X1015494Y869371D01*
X1013264Y870295D01*
X1011259D01*
G01Y880295D02*
X1015708D01*
X1019413Y884000D01*
X1024913D01*
G01X1021408Y895008D02*
X1021233D01*
X1015946Y900295D01*
X1011259D01*
G01Y880295D02*
X1010629D01*
G01Y905295D02*
X1011259D01*
G01X1010629Y900295D02*
X1011259D01*
G01X1017994Y958822D02*
X1021802D01*
X1030447Y967467D01*
X1176882D01*
X1184730Y975315D01*
Y1011941D01*
X1192220Y1019431D01*
X1201800D01*
G01X1014009Y991956D02*
Y988813D01*
G01D02*
Y986106D01*
G01X1018009Y991956D02*
Y988813D01*
G01D02*
Y986106D01*
G01X1504938Y859711D02*
X1502316Y857089D01*
X1445496D01*
X1439609Y862976D01*
X1424687D01*
X1419910Y867753D01*
Y896198D01*
X1417897Y898211D01*
Y905696D01*
X1419371Y907170D01*
Y917843D01*
X1309215Y1027999D01*
X1256137D01*
X1239020Y1045116D01*
X1153287D01*
X1085552Y977381D01*
X1063112D01*
X1060037Y980456D01*
X1021924D01*
G01X1026009Y991956D02*
Y988813D01*
G01D02*
Y986106D01*
G01X1022009Y991956D02*
Y988813D01*
G01D02*
Y986106D01*
G01X1023109Y1212938D02*
X1024543Y1214372D01*
X1026221D01*
G01X1025937Y1210110D02*
X1023109Y1212938D01*
G01X1019927Y1216120D02*
X1021976Y1218169D01*
G01X1031601Y1228380D02*
X1030786Y1229195D01*
X1029003D01*
X1026409Y1226601D01*
X1023774D01*
G01X1049720Y1234921D02*
X1045465D01*
X1034894Y1230543D01*
X1023716D01*
X1019774Y1226601D01*
G01X1017329Y1313437D02*
X1021249D01*
X1021259Y1313447D01*
G01D02*
X1025378D01*
X1025399Y1313426D01*
G01X1032295Y1315612D02*
X1027585D01*
X1025399Y1313426D01*
G01X1020049Y1330761D02*
X1024062D01*
X1024115Y1330814D01*
G01X1032295Y1323092D02*
X1032220Y1323017D01*
X1028962D01*
X1027605Y1324374D01*
X1022250D01*
X1021406Y1323530D01*
G01X1020049Y1330761D02*
Y1324887D01*
X1021406Y1323530D01*
G01X1027569Y1348200D02*
X1019797D01*
X1019671Y1348074D01*
G01X1019109Y1353132D02*
X1019671Y1352570D01*
Y1348074D01*
G01X1010917Y1368835D02*
X1013204Y1366548D01*
X1019257D01*
G01X1035816Y1365009D02*
X1027767D01*
X1026228Y1366548D01*
X1019257D01*
G01X1014036Y1363533D02*
X1014171Y1363398D01*
X1019257D01*
G01D02*
X1024316Y1358339D01*
G01D02*
Y1353747D01*
X1026123Y1351940D01*
X1027569D01*
G01X1014079Y1357938D02*
Y1353718D01*
X1014083Y1353714D01*
G01D02*
X1014304Y1353493D01*
X1018748D01*
X1019109Y1353132D01*
G01X1019391Y1377061D02*
X1027479D01*
X1031012Y1380594D01*
X1038734D01*
X1041503Y1377825D01*
Y1370738D01*
X1040861Y1370096D01*
X1040501D01*
X1038996Y1368591D01*
Y1368492D01*
G01X1014067Y1368835D02*
X1014058Y1368844D01*
G01D02*
Y1372734D01*
G01X1019330Y1380797D02*
X1025365D01*
X1025466Y1380696D01*
G01X1014053Y1376752D02*
Y1380788D01*
X1014062Y1380797D01*
G01D02*
X1019330D01*
G01X1037883Y1344460D02*
X1039217D01*
X1040548Y1343129D01*
X1043369D01*
X1045127Y1344887D01*
Y1346273D01*
X1041764Y1349636D01*
Y1354622D01*
X1042856Y1355714D01*
Y1378382D01*
X1038383Y1382855D01*
X1027625D01*
X1025466Y1380696D01*
G01X1027480Y110784D02*
X1027490Y110794D01*
Y113684D01*
G01X1029755Y107899D02*
X1033755D01*
G01X1029458Y113684D02*
Y111534D01*
X1030208Y110784D01*
X1032480D01*
G01D02*
X1033755Y109509D01*
Y107899D01*
G01X1035834Y130903D02*
X1035803Y130934D01*
Y134838D01*
G01X1035834Y127753D02*
Y126313D01*
X1037040Y125107D01*
G01X1029458Y121558D02*
Y124163D01*
X1029958Y124663D01*
X1032059D01*
G01D02*
Y126008D01*
X1031780Y126287D01*
Y127748D01*
G01X1027780D02*
X1027037Y127005D01*
Y124879D01*
G01D02*
X1027490Y123785D01*
Y121558D01*
G01X1042424Y143762D02*
X1045654D01*
G01X1042424Y146912D02*
Y148000D01*
X1041707Y148717D01*
X1039554D01*
G01D02*
X1033429D01*
X1031881Y150265D01*
Y153296D01*
G01X1029902Y136742D02*
Y138338D01*
X1030402Y138838D01*
X1033403D01*
G01X1035803Y134838D02*
Y138838D01*
G01X1033403D02*
X1035803D01*
G01X1039134Y228646D02*
X1035099Y232681D01*
Y232859D01*
G01X1040712Y225055D02*
Y227068D01*
X1039134Y228646D01*
G01X1037229Y242078D02*
X1033400D01*
G01X1034998Y247292D02*
X1034741Y247035D01*
Y244571D01*
G01D02*
X1033400Y243230D01*
Y242078D01*
G01X1046891Y250599D02*
X1047087Y250795D01*
Y253923D01*
X1044616Y256394D01*
X1042084D01*
G01D02*
Y253198D01*
G01X1046891Y250599D02*
X1046537Y250245D01*
X1042084D01*
G01X1029430Y252371D02*
Y248371D01*
G01X1034998Y250245D02*
X1033258D01*
X1032121Y249108D01*
G01D02*
X1031849D01*
X1031112Y248371D01*
X1029430D01*
G01X1027216Y289440D02*
X1028376Y290600D01*
X1064080D01*
X1103432Y329952D01*
Y340544D01*
G01X1037606Y319120D02*
X1038290D01*
X1038790Y318620D01*
Y316535D01*
X1041496Y313829D01*
Y311094D01*
G01X1045650Y305826D02*
X1041496D01*
G01Y311094D02*
Y305826D01*
G01X1029639D02*
Y307490D01*
X1030418Y308269D01*
Y310476D01*
G01D02*
X1032169Y312227D01*
Y314658D01*
X1031208Y315619D01*
Y316659D01*
G01X1037606Y321088D02*
X1038348D01*
X1044897Y314539D01*
X1050632D01*
G01X1045939Y332533D02*
X1044707Y331301D01*
X1040755D01*
G01X1062349Y458711D02*
Y458807D01*
X1060967Y460189D01*
Y461010D01*
X1057177Y464800D01*
X1044118D01*
X1041408Y462090D01*
Y455656D01*
G01Y452506D02*
X1043117D01*
X1044873Y450750D01*
X1047268D01*
G01X1041408Y452506D02*
Y448656D01*
G01X1033200Y731700D02*
X1035030Y729870D01*
X1040578D01*
X1068918Y701530D01*
Y652539D01*
X1061526Y645147D01*
Y636306D01*
X1063642Y634190D01*
G01X1029913Y853842D02*
Y847222D01*
G01X1033063D02*
X1037934D01*
G01X1033370Y953994D02*
X1034736Y955360D01*
Y962735D01*
X1037501Y965500D01*
X1194613D01*
X1198029Y968916D01*
X1279822D01*
G01X1038009Y991956D02*
Y988813D01*
G01D02*
Y986106D01*
G01X1030009Y991956D02*
Y988813D01*
G01D02*
Y986106D01*
G01X1042009D02*
Y988813D01*
G01D02*
Y991956D01*
G01X1034009D02*
Y988813D01*
G01D02*
Y986106D01*
G01X1031594Y1204453D02*
X1028766Y1207281D01*
G01X1037257Y1222724D02*
X1040085Y1219896D01*
G01X1032831Y1207950D02*
X1031656Y1209125D01*
X1030610D01*
X1028766Y1207281D01*
G01X1031601Y1228380D02*
X1038579D01*
X1040606Y1230407D01*
G01X1043588Y1227300D02*
X1040275Y1223987D01*
X1038520D01*
X1037257Y1222724D01*
G01D02*
X1037255D01*
G01X1049770Y1229402D02*
X1042701D01*
X1040123Y1226824D01*
X1035700D01*
X1034428Y1225552D01*
G01X1043238Y1309487D02*
X1040456Y1312269D01*
Y1314209D01*
X1041859Y1315612D01*
X1042925D01*
G01X1040088Y1309487D02*
X1039139Y1308538D01*
X1034697D01*
X1034196Y1309039D01*
Y1309624D01*
G01D02*
X1034241Y1309669D01*
Y1314601D01*
X1033230Y1315612D01*
X1032295D01*
G01Y1323092D02*
X1035312D01*
X1036806Y1324586D01*
Y1335566D01*
X1034544Y1337828D01*
X1032295D01*
X1032272Y1337805D01*
G01X1039015Y1357372D02*
Y1355595D01*
X1037674Y1354254D01*
X1032902D01*
X1031229Y1352581D01*
Y1345391D01*
X1030298Y1344460D01*
X1027569D01*
G01X1057608Y1315605D02*
Y1336995D01*
X1053638Y1340965D01*
X1036475D01*
X1035230Y1342210D01*
Y1342918D01*
X1036772Y1344460D01*
X1037883D01*
G01X1038958Y1361287D02*
X1039015Y1361230D01*
Y1357372D01*
G01X1038966Y1365009D02*
Y1361295D01*
X1038958Y1361287D01*
G01X1038996Y1368492D02*
Y1365039D01*
X1038966Y1365009D01*
G01X1035816D02*
Y1361295D01*
X1035808Y1361287D01*
G01X1033340Y1376956D02*
X1038312D01*
X1038996Y1376272D01*
G01D02*
Y1371642D01*
G01X1051583Y103411D02*
Y102126D01*
X1053748Y99961D01*
X1058523D01*
G01Y97599D02*
X1052045D01*
X1051977Y97667D01*
G01D02*
X1048708D01*
G01X1058523Y90512D02*
X1062635D01*
X1062773Y90650D01*
G01X1058523Y88150D02*
X1065620D01*
X1068085Y90615D01*
G01X1062523Y95236D02*
X1058523D01*
G01Y92874D02*
X1049610D01*
X1047373Y95111D01*
G01X1051583Y103411D02*
X1048506D01*
G01X1044524Y106495D02*
X1048440D01*
X1048506Y106561D01*
G01D02*
X1051742D01*
G01X1044524Y102495D02*
Y106495D01*
G01X1044649Y225055D02*
Y229782D01*
X1043875Y230556D01*
G01X1048736Y232984D02*
Y231180D01*
X1048130Y230574D01*
Y227824D01*
G01D02*
Y227724D01*
X1046618Y226212D01*
Y225055D01*
G01X1050437Y241681D02*
Y244297D01*
G01X1044501Y232959D02*
X1043875Y232333D01*
Y230556D01*
G01X1047287Y241681D02*
X1046646Y241040D01*
Y233484D01*
X1047146Y232984D01*
X1048736D01*
G01X1055650Y310574D02*
Y314539D01*
G01X1050632D02*
X1055650D01*
G01X1055537Y343509D02*
Y339509D01*
G01D02*
Y339259D01*
X1050392Y334114D01*
X1047520D01*
X1045939Y332533D01*
G01X1055129Y360151D02*
Y356151D01*
G01Y368276D02*
Y364276D01*
G01D02*
X1050163D01*
X1047063Y361176D01*
G01X1059549Y458711D02*
X1054960Y463300D01*
X1048304D01*
X1047268Y462264D01*
Y450750D01*
G01X1060573Y455375D02*
X1058185D01*
X1054148Y459412D01*
X1051008D01*
G01X1054009Y991956D02*
Y988813D01*
G01D02*
Y986106D01*
G01X1046009Y991956D02*
Y988813D01*
G01D02*
Y986106D01*
G01X1050009Y991956D02*
Y988813D01*
G01D02*
Y986106D01*
G01X1058009Y991956D02*
Y988813D01*
G01D02*
Y986106D01*
G01X1059251Y1090157D02*
X1057381Y1088287D01*
G01X1059251Y1108858D02*
X1057381Y1106988D01*
G01X1059251Y1101377D02*
X1057381Y1099507D01*
G01X1059251Y1116338D02*
X1057381Y1114468D01*
G01X1059251Y1123818D02*
X1057381Y1121948D01*
G01X1059251Y1131299D02*
X1057381Y1129429D01*
G01X1059251Y1138779D02*
X1057381Y1136909D01*
G01X1059251Y1149999D02*
X1057381Y1148129D01*
G01X1045742Y1214239D02*
X1048570Y1211411D01*
X1048571D01*
G01X1049930Y1221407D02*
Y1218427D01*
X1045742Y1214239D01*
G01X1050605Y1224472D02*
X1050318D01*
X1042913Y1217067D01*
G01X1398854Y987277D02*
X1397131Y989000D01*
X1358600D01*
X1327188Y1020412D01*
Y1041912D01*
X1322600Y1046500D01*
X1307500D01*
X1304216Y1049784D01*
Y1085584D01*
X1287898Y1101902D01*
Y1236298D01*
X1301423Y1249823D01*
Y1282322D01*
X1306400Y1287299D01*
Y1290418D01*
X1301618Y1295200D01*
X1054603D01*
X1052660Y1293257D01*
G01X1050002Y1293283D02*
Y1294103D01*
X1053006Y1297107D01*
X1302593D01*
X1308377Y1291323D01*
Y1286610D01*
X1303300Y1281533D01*
Y1248400D01*
X1289704Y1234804D01*
Y1102596D01*
X1306000Y1086300D01*
Y1050700D01*
X1308400Y1048300D01*
X1323400D01*
X1329100Y1042600D01*
Y1021700D01*
X1359900Y990900D01*
X1382233D01*
X1383162Y991829D01*
G01X1057562Y1311436D02*
Y1315559D01*
X1057608Y1315605D01*
G01X1042925Y1315612D02*
X1049174D01*
G01D02*
X1054451D01*
X1054458Y1315605D01*
G01X1049670Y1347462D02*
X1046237D01*
X1043377Y1350322D01*
Y1353792D01*
X1044492Y1354907D01*
Y1398592D01*
X1064000Y1418100D01*
X1096300D01*
X1108898Y1430698D01*
Y1555110D01*
X1106675Y1557333D01*
X1098376D01*
G01X1046075Y1350650D02*
X1046627Y1351202D01*
Y1397728D01*
X1065399Y1416500D01*
X1097300D01*
X1110818Y1430018D01*
Y1608446D01*
X1104555Y1614709D01*
X1101946D01*
G01X1049493Y1350694D02*
Y1398140D01*
X1066176Y1414823D01*
X1097923D01*
X1112736Y1429636D01*
Y1637777D01*
X1108747Y1641766D01*
X1099354D01*
X1097474Y1639886D01*
Y1637753D01*
G01X1060674Y1450896D02*
X1057897D01*
X1056934Y1449933D01*
Y1443022D01*
G01X1062053Y1437930D02*
X1059195D01*
X1056934Y1440191D01*
Y1443022D01*
G01X1053194Y1450896D02*
Y1456493D01*
G01D02*
X1058153D01*
X1058160Y1456486D01*
X1058260D01*
G01X1072456Y95236D02*
X1076633D01*
G01Y99961D02*
X1072406D01*
G01X1062234Y378600D02*
X1065198D01*
G01X1095442Y382067D02*
X1081852D01*
X1081319Y382600D01*
X1073102D01*
G01X1068348Y378600D02*
Y382600D01*
G01X1073102D02*
X1068348D01*
G01X1065198Y459600D02*
Y458292D01*
X1065952Y457538D01*
X1076755D01*
X1079552Y460335D01*
X1120866D01*
X1125397Y455804D01*
X1135548D01*
G01X1063113Y455921D02*
X1061119D01*
X1060573Y455375D01*
G01X1062349Y458711D02*
X1063238Y459600D01*
X1065198D01*
G01X1095442Y465177D02*
X1073193D01*
G01X1068348Y459600D02*
Y463600D01*
G01X1073193Y465177D02*
X1069925D01*
X1068348Y463600D01*
G01X1065286Y554555D02*
Y553351D01*
X1065963Y552674D01*
X1073217D01*
G01X1061436Y554555D02*
X1065286D01*
G01X1073217Y552674D02*
X1077098Y556555D01*
X1095442D01*
G01X1065318Y562567D02*
Y564074D01*
X1065818Y564574D01*
X1072952D01*
X1073155Y564371D01*
G01X1061436Y562555D02*
X1065306D01*
X1065318Y562567D01*
G01X1073155Y564371D02*
X1078433D01*
X1081524Y561280D01*
X1095442D01*
G01X1065286Y558555D02*
Y559757D01*
X1065954Y560425D01*
X1069919D01*
X1070973Y559371D01*
X1073155D01*
G01X1061436Y558555D02*
X1065286D01*
G01X1073155Y559371D02*
X1075836D01*
X1076290Y558917D01*
X1095442D01*
G01Y606929D02*
X1085111D01*
X1079439Y601257D01*
X1073215D01*
G01D02*
X1071546Y599588D01*
X1067716D01*
G01X1095442Y604567D02*
X1086358D01*
X1080770Y598978D01*
X1078685Y596894D01*
X1078112Y596321D01*
X1072371D01*
G01D02*
X1070173D01*
X1069440Y595588D01*
X1067716D01*
G01X1095442Y592756D02*
X1083206D01*
X1081838Y591388D01*
X1073193D01*
G01D02*
X1072993Y591588D01*
X1067716D01*
G01Y607588D02*
Y603632D01*
X1067748Y603600D01*
G01X1072393Y606190D02*
X1069803Y603600D01*
X1067748D01*
G01Y615600D02*
X1069300D01*
X1069769Y616069D01*
X1072415D01*
G01D02*
X1083480D01*
X1085533Y614016D01*
X1095442D01*
G01X1067748Y611600D02*
X1069420D01*
X1069894Y611126D01*
X1073222D01*
G01D02*
X1080468D01*
X1080996Y611654D01*
X1095442D01*
G01X1073219Y621005D02*
X1071814Y619600D01*
X1067748D01*
G01X1095442Y609291D02*
X1083194D01*
X1080093Y606190D01*
X1072393D01*
G01X1072728Y637979D02*
X1074876Y635831D01*
X1078781D01*
X1091147Y623465D01*
X1095442D01*
G01Y618740D02*
X1088791D01*
X1081581Y625950D01*
X1072392D01*
G01D02*
X1070042Y623600D01*
X1067748D01*
G01X1095442Y621102D02*
X1089858D01*
X1080074Y630886D01*
X1073196D01*
G01D02*
X1069910Y627600D01*
X1067748D01*
G01X1095442Y616378D02*
X1087319D01*
X1082702Y620995D01*
X1073229D01*
X1073219Y621005D01*
G01X1064598Y627600D02*
Y631421D01*
G01X1063642Y634190D02*
X1064598Y633234D01*
Y631421D01*
G01X1067748Y637969D02*
X1072718D01*
X1072728Y637979D01*
G01X1067748Y641974D02*
Y637969D01*
G01X1066931Y645389D02*
X1066131D01*
X1064598Y643856D01*
Y641974D01*
G01X1062009Y991956D02*
Y988813D01*
G01D02*
Y986106D01*
G01X1066009Y991956D02*
Y988997D01*
X1065785Y988773D01*
G01X1066009Y986106D02*
Y988549D01*
X1065785Y988773D01*
G01D02*
X1065823D01*
G01X1074009Y991956D02*
Y988813D01*
G01D02*
Y986106D01*
G01D02*
X1092553D01*
X1152782Y1046335D01*
X1239525D01*
X1256642Y1029218D01*
X1309720D01*
X1420590Y918348D01*
Y906665D01*
X1419116Y905191D01*
Y898716D01*
X1421129Y896703D01*
Y868258D01*
X1425192Y864195D01*
X1440114D01*
X1446100Y858209D01*
X1498935D01*
X1500353Y859627D01*
Y859855D01*
G01X1070009Y995106D02*
Y997860D01*
G01X1072342Y1073326D02*
X1074212Y1075196D01*
G01X1066732D02*
X1064862Y1073326D01*
G01X1072342Y1077066D02*
X1074212Y1078936D01*
G01X1070472Y1086417D02*
X1068602Y1084547D01*
G01X1070472Y1082677D02*
X1068602Y1080807D01*
G01X1062991Y1090157D02*
X1061121Y1088287D01*
G01X1070472Y1101377D02*
X1068602Y1099507D01*
G01X1066732Y1093897D02*
X1064862Y1092027D01*
G01X1072342Y1095767D02*
X1074212Y1097637D01*
G01X1062991Y1108858D02*
X1061121Y1106988D01*
G01X1070472Y1105117D02*
X1068602Y1103247D01*
G01X1066732Y1097637D02*
X1064862Y1095767D01*
G01X1072342Y1092027D02*
X1074212Y1093897D01*
G01X1062991Y1101377D02*
X1061121Y1099507D01*
G01X1062991Y1116338D02*
X1061121Y1114468D01*
G01X1070472Y1112598D02*
X1068602Y1110728D01*
G01X1070472Y1120078D02*
X1068602Y1118208D01*
G01X1066732Y1112598D02*
X1064862Y1110728D01*
G01X1066732Y1120078D02*
X1064862Y1118208D01*
G01X1062991Y1123818D02*
X1061121Y1121948D01*
G01X1066732Y1127558D02*
X1064862Y1125688D01*
G01X1070472Y1127558D02*
X1068602Y1125688D01*
G01X1062991Y1131299D02*
X1061121Y1129429D01*
G01X1066732Y1135039D02*
X1064862Y1133169D01*
G01X1062991Y1138779D02*
X1061121Y1136909D01*
G01X1062991Y1149999D02*
X1061121Y1148129D01*
G01X1066260Y1442391D02*
Y1439262D01*
X1064928Y1437930D01*
X1062053D01*
G01X1076633Y92874D02*
X1081364D01*
G01D02*
Y95018D01*
X1082758Y96412D01*
X1091534D01*
X1093195Y98073D01*
Y98198D01*
G01X1081692Y1075196D02*
X1079822Y1073326D01*
G01X1085432Y1086417D02*
X1083562Y1084547D01*
G01X1081692Y1078936D02*
X1079822Y1077066D01*
G01X1077952Y1086417D02*
X1076082Y1084547D01*
G01X1077952Y1082677D02*
X1076082Y1080807D01*
G01X1085432Y1082677D02*
X1083562Y1080807D01*
G01X1077952Y1105117D02*
X1076082Y1103247D01*
G01X1081692Y1097637D02*
X1079822Y1095767D01*
G01X1081692Y1093897D02*
X1079822Y1092027D01*
G01X1077952Y1101377D02*
X1076082Y1099507D01*
G01X1085432Y1105117D02*
X1083562Y1103247D01*
G01X1081692Y1112598D02*
X1079822Y1110728D01*
G01X1085432Y1116338D02*
X1083562Y1114468D01*
G01X1089172Y1116338D02*
X1087302Y1114468D01*
G01X1077952Y1112598D02*
X1076082Y1110728D01*
G01X1085432Y1149999D02*
X1083562Y1148129D01*
G01X1081692Y1146259D02*
X1079822Y1144389D01*
G01X1081692Y1149999D02*
X1079822Y1148129D01*
G01X1085432Y1153740D02*
X1083562Y1151870D01*
G01X1081692Y1153740D02*
X1079822Y1151870D01*
G01X1085432Y1157480D02*
X1083562Y1155610D01*
G01X1081692Y1157480D02*
X1079822Y1155610D01*
G01X1081692Y1161220D02*
X1079822Y1159350D01*
G01X1085432Y1161220D02*
X1083562Y1159350D01*
G01X1090469Y1582410D02*
Y1580046D01*
X1091093Y1579422D01*
X1092527D01*
G01X1090469Y1585560D02*
X1089116D01*
X1088646Y1585090D01*
Y1583251D01*
X1087805Y1582410D01*
X1086469D01*
G01X1090469Y1588435D02*
Y1585560D01*
G01X1090904Y1593206D02*
X1086904D01*
G01X1094904D02*
X1090904D01*
G01X1086904D02*
X1083900D01*
G01X1083735Y1606773D02*
X1083911Y1606949D01*
X1088021D01*
G01X1083735Y1611559D02*
Y1606773D01*
G01X1088021Y1606949D02*
X1088142Y1606828D01*
Y1604327D01*
X1088642Y1603827D01*
X1089959D01*
X1091168Y1605036D01*
Y1606949D01*
G01X1086904Y1596356D02*
Y1599004D01*
G01X1101946Y1614709D02*
X1083735D01*
G01X1090093Y1628297D02*
X1093727Y1624663D01*
Y1621515D01*
G01X1089474Y1635000D02*
Y1638213D01*
G01X1085474Y1635000D02*
X1089474D01*
G01Y1631850D02*
Y1630490D01*
X1090093Y1629871D01*
Y1628297D01*
G01X1105741Y76587D02*
X1108141D01*
G01X1105741Y72615D02*
X1105769Y72587D01*
X1108141D01*
G01X1097195Y98198D02*
X1093195D01*
G01X1102699Y97475D02*
X1100199D01*
G01X1107180Y100625D02*
X1108546Y99259D01*
X1112102D01*
G01X1102699Y100625D02*
X1107180D01*
G01X1102699Y105087D02*
Y100625D01*
G01X1104834Y141247D02*
X1107759D01*
G01X1101684D02*
X1097855D01*
G01X1099453Y146461D02*
X1099196Y146204D01*
Y143740D01*
G01D02*
X1097855Y142399D01*
Y141247D01*
G01X1093885Y151540D02*
Y147540D01*
G01X1099453Y149414D02*
X1097713D01*
X1096576Y148277D01*
G01D02*
X1096304D01*
X1095567Y147540D01*
X1093885D01*
G01X1106539Y152367D02*
X1111340D01*
X1111346Y152373D01*
G01X1106539Y149414D02*
X1110992D01*
X1111346Y149768D01*
G01X1097301Y259535D02*
Y256303D01*
G01X1091973Y265701D02*
X1093301Y264373D01*
Y262685D01*
G01X1102076Y266114D02*
Y264678D01*
X1101301Y263903D01*
Y262685D01*
G01X1097060Y265896D02*
Y264086D01*
X1097301Y263845D01*
Y262685D01*
G01X1095573Y269603D02*
Y267575D01*
X1094877Y266879D01*
X1093151D01*
X1091973Y265701D01*
G01X1099549Y281982D02*
X1097541Y279974D01*
Y277477D01*
G01X1102076Y266114D02*
X1099509Y268681D01*
Y269603D01*
G01X1097541D02*
Y267599D01*
X1097060Y267118D01*
Y265896D01*
G01X1093608Y281716D02*
X1095573Y279751D01*
Y277477D01*
G01X1100354Y284908D02*
Y282787D01*
X1099549Y281982D01*
G01X1092354Y284908D02*
X1096354D01*
G01X1093608Y281716D02*
X1094966D01*
X1096354Y283104D01*
Y284908D01*
G01X1095442Y554193D02*
X1098066D01*
X1106869Y562996D01*
Y576349D01*
X1108236Y577716D01*
G01X1095442Y549469D02*
X1097391D01*
X1099501Y547359D01*
Y545528D01*
G01X1108045Y668153D02*
Y665031D01*
X1106362Y663348D01*
Y658136D01*
X1103946Y655720D01*
X1101020D01*
G01X1104133Y1116338D02*
X1102263Y1114468D01*
G01X1100393Y1116338D02*
X1098523Y1114468D01*
G01X1107873Y1116338D02*
X1106003Y1114468D01*
G01X1107873Y1131299D02*
X1106003Y1129429D01*
G01X1107873Y1135039D02*
X1106003Y1133169D01*
G01X1107873Y1142519D02*
X1106003Y1140649D01*
G01X1104133Y1217322D02*
X1106003Y1215452D01*
G01X1100393Y1217322D02*
X1098523Y1215452D01*
G01X1104133Y1213582D02*
X1102263Y1215452D01*
G01X1099339Y1521648D02*
Y1529639D01*
X1101402Y1531702D01*
G01X1091661Y1540152D02*
Y1546164D01*
X1091525Y1546300D01*
G01X1098617Y1546183D02*
X1096083D01*
X1094220Y1544320D01*
Y1540152D01*
G01X1096780D02*
Y1535400D01*
G01X1099371Y1561153D02*
Y1559408D01*
X1098376Y1558413D01*
Y1557333D01*
G01X1098823Y1566933D02*
Y1563693D01*
X1099371Y1563145D01*
Y1561153D01*
G01X1091569Y1561300D02*
X1093705Y1563436D01*
Y1566933D01*
G01X1093376Y1557333D02*
Y1559493D01*
X1091569Y1561300D01*
G01X1092527Y1579422D02*
X1093705Y1578244D01*
Y1574807D01*
G01X1100476Y1579318D02*
X1099323D01*
X1098823Y1578818D01*
Y1574807D01*
G01X1102904Y1593206D02*
X1106905Y1589205D01*
Y1570669D01*
X1102904Y1566668D01*
G01X1100233Y1582433D02*
Y1580673D01*
X1100476Y1580430D01*
Y1579318D01*
G01X1100233Y1585583D02*
X1101299D01*
X1101800Y1585082D01*
Y1583430D01*
X1102797Y1582433D01*
X1104233D01*
G01X1100233Y1585583D02*
Y1588000D01*
G01X1098904Y1596356D02*
Y1602138D01*
G01X1102904Y1596356D02*
X1098904D01*
G01Y1602138D02*
X1097132D01*
X1096287Y1602983D01*
Y1606949D01*
G01X1093778Y1599574D02*
X1093727Y1599625D01*
Y1606949D01*
G01X1093778Y1599574D02*
X1094904Y1598448D01*
Y1596356D01*
G01X1096287Y1621515D02*
Y1624862D01*
X1096941Y1625516D01*
Y1627905D01*
G01X1098846Y1621515D02*
Y1625239D01*
X1103057Y1629450D01*
X1105474D01*
G01Y1635000D02*
Y1638426D01*
G01X1101474Y1631850D02*
X1102946D01*
X1103478Y1632382D01*
Y1634811D01*
X1103667Y1635000D01*
X1105474D01*
G01X1093474Y1631850D02*
X1097474D01*
G01D02*
Y1630426D01*
X1096941Y1629893D01*
Y1627905D01*
G01X1097474Y1635000D02*
Y1637753D01*
G01X1105474Y1631850D02*
Y1629450D01*
G01X1120021Y60513D02*
Y64722D01*
G01D02*
Y72679D01*
X1117933Y74767D01*
X1113471D01*
X1111291Y72587D01*
G01X1122881Y60438D02*
Y64422D01*
X1122581Y64722D01*
G01D02*
Y72967D01*
X1118961Y76587D01*
X1111291D01*
G01X1120149Y85731D02*
X1120021Y85603D01*
Y81848D01*
G01X1123703Y86046D02*
X1122581Y84924D01*
Y81848D01*
G01X1108096Y68581D02*
Y69564D01*
X1111119Y72587D01*
X1111291D01*
G01X1108096Y80581D02*
Y79618D01*
X1111127Y76587D01*
X1111291D01*
G01X1120149Y85731D02*
Y88244D01*
X1120706Y88801D01*
G01X1124655Y88729D02*
Y86998D01*
X1123703Y86046D01*
G01X1120706Y91951D02*
Y94351D01*
G01X1111553Y112083D02*
Y112402D01*
X1113639Y114488D01*
G01X1115842Y107921D02*
Y103621D01*
G01X1125178Y142648D02*
X1123656D01*
X1121208Y140200D01*
X1111606D01*
X1110559Y141247D01*
X1107759D01*
G01X1119991Y157370D02*
Y148980D01*
X1121220Y147754D01*
X1123331D01*
G01X1130142Y130898D02*
X1130300Y131056D01*
Y145019D01*
X1127569Y147754D01*
X1123331D01*
G01X1117032Y158194D02*
Y148325D01*
X1116532Y147825D01*
X1111915D01*
X1111346Y147256D01*
Y145768D01*
G01X1112246Y143518D02*
X1114146D01*
X1114496Y143868D01*
Y145768D01*
G01X1125178Y139695D02*
X1126630D01*
X1127300Y140365D01*
Y144012D01*
X1126612Y144700D01*
X1122699D01*
X1120164Y142165D01*
X1112473D01*
X1112246Y142392D01*
Y143518D01*
G01X1123331Y154865D02*
X1128268D01*
G01X1123331Y150904D02*
Y154865D01*
G01X1117032Y158194D02*
X1117591Y158753D01*
Y158990D01*
X1124145Y165544D01*
X1151196D01*
X1158545Y158195D01*
X1219393D01*
X1219394Y158194D01*
G01X1111346Y152373D02*
Y149768D01*
G01X1109903Y168713D02*
Y171523D01*
G01X1115298Y178560D02*
Y179904D01*
G01X1118282Y180665D02*
X1116059D01*
X1115298Y179904D01*
G01X1118282Y176665D02*
Y180665D01*
G01X1115298Y179904D02*
Y180204D01*
X1113636Y181866D01*
X1111992D01*
G01X1118282Y168665D02*
Y172665D01*
G01X1113053Y168713D02*
X1118234D01*
X1118282Y168665D01*
G01X1111992Y179897D02*
Y176034D01*
X1115361Y172665D01*
G01D02*
X1118282D01*
G01X1121432Y192665D02*
X1124075D01*
G01X1121432Y196665D02*
X1124075D01*
G01X1109433Y188362D02*
Y192490D01*
G01D02*
X1113608Y196665D01*
X1118282D01*
G01Y184665D02*
X1117451Y183834D01*
X1115188D01*
G01D02*
X1111992D01*
G01Y185803D02*
Y189278D01*
X1112899Y190185D01*
X1114708D01*
G01D02*
Y191730D01*
X1115643Y192665D01*
X1118282D01*
G01X1124188Y186778D02*
Y185398D01*
X1123455Y184665D01*
X1121432D01*
G01Y188665D02*
X1123457D01*
X1124188Y187934D01*
Y186778D01*
G01X1115478Y200864D02*
X1118377D01*
G01X1111603Y209229D02*
X1112325D01*
X1112913Y208641D01*
Y203429D01*
X1115478Y200864D01*
G01X1118377Y204864D02*
Y208864D01*
G01X1115501Y207037D02*
X1117328Y208864D01*
X1118377D01*
G01X1111603Y211197D02*
X1113056D01*
X1115501Y208752D01*
Y207037D01*
G01X1118377Y212864D02*
X1117968Y212455D01*
X1115567D01*
G01X1111603Y213166D02*
X1113289D01*
X1114000Y212455D01*
X1115567D01*
G01X1121527Y208864D02*
X1124107D01*
G01X1111603Y217103D02*
X1113616D01*
X1118377Y221864D01*
G01X1118374Y225719D02*
Y221867D01*
X1118377Y221864D01*
G01X1120376Y228631D02*
Y227721D01*
X1118374Y225719D01*
G01X1132612Y242078D02*
X1125340D01*
X1122852Y244566D01*
Y255458D01*
X1125313Y257919D01*
X1177035D01*
G01X1129075Y329000D02*
Y327338D01*
X1128237Y326500D01*
X1123075D01*
X1120575Y329000D01*
G01X1129075Y334000D02*
Y332347D01*
X1128228Y331500D01*
X1123075D01*
X1120575Y334000D01*
G01X1129075Y339000D02*
Y341000D01*
X1128575Y341500D01*
X1121076D01*
X1120575Y340999D01*
Y339000D01*
G01X1118848Y382109D02*
X1118806Y382067D01*
X1113553D01*
G01Y465177D02*
X1122130D01*
X1124507Y462800D01*
X1127767D01*
G01X1113553Y556555D02*
X1119721D01*
X1121678Y554598D01*
X1127857D01*
G01X1113553Y549469D02*
X1127835D01*
G01X1118847Y551683D02*
X1118699Y551831D01*
X1113553D01*
G01X1118847Y561420D02*
X1117421D01*
X1117281Y561280D01*
X1113553D01*
G01X1132598Y562800D02*
X1122989D01*
X1121609Y561420D01*
X1118847D01*
G01X1113553Y558917D02*
X1118847D01*
G01D02*
X1121466D01*
X1122883Y557500D01*
X1131298D01*
X1132598Y558800D01*
G01X1113553Y592756D02*
X1119929D01*
X1122673Y595500D01*
G01X1113553Y621102D02*
X1119071D01*
X1120673Y619500D01*
X1128173D01*
G01X1113553Y609291D02*
X1116759D01*
X1117540Y610072D01*
X1123331D01*
G01X1113553Y614016D02*
X1116568D01*
X1117836Y615284D01*
X1122234D01*
X1123267Y616317D01*
G01X1113553Y606929D02*
X1117673D01*
G01X1113553Y604567D02*
X1122173D01*
G01X1113553Y616378D02*
X1117133D01*
X1117633Y616878D01*
Y618400D01*
G01X1113553Y611654D02*
X1116976D01*
X1117914Y612592D01*
G01X1113553Y623465D02*
X1124638D01*
X1126573Y625400D01*
X1128173D01*
G01X1115151Y653161D02*
Y650119D01*
G01X1115320Y646449D02*
X1119151Y650280D01*
Y653161D01*
G01Y656311D02*
X1125979D01*
X1133869Y648421D01*
G01X1119151Y656311D02*
X1115151D01*
G01D02*
X1113429D01*
X1113005Y655887D01*
Y654165D01*
X1112001Y653161D01*
X1109682D01*
G01X1108045Y672360D02*
Y668153D01*
G01X1115525Y682006D02*
X1118513D01*
X1119562Y683055D01*
X1122228D01*
G01D02*
Y685271D01*
X1119075Y688424D01*
Y689694D01*
G01X1111785Y682006D02*
Y686971D01*
G01X1122225Y689694D02*
X1130970D01*
G01X1119075D02*
X1118855Y689914D01*
Y694797D01*
G01X1116296D02*
Y691851D01*
G01Y702277D02*
Y705414D01*
X1114955Y706755D01*
Y710129D01*
G01D02*
X1110385D01*
X1109113Y708857D01*
Y706901D01*
G01D02*
Y703929D01*
X1110765Y702277D01*
X1113737D01*
G01X1119094Y1116338D02*
X1117224Y1114468D01*
G01X1115354Y1116338D02*
X1113484Y1114468D01*
G01X1122834Y1116338D02*
X1120964Y1114468D01*
G01X1111613Y1116338D02*
X1109743Y1114468D01*
G01X1111613Y1142519D02*
X1109743Y1140649D01*
G01X1122834Y1217322D02*
X1120964Y1215452D01*
G01Y1211712D02*
X1122834Y1213582D01*
G01X1111613D02*
X1109743Y1215452D01*
G01X1115354Y1213582D02*
X1113484Y1211712D01*
G01X1117224D02*
X1119094Y1213582D01*
G01X1125435Y81848D02*
Y82885D01*
X1128562Y86012D01*
G01X1124655Y91879D02*
Y94279D01*
G01X1128562Y86012D02*
Y88824D01*
G01X1129852Y113684D02*
Y110794D01*
X1129842Y110784D01*
G01D02*
X1128117Y109059D01*
Y107899D01*
G01X1132117D02*
X1136117D01*
G01X1131820Y113684D02*
Y111534D01*
X1132570Y110784D01*
X1134842D01*
G01D02*
X1136117Y109509D01*
Y107899D01*
G01X1138196Y130903D02*
X1138165Y130934D01*
Y134838D01*
G01X1138196Y127753D02*
Y126313D01*
X1139402Y125107D01*
G01X1129852Y121558D02*
Y123785D01*
X1129399Y124879D01*
G01D02*
Y127005D01*
X1130142Y127748D01*
G01X1131820Y121558D02*
Y124163D01*
X1132320Y124663D01*
X1134421D01*
G01D02*
Y126008D01*
X1134142Y126287D01*
Y127748D01*
G01X1127884Y121558D02*
Y123126D01*
X1126727Y124283D01*
X1124333D01*
G01D02*
X1124365Y124315D01*
Y125971D01*
X1126142Y127748D01*
G01X1134243Y153296D02*
Y150265D01*
X1135791Y148717D01*
X1141916D01*
G01X1132264Y136742D02*
Y138338D01*
X1132764Y138838D01*
X1135765D01*
G01X1138165Y134838D02*
Y138838D01*
G01X1135765D02*
X1138165D01*
G01X1128268Y154865D02*
X1131112Y157709D01*
X1137483D01*
X1137983Y158209D01*
Y161958D01*
G01X1137461Y232859D02*
Y232681D01*
X1141496Y228646D01*
G01X1139591Y242078D02*
X1135762D01*
G01X1137360Y247292D02*
X1137103Y247035D01*
Y244571D01*
G01D02*
X1135762Y243230D01*
Y242078D01*
G01X1131792Y252371D02*
Y248371D01*
G01X1137360Y250245D02*
X1135620D01*
X1134483Y249108D01*
G01D02*
X1134211D01*
X1133474Y248371D01*
X1131792D01*
G01X1150912Y334148D02*
X1139912D01*
X1137830Y336230D01*
G01D02*
X1135748Y334148D01*
X1129223D01*
X1129075Y334000D01*
G01Y339000D02*
X1132939D01*
X1133087Y339148D01*
X1145587D01*
G01X1150912Y329148D02*
X1138571D01*
G01D02*
X1129223D01*
X1129075Y329000D01*
G01X1135548Y455804D02*
Y458800D01*
G01X1132398D02*
Y462800D01*
G01X1127767D02*
X1132398D01*
G01X1135748Y545800D02*
Y541000D01*
X1136248Y540500D01*
X1139173D01*
G01X1127857Y554598D02*
X1131673D01*
X1133908Y552363D01*
X1138535D01*
X1141198Y549700D01*
G01X1132598Y545800D02*
Y549800D01*
G01X1127835Y549469D02*
X1130567D01*
X1130898Y549800D01*
X1132598D01*
G01X1137673Y568000D02*
X1144348Y561325D01*
Y557700D01*
G01X1128173Y619500D02*
X1131098D01*
X1132998Y621400D01*
G01X1136148D02*
Y625400D01*
G01X1133869Y648421D02*
X1136148Y646142D01*
Y625400D01*
G01X1128173D02*
X1132998D01*
G01X1130970Y689694D02*
X1155793D01*
X1166013Y679474D01*
Y675889D01*
G01X1141535Y1116338D02*
X1139665Y1114468D01*
G01X1137795Y1116338D02*
X1135925Y1114468D01*
G01X1134054Y1116338D02*
X1132184Y1114468D01*
G01X1126574Y1116338D02*
X1124704Y1114468D01*
G01X1126574Y1213582D02*
X1124704Y1215452D01*
G01X1130314Y1217322D02*
X1132184Y1215452D01*
G01X1130314Y1213582D02*
X1128444Y1211712D01*
G01X1153945Y103411D02*
Y102126D01*
X1156110Y99961D01*
X1160885D01*
G01X1151070Y97667D02*
X1154339D01*
G01X1160885Y97599D02*
X1154407D01*
X1154339Y97667D01*
G01X1160885Y92874D02*
X1151972D01*
X1149735Y95111D01*
G01X1153945Y103411D02*
X1150868D01*
G01Y106561D02*
X1154104D01*
G01X1146886Y106495D02*
X1150802D01*
X1150868Y106561D01*
G01X1146886Y102495D02*
Y106495D01*
G01X1144786Y143762D02*
X1148016D01*
G01X1141916Y148717D02*
X1144069D01*
X1144786Y148000D01*
Y146912D01*
G01X1147011Y225055D02*
Y229782D01*
X1146237Y230556D01*
G01X1155082Y230117D02*
X1155098Y230133D01*
Y232984D01*
G01X1151098D02*
Y231180D01*
X1150492Y230574D01*
Y227824D01*
G01D02*
Y227724D01*
X1148980Y226212D01*
Y225055D01*
G01X1143074D02*
Y227068D01*
X1141496Y228646D01*
G01X1146863Y232959D02*
X1146237Y232333D01*
Y230556D01*
G01X1152799Y241681D02*
Y244297D01*
G01X1149649Y241681D02*
X1149008Y241040D01*
Y233484D01*
X1149508Y232984D01*
X1151098D01*
G01X1144446Y253198D02*
X1147590D01*
G01X1144446Y250245D02*
X1148899D01*
X1149253Y250599D01*
G01X1147590Y253198D02*
X1149094D01*
X1149449Y252843D01*
Y250795D01*
X1149253Y250599D01*
G01X1145587Y339148D02*
X1150912D01*
G01X1169668Y373503D02*
X1145362D01*
X1144862Y374003D01*
Y380718D01*
G01D02*
Y384718D01*
G01X1148012D02*
X1166177D01*
G01X1144862Y388718D02*
Y390010D01*
X1145363Y390511D01*
X1161902D01*
X1162887Y391496D01*
X1167359D01*
G01X1148012Y388718D02*
X1156242D01*
X1157076Y387884D01*
X1160314D01*
G01X1184478Y382047D02*
X1180735D01*
X1179406Y380718D01*
X1155998D01*
G01D02*
X1148012D01*
G01Y392718D02*
X1157993D01*
X1159133Y393858D01*
G01X1148012Y396718D02*
Y392718D01*
G01Y404718D02*
X1156571D01*
G01X1148012Y408718D02*
X1165774D01*
G01X1148012Y400718D02*
X1166992D01*
G01X1148012Y412718D02*
X1156734D01*
G01X1275660Y345785D02*
Y346940D01*
X1260900Y361700D01*
X1242200D01*
X1231400Y372500D01*
X1221700D01*
X1218800Y375400D01*
Y406700D01*
X1210700Y414800D01*
X1168500D01*
X1147700Y435600D01*
Y546500D01*
X1156600Y555400D01*
X1163300D01*
X1165400Y553300D01*
G01X1167900D02*
Y552200D01*
X1166600Y550900D01*
X1164000D01*
X1161900Y553000D01*
X1157400D01*
X1149700Y545300D01*
Y436501D01*
X1169601Y416600D01*
X1211701D01*
X1221360Y406941D01*
Y376461D01*
X1222761Y375060D01*
X1232461D01*
X1243261Y364260D01*
X1261961D01*
X1279655Y346566D01*
Y345726D01*
G01X1144348Y549700D02*
Y553700D01*
G01D02*
Y557700D01*
G01X1160275Y650671D02*
X1156275D01*
G01X1157251Y645900D02*
Y647895D01*
X1156275Y648871D01*
Y650671D01*
G01X1152485Y767567D02*
Y764552D01*
G01X1155929Y786294D02*
Y783586D01*
X1152485Y780142D01*
Y775642D01*
G01D02*
Y770717D01*
G01X1153485Y813142D02*
X1155929Y810698D01*
Y808342D01*
G01X1154985Y802897D02*
X1157402D01*
X1158488Y803983D01*
Y808342D01*
G01X1155485Y839067D02*
X1159485D01*
G01X1155485Y842217D02*
Y846325D01*
X1153229Y848581D01*
G01X1141535Y1217322D02*
X1143405Y1215452D01*
G01X1154625D02*
X1152755Y1213582D01*
G01X1160885Y88150D02*
X1167982D01*
X1170447Y90615D01*
G01X1160885Y90512D02*
X1164997D01*
X1165135Y90650D01*
G01X1164885Y95236D02*
X1160885D01*
G01X1171712Y324148D02*
X1175431D01*
X1180312Y319267D01*
G01X1171712Y329148D02*
X1178259D01*
X1178814Y329703D01*
X1181155D01*
G01X1169668Y373503D02*
X1172885Y370286D01*
Y367129D01*
X1182873Y357141D01*
X1236297D01*
X1238577Y354861D01*
Y342819D01*
X1238077Y342319D01*
X1235589D01*
G01X1166177Y384718D02*
X1173729D01*
X1174037Y384410D01*
X1184478D01*
G01X1167359Y391496D02*
X1184478D01*
G01X1160314Y387884D02*
X1171891D01*
X1173141Y389134D01*
X1184478D01*
G01X1159133Y393858D02*
X1184478D01*
G01X1156571Y404718D02*
X1170243D01*
X1176378Y398583D01*
X1184478D01*
G01X1165774Y408718D02*
X1169808D01*
X1174550Y403976D01*
Y403961D01*
X1177566Y400945D01*
X1184478D01*
G01X1166992Y400718D02*
X1169878D01*
X1174375Y396221D01*
X1184478D01*
G01X1156734Y412718D02*
X1156772Y412756D01*
X1184478D01*
G01X1163298Y453873D02*
Y449873D01*
G01Y445873D02*
Y443426D01*
X1163768Y442956D01*
X1166868D01*
G01X1163298Y449873D02*
Y445873D01*
G01X1166448Y453873D02*
X1173934D01*
X1176699Y451108D01*
G01X1163298Y465874D02*
Y462859D01*
G01X1166448Y458859D02*
X1171920D01*
X1172324Y458455D01*
X1176138D01*
G01X1166448Y462859D02*
Y458859D01*
G01X1162483Y546712D02*
X1159535D01*
G01X1162483D02*
Y548050D01*
X1163309Y548876D01*
X1173466D01*
X1177165Y545177D01*
X1218479D01*
X1221276Y547974D01*
X1231967D01*
X1232833Y547108D01*
Y545912D01*
G01X1165633Y542712D02*
X1170264D01*
G01X1165633Y546712D02*
Y542712D01*
G01X1170264D02*
X1173524D01*
X1175901Y540335D01*
X1184478D01*
G01X1157451Y620788D02*
Y618288D01*
G01X1165451Y620788D02*
X1170293D01*
G01D02*
X1172687D01*
X1175344Y623445D01*
X1184478D01*
G01X1160204Y633786D02*
Y631449D01*
X1157451Y628696D01*
G01D02*
Y623938D01*
G01X1163157Y633786D02*
Y628670D01*
G01X1165451Y623938D02*
X1161451D01*
G01X1163157Y628670D02*
X1161451Y626964D01*
Y623938D01*
G01X1160204Y640872D02*
Y643255D01*
X1161149Y644200D01*
X1162299D01*
X1164040Y645941D01*
G01D02*
X1164275Y646176D01*
Y650671D01*
G01X1157251Y645900D02*
Y640872D01*
G01X1160275Y653821D02*
Y656321D01*
G01X1159887Y869106D02*
Y867113D01*
X1165000Y862000D01*
X1190000D01*
X1194500Y857500D01*
Y803729D01*
X1184500Y779586D01*
Y676546D01*
X1164275Y656321D01*
G01Y653821D02*
Y656321D01*
G01X1164756Y669913D02*
Y672917D01*
X1166013Y674174D01*
Y675889D01*
G01X1156485Y770717D02*
Y779142D01*
G01D02*
X1160528Y783185D01*
X1161047Y784438D01*
Y786294D01*
G01X1168725D02*
Y780642D01*
X1168985Y780382D01*
Y775642D01*
G01D02*
Y771085D01*
X1168485Y770585D01*
G01X1164485Y770717D02*
X1164985Y771217D01*
Y779142D01*
G01D02*
X1166166Y780323D01*
Y786294D01*
G01X1160485Y770717D02*
Y775642D01*
G01D02*
Y778498D01*
X1161519Y780994D01*
X1162907Y782382D01*
X1163606Y784070D01*
Y786294D01*
G01X1167485Y820642D02*
X1163606Y816763D01*
Y808342D01*
G01X1166166D02*
Y813823D01*
X1172485Y820142D01*
X1175485D01*
G01X1168725Y808342D02*
Y812142D01*
X1172725Y816142D01*
X1178985D01*
X1183485Y820642D01*
G01X1159485D02*
Y816143D01*
X1161047Y814581D01*
Y808342D01*
G01X1164732Y802269D02*
X1166830Y804367D01*
X1170058D01*
X1171284Y805593D01*
Y808342D01*
G01X1159485Y834142D02*
Y828717D01*
G01X1167485Y834142D02*
Y828717D01*
G01Y825567D02*
Y820642D01*
G01X1159485Y825567D02*
Y820642D01*
G01Y839067D02*
Y834142D01*
G01X1171485Y839067D02*
X1175485D01*
G01X1167485D02*
Y834142D01*
G01X1163485Y839067D02*
X1167485D01*
G01X1163579Y850774D02*
X1171485Y842868D01*
Y842217D01*
G01X1161535Y844167D02*
X1163485Y842217D01*
G01X1183012Y856553D02*
X1167050D01*
X1161866Y854406D01*
X1160319Y852859D01*
Y849383D01*
X1167485Y842217D01*
G01X1190213Y856816D02*
X1184126Y859337D01*
X1167175D01*
X1159930Y856336D01*
X1157771Y854177D01*
Y843931D01*
X1159485Y842217D01*
G01X1160235Y1112598D02*
X1160236D01*
X1162106Y1114468D01*
G01X1167716Y1112598D02*
X1169586Y1114468D01*
G01X1160235Y1116338D02*
X1160236D01*
X1162106Y1118208D01*
G01X1171456Y1112598D02*
X1173326Y1114468D01*
G01X1171456Y1116338D02*
X1173326Y1118208D01*
G01X1167716Y1116338D02*
X1169586Y1118208D01*
G01X1167716Y1217322D02*
X1169586Y1215452D01*
G01X1162105Y1215451D02*
X1160235Y1217322D01*
G01X1158365Y1215452D02*
X1156495Y1213582D01*
G01X1162105Y1211711D02*
X1160235Y1213582D01*
G01X1165846Y1211711D02*
X1163976Y1213582D01*
G01X1195557Y98198D02*
Y98073D01*
X1193896Y96412D01*
X1185120D01*
X1183726Y95018D01*
Y92874D01*
G01D02*
X1178995D01*
G01Y99961D02*
X1174768D01*
G01X1174818Y95236D02*
X1178995D01*
G01X1180312Y319267D02*
X1184009Y322964D01*
Y324142D01*
G01X1187159D02*
X1190127D01*
G01X1181155Y329703D02*
X1184934D01*
X1185239Y329398D01*
X1188889D01*
G01X1176699Y451108D02*
X1178850Y448957D01*
X1184478D01*
G01X1176138Y458455D02*
X1178550Y456043D01*
X1184478D01*
G01Y453681D02*
X1179384D01*
X1179184Y453881D01*
G01X1184478Y444232D02*
X1179459D01*
X1178083Y442856D01*
G01X1184478Y446595D02*
X1179184D01*
G01X1173122Y802759D02*
X1173182D01*
X1173843Y803420D01*
Y808342D01*
G01X1183485Y834142D02*
Y828717D01*
G01X1175485Y833642D02*
Y828717D01*
G01Y820142D02*
Y825567D01*
G01X1183485Y820642D02*
Y825567D01*
G01Y839067D02*
Y834142D01*
G01X1179485Y839067D02*
X1183485D01*
G01X1175485D02*
Y833642D01*
G01X1185516Y844248D02*
X1183485Y842217D01*
G01X1190968Y848703D02*
X1189534Y847269D01*
X1184537D01*
X1179485Y842217D01*
G01X1175485D02*
X1184340Y851072D01*
G01X1186417Y1116338D02*
X1188287Y1114468D01*
G01X1175196Y1112598D02*
X1177066Y1114468D01*
G01X1175196Y1116338D02*
X1177066Y1118208D01*
G01X1182676Y1112598D02*
X1184546Y1114468D01*
G01X1175196Y1217322D02*
X1177066Y1215452D01*
G01X1188287Y1211712D02*
X1186417Y1213582D01*
G01X1184547Y1215452D02*
X1182677Y1217322D01*
X1182676D01*
G01X1199557Y98198D02*
X1195557D01*
G01X1205061Y97475D02*
X1202561D01*
G01X1205061Y100625D02*
X1209542D01*
G01X1205061Y105087D02*
Y100625D01*
G01X1204046Y141247D02*
X1200217D01*
G01X1201815Y146461D02*
X1201558Y146204D01*
Y143740D01*
G01D02*
X1200217Y142399D01*
Y141247D01*
G01X1196247Y151540D02*
Y147540D01*
G01D02*
X1197929D01*
X1198666Y148277D01*
X1198938D01*
G01X1201815Y149414D02*
X1200075D01*
X1198938Y148277D01*
G01X1199663Y259535D02*
Y256303D01*
G01X1199422Y265896D02*
Y264086D01*
X1199663Y263845D01*
Y262685D01*
G01X1204438Y266114D02*
Y264678D01*
X1203663Y263903D01*
Y262685D01*
G01X1194335Y265701D02*
X1195663Y264373D01*
Y262685D01*
G01X1201911Y281982D02*
X1199903Y279974D01*
Y277477D01*
G01Y269603D02*
Y267599D01*
X1199422Y267118D01*
Y265896D01*
G01X1195970Y281716D02*
X1197935Y279751D01*
Y277477D01*
G01X1204438Y266114D02*
X1201871Y268681D01*
Y269603D01*
G01X1194335Y265701D02*
X1195513Y266879D01*
X1197239D01*
X1197935Y267575D01*
Y269603D01*
G01X1202716Y284908D02*
Y282787D01*
X1201911Y281982D01*
G01X1194716Y284908D02*
X1198716D01*
G01X1195970Y281716D02*
X1197328D01*
X1198716Y283104D01*
Y284908D01*
G01X1204263Y317873D02*
X1204301Y317911D01*
X1209014D01*
G01X1195800Y324000D02*
Y327931D01*
X1194333Y329398D01*
X1192039D01*
G01X1202589Y386772D02*
X1208401D01*
X1213173Y382000D01*
Y377912D01*
G01X1202589Y384410D02*
X1206693D01*
G01X1202589Y389134D02*
X1210539D01*
X1213173Y386500D01*
G01X1202589Y382047D02*
X1209872D01*
G01X1202589Y391496D02*
X1212173D01*
G01X1202589Y398583D02*
X1208173D01*
G01X1202589Y396221D02*
X1211570D01*
X1213261Y397912D01*
G01X1202589Y393858D02*
X1206531D01*
G01X1202589Y400945D02*
X1207618D01*
X1210173Y403500D01*
G01X1202589Y412756D02*
X1208417D01*
X1212173Y409000D01*
G01X1192702Y440489D02*
Y441623D01*
X1197674Y446595D01*
X1202589D01*
G01X1192957Y435158D02*
X1194651Y436852D01*
Y441917D01*
X1197819Y445085D01*
X1199959D01*
X1200812Y444232D01*
X1202589D01*
G01Y448957D02*
X1201418D01*
X1200099Y448411D01*
X1196570D01*
X1193000Y444841D01*
G01X1192686Y449961D02*
X1192825Y450100D01*
X1199465D01*
X1200684Y451319D01*
X1202589D01*
G01Y456043D02*
X1200008D01*
X1199240Y456811D01*
X1197405Y457570D01*
X1196403Y458572D01*
G01X1202589Y540335D02*
X1224838D01*
G01X1202589Y623445D02*
X1216179D01*
X1216712Y622912D01*
X1224929D01*
G01X1268715Y914949D02*
X1245488Y938176D01*
X1191746D01*
X1189219Y940703D01*
G01X1268715Y918956D02*
X1247026Y940645D01*
X1197173D01*
G01X1193897Y1112598D02*
X1195767Y1114468D01*
G01X1190157Y1112598D02*
X1192027Y1114468D01*
G01X1197637Y1112598D02*
X1199507Y1114468D01*
G01X1197637Y1138779D02*
X1199507Y1136909D01*
G01X1197637Y1142519D02*
X1199507Y1140649D01*
G01X1201377Y1149999D02*
X1203247Y1148129D01*
G01X1197637Y1146259D02*
X1195767Y1144389D01*
G01X1197637Y1149999D02*
X1199507Y1148129D01*
G01X1201377Y1146259D02*
X1199507Y1144389D01*
G01X1201377Y1142519D02*
X1203247Y1140649D01*
G01X1199507Y1204232D02*
X1201377Y1206102D01*
G01X1195767Y1200491D02*
X1197637Y1198621D01*
G01X1199507Y1211712D02*
X1201377Y1213582D01*
G01X1199507Y1215452D02*
X1201377Y1217322D01*
G01X1199507Y1207972D02*
X1197637Y1209842D01*
G01X1195767Y1215452D02*
X1193897Y1217322D01*
G01X1192027Y1207972D02*
X1190157Y1206102D01*
G01X1197637D02*
X1195767Y1207972D01*
G01X1197637Y1213582D02*
X1195767Y1211712D01*
G01X1208103Y72615D02*
X1208131Y72587D01*
X1210503D01*
G01X1208103Y76587D02*
X1210503D01*
G01X1210458Y80581D02*
Y79618D01*
X1213489Y76587D01*
X1213653D01*
G01D02*
X1221323D01*
X1224943Y72967D01*
Y64722D01*
G01X1210458Y68581D02*
Y69564D01*
X1213481Y72587D01*
X1213653D01*
G01X1222383Y64722D02*
Y73017D01*
X1220633Y74767D01*
X1215833D01*
X1213653Y72587D01*
G01X1209542Y100625D02*
X1210908Y99259D01*
X1214464D01*
G01X1213915Y112083D02*
Y112402D01*
X1216001Y114488D01*
G01X1218204Y107921D02*
Y103621D01*
G01X1210121Y141247D02*
X1207196D01*
G01X1210121D02*
X1212921D01*
X1213868Y140300D01*
X1223670D01*
X1226018Y142648D01*
X1227540D01*
G01X1213708Y145768D02*
Y147256D01*
X1214277Y147825D01*
X1218894D01*
X1219394Y148325D01*
Y158194D01*
G01X1216858Y145768D02*
Y143868D01*
X1216508Y143518D01*
X1214608D01*
G01D02*
Y142392D01*
X1214835Y142165D01*
X1223066D01*
X1225801Y144900D01*
X1228974D01*
X1229700Y144174D01*
Y140403D01*
X1228992Y139695D01*
X1227540D01*
G01X1369100Y157500D02*
X1261602D01*
X1253558Y165544D01*
X1226543D01*
X1219953Y158954D01*
Y158753D01*
X1219394Y158194D01*
G01X1208901Y149414D02*
X1213354D01*
X1213708Y149768D01*
G01X1208901Y152367D02*
X1213702D01*
X1213708Y152373D01*
G01D02*
Y149768D01*
G01X1212265Y168713D02*
Y171523D01*
G01X1220644Y168665D02*
Y172665D01*
G01X1215415Y168713D02*
X1220596D01*
X1220644Y168665D01*
G01X1214354Y179897D02*
Y176034D01*
X1217723Y172665D01*
G01D02*
X1220644D01*
G01X1214354Y181866D02*
X1215998D01*
X1217660Y180204D01*
Y179904D01*
G01Y178560D02*
Y179904D01*
G01X1220644Y176665D02*
Y180665D01*
G01X1217660Y179904D02*
X1218421Y180665D01*
X1220644D01*
G01X1211795Y188362D02*
Y192490D01*
G01D02*
X1213700Y194395D01*
X1215577D01*
X1216470Y195288D01*
Y196620D01*
G01X1220644Y184665D02*
X1219813Y183834D01*
X1217550D01*
G01D02*
X1214354D01*
G01X1210268Y198671D02*
X1212319Y196620D01*
X1213320D01*
G01X1220644Y192665D02*
Y196665D01*
G01X1214354Y185803D02*
Y189278D01*
X1215261Y190185D01*
X1217070D01*
G01D02*
Y191730D01*
X1218005Y192665D01*
X1220644D01*
G01X1223794Y196665D02*
Y197941D01*
X1222898Y198837D01*
X1215070D01*
X1213367Y200540D01*
X1208192D01*
X1207692Y200040D01*
Y192361D01*
X1207753Y192300D01*
G01X1220739Y204864D02*
Y208864D01*
G01X1217863Y207037D02*
X1219690Y208864D01*
X1220739D01*
G01X1213965Y211197D02*
X1215418D01*
X1217863Y208752D01*
Y207037D01*
G01X1220739Y212864D02*
X1220330Y212455D01*
X1217929D01*
G01X1213965Y213166D02*
X1215651D01*
X1216362Y212455D01*
X1217929D01*
G01X1217840Y200864D02*
X1220739D01*
G01X1213965Y209229D02*
X1214687D01*
X1215275Y208641D01*
Y203429D01*
X1217840Y200864D01*
G01X1213965Y217103D02*
X1215978D01*
X1220739Y221864D01*
G01X1220736Y225719D02*
Y221867D01*
X1220739Y221864D01*
G01X1222738Y228631D02*
X1220736Y226629D01*
Y225719D01*
G01X1214006Y319290D02*
X1210393D01*
X1209014Y317911D01*
G01D02*
X1210194Y316731D01*
X1214006D01*
G01X1221486Y319290D02*
X1219682D01*
X1219212Y319760D01*
Y322955D01*
X1220723Y324466D01*
G01X1217458Y344878D02*
X1212362D01*
X1211892Y344408D01*
Y339559D01*
G01D02*
Y338076D01*
X1213644Y336324D01*
X1224801D01*
G01X1208858Y1138779D02*
X1206988Y1140649D01*
G01X1216338Y1142519D02*
X1218208Y1144389D01*
G01X1216338Y1149999D02*
X1218208Y1151869D01*
G01X1208858Y1153740D02*
X1206988Y1155610D01*
G01X1208858Y1146259D02*
X1206988Y1148129D01*
G01X1212598Y1153740D02*
X1210728Y1155610D01*
G01X1220078Y1149999D02*
X1221948Y1151869D01*
G01X1220078Y1142519D02*
X1221948Y1144389D01*
G01X1224943Y64722D02*
X1225243Y64422D01*
Y60438D01*
G01X1222383Y64722D02*
Y60513D01*
G01X1222511Y85731D02*
X1222383Y85603D01*
Y81848D01*
G01X1226065Y86046D02*
X1224943Y84924D01*
Y81848D01*
G01X1230924Y86012D02*
X1227797Y82885D01*
Y81848D01*
G01X1223068Y88801D02*
X1222511Y88244D01*
Y85731D01*
G01X1227017Y88729D02*
Y86998D01*
X1226065Y86046D01*
G01X1230924Y88824D02*
Y86012D01*
G01X1227017Y91879D02*
Y94279D01*
G01X1223068Y91951D02*
Y94351D01*
G01X1232214Y113684D02*
Y110794D01*
X1232204Y110784D01*
G01D02*
X1230479Y109059D01*
Y107899D01*
G01X1238479D02*
Y109509D01*
X1237204Y110784D01*
G01X1234479Y107899D02*
X1238479D01*
G01X1237204Y110784D02*
X1234932D01*
X1234182Y111534D01*
Y113684D01*
G01X1232504Y130898D02*
Y132200D01*
X1232700Y132396D01*
Y135300D01*
X1232504Y135496D01*
Y145177D01*
X1229931Y147754D01*
X1225693D01*
G01X1234182Y121558D02*
Y124163D01*
X1234682Y124663D01*
X1236783D01*
G01D02*
Y126008D01*
X1236504Y126287D01*
Y127748D01*
G01X1230246Y121558D02*
Y123126D01*
X1229089Y124283D01*
X1226695D01*
G01D02*
X1226727Y124315D01*
Y127525D01*
X1226504Y127748D01*
G01X1232214Y121558D02*
Y123785D01*
X1231761Y124879D01*
G01D02*
Y127005D01*
X1232504Y127748D01*
G01X1222353Y157370D02*
Y148980D01*
X1223582Y147754D01*
X1225693D01*
G01X1234626Y136742D02*
Y138338D01*
X1235126Y138838D01*
X1238127D01*
G01X1236605Y153296D02*
Y150265D01*
X1238153Y148717D01*
X1244278D01*
G01X1225693Y150904D02*
Y154865D01*
G01X1240345Y161958D02*
Y158209D01*
X1239845Y157709D01*
X1233474D01*
X1230630Y154865D01*
G01D02*
X1225693D01*
G01X1223794Y192665D02*
X1226437D01*
G01X1223794Y188665D02*
X1225819D01*
X1226550Y187934D01*
Y186778D01*
G01D02*
Y185398D01*
X1225817Y184665D01*
X1223794D01*
G01X1223889Y208864D02*
X1226469D01*
G01X1234974Y242078D02*
X1227702D01*
X1225214Y244566D01*
Y255458D01*
X1228636Y258880D01*
X1279246D01*
G01X1234154Y252371D02*
Y248371D01*
G01X1239722Y250245D02*
X1237982D01*
X1236845Y249108D01*
G01D02*
X1236573D01*
X1235836Y248371D01*
X1234154D01*
G01X1226436Y318740D02*
Y314890D01*
G01D02*
X1229252D01*
G01D02*
X1231293Y312849D01*
X1233600D01*
G01X1221486Y321849D02*
X1226395D01*
X1226436Y321890D01*
G01X1234447Y328844D02*
X1230762D01*
X1226436Y324518D01*
G01D02*
Y321890D01*
G01X1226120Y342319D02*
X1231589D01*
G01D02*
X1235589D01*
G01X1234447Y332584D02*
X1229438D01*
G01X1235589Y345469D02*
Y348015D01*
G01X1229942Y347937D02*
X1231088D01*
X1231589Y347436D01*
Y345469D01*
G01X1232833Y545912D02*
X1234024Y544721D01*
X1247443D01*
X1252151Y549429D01*
Y552165D01*
X1253087Y553101D01*
G01X1229683Y545912D02*
Y541912D01*
G01X1224838Y540335D02*
X1228106D01*
X1229683Y541912D01*
G01X1237458Y550137D02*
X1239830Y547765D01*
X1244338D01*
X1246858Y550285D01*
Y551381D01*
G01X1234941Y550137D02*
X1237458D01*
G01X1235930Y626229D02*
X1235247Y626912D01*
X1232833D01*
G01X1229683D02*
Y622912D01*
G01X1224929D02*
X1229683D01*
G01X1235039Y1138779D02*
X1236909Y1136909D01*
G01X1235039Y1153740D02*
X1236909Y1151870D01*
G01X1227558Y1149999D02*
X1225688Y1148129D01*
G01X1227558Y1142519D02*
X1225688Y1140649D01*
G01X1231298Y1142519D02*
X1229428Y1140649D01*
G01X1231298Y1149999D02*
X1229428Y1148129D01*
G01X1227558Y1157480D02*
X1225688Y1155610D01*
G01X1235039Y1146259D02*
X1236909Y1144389D01*
G01X1231298Y1157480D02*
X1229428Y1155610D01*
G01X1235039Y1161220D02*
X1236909Y1159350D01*
G01X1235039Y1183661D02*
X1236909Y1181791D01*
G01X1235039Y1176180D02*
X1236909Y1174310D01*
G01X1235039Y1191141D02*
X1236909Y1189271D01*
G01X1253432Y97667D02*
X1256701D01*
G01X1263247Y92874D02*
X1254334D01*
X1252097Y95111D01*
G01X1253230Y103411D02*
X1256307D01*
G01X1249248Y102495D02*
Y106495D01*
G01D02*
X1253164D01*
X1253230Y106561D01*
G01D02*
X1256466D01*
G01X1240558Y130903D02*
X1240527Y130934D01*
Y134838D01*
G01X1240558Y127753D02*
Y126313D01*
X1241764Y125107D01*
G01X1247148Y143762D02*
X1250378D01*
G01X1244278Y148717D02*
X1246431D01*
X1247148Y148000D01*
Y146912D01*
G01X1240527Y134838D02*
Y138838D01*
G01X1238127D02*
X1240527D01*
G01X1249373Y225055D02*
Y229782D01*
X1248599Y230556D01*
G01X1251342Y225055D02*
Y226212D01*
X1252854Y227724D01*
Y227824D01*
G01D02*
Y230574D01*
X1253460Y231180D01*
Y232984D01*
G01X1243858Y228646D02*
X1239823Y232681D01*
Y232859D01*
G01X1245436Y225055D02*
Y227068D01*
X1243858Y228646D01*
G01X1249225Y232959D02*
X1248599Y232333D01*
Y230556D01*
G01X1252011Y241681D02*
X1251370Y241040D01*
Y233484D01*
X1251870Y232984D01*
X1253460D01*
G01X1241953Y242078D02*
X1238124D01*
G01X1239722Y247292D02*
X1239465Y247035D01*
Y244571D01*
G01D02*
X1238124Y243230D01*
Y242078D01*
G01X1251615Y250599D02*
X1251261Y250245D01*
X1246808D01*
G01Y253198D02*
Y256394D01*
G01D02*
X1249340D01*
X1251811Y253923D01*
Y250795D01*
X1251615Y250599D01*
G01X1256458Y555137D02*
X1255123D01*
X1253087Y553101D01*
G01X1241629Y550065D02*
Y552228D01*
X1245725Y556324D01*
X1247857D01*
X1250598Y559065D01*
Y560043D01*
G01D02*
X1253142D01*
X1254898Y558287D01*
X1256458D01*
G01X1253424Y1138130D02*
X1254425Y1137129D01*
X1255921D01*
G01X1255485Y1198850D02*
X1257788Y1196547D01*
Y1190888D01*
X1257141Y1190241D01*
X1253258D01*
X1245400Y1182383D01*
Y1139900D01*
X1246820Y1138480D01*
Y1135881D01*
X1250410Y1132291D01*
Y1131491D01*
X1300776Y1081125D01*
Y1048223D01*
X1306174Y1042825D01*
X1315606D01*
G01X1249230Y1189346D02*
Y1188849D01*
X1243700Y1183319D01*
Y1139200D01*
X1245168Y1137732D01*
Y1134181D01*
X1299056Y1080293D01*
Y1047332D01*
X1307044Y1039344D01*
X1315756D01*
G01X1249363Y1166065D02*
X1248073Y1164775D01*
Y1139827D01*
X1248900Y1139000D01*
Y1137501D01*
X1249272Y1137129D01*
X1250928D01*
G01X1238779Y1138779D02*
X1240649Y1136909D01*
G01X1256373Y1161400D02*
X1254073D01*
X1252873Y1160200D01*
Y1153249D01*
X1252880Y1153242D01*
G01X1238779Y1153740D02*
X1240649Y1151870D01*
G01X1238779Y1146259D02*
X1240649Y1144389D01*
G01X1255439Y1153242D02*
Y1150166D01*
X1254873Y1149600D01*
X1253973D01*
X1250928Y1146555D01*
Y1142828D01*
G01D02*
Y1140279D01*
G01X1238779Y1161220D02*
X1240649Y1159350D01*
G01X1238779Y1176180D02*
X1240649Y1174310D01*
G01X1238779Y1183661D02*
X1240649Y1181791D01*
G01X1238779Y1191141D02*
X1240649Y1189271D01*
G01X1251302Y1198850D02*
Y1195417D01*
X1251802Y1194917D01*
X1253056D01*
G01X1252381Y1207061D02*
X1251978Y1207464D01*
X1248490D01*
X1246734Y1205708D01*
Y1194272D01*
X1248510Y1192496D01*
X1249230D01*
G01X1252381Y1207061D02*
Y1203079D01*
X1251302Y1202000D01*
G01X1249230Y1192496D02*
X1249350Y1192376D01*
X1252865D01*
G01X1257110Y1523458D02*
X1254241D01*
X1249894Y1527805D01*
G01X1253904Y1519645D02*
X1254090Y1519459D01*
X1257058D01*
G01X1254275Y1531334D02*
X1254267Y1531342D01*
X1250690D01*
G01X1257095Y1535385D02*
X1250485D01*
X1250434Y1535334D01*
G01X1263247Y99961D02*
X1258472D01*
X1256307Y102126D01*
Y103411D01*
G01X1263247Y97599D02*
X1256769D01*
X1256701Y97667D01*
G01X1263247Y88150D02*
X1270344D01*
X1272809Y90615D01*
G01X1263247Y90512D02*
X1267359D01*
X1267497Y90650D01*
G01X1267247Y95236D02*
X1263247D01*
G01X1255161Y241681D02*
Y244297D01*
G01X1268294Y333215D02*
X1264215D01*
G01X1268294Y330655D02*
X1262500D01*
G01X1268294Y336069D02*
X1264069D01*
X1264000Y336000D01*
X1263500D01*
G01D02*
X1261075D01*
G01X1260659Y382723D02*
Y382819D01*
X1263484Y385644D01*
G01X1256659Y382723D02*
X1260659D01*
G01X1270716Y389013D02*
Y387971D01*
X1269846Y387101D01*
X1264941D01*
X1263484Y385644D01*
G01X1264659Y382723D02*
X1268659D01*
G01X1272685Y389013D02*
Y387578D01*
X1270230Y385123D01*
X1268659D01*
G01D02*
Y382723D01*
G01X1261623Y454334D02*
X1259223D01*
G01X1270963Y458012D02*
X1268858D01*
X1267540Y459330D01*
G01X1270963Y456044D02*
X1269323D01*
X1267493Y454214D01*
G01D02*
X1266325D01*
X1266205Y454334D01*
X1264773D01*
G01Y450334D02*
X1266547D01*
X1267836Y449045D01*
G01D02*
X1269213Y450422D01*
Y453488D01*
X1269801Y454076D01*
X1270963D01*
G01X1267540Y459330D02*
X1266544Y458334D01*
X1264773D01*
G01X1256458Y558287D02*
Y562137D01*
G01X1263108Y854487D02*
X1268457D01*
G01D02*
X1270915Y852029D01*
X1273680D01*
G01X1263108Y859487D02*
X1268457D01*
G01D02*
X1273692D01*
G01X1259368Y854487D02*
Y859487D01*
G01Y864487D02*
Y859487D01*
G01X1269629Y848124D02*
X1271365D01*
X1271386Y848145D01*
X1273596D01*
G01X1263108Y879487D02*
X1268457D01*
G01D02*
X1273692D01*
G01X1263108Y869487D02*
X1268457D01*
G01D02*
X1273692D01*
G01X1263108Y864487D02*
X1268457D01*
G01D02*
X1273692D01*
G01X1263108Y874487D02*
X1268457D01*
G01D02*
X1273692D01*
G01X1259368Y884487D02*
Y879487D01*
G01D02*
Y874487D01*
G01D02*
Y869487D01*
G01D02*
Y864487D01*
G01X1263108Y889487D02*
X1268457D01*
G01D02*
X1273692D01*
G01X1263108Y884487D02*
X1268457D01*
G01D02*
X1273692D01*
G01X1261619Y894866D02*
X1261616Y894863D01*
X1256938D01*
G01X1261622Y898442D02*
Y894869D01*
X1261619Y894866D01*
G01X1259368Y889487D02*
Y884487D01*
G01X1256938Y894863D02*
Y889987D01*
X1257438Y889487D01*
X1259368D01*
G01X1261622Y901592D02*
Y907067D01*
G01D02*
X1265083Y910528D01*
X1272627D01*
X1274878Y908277D01*
G01X1267792Y905324D02*
X1270586D01*
G01X1267921Y1134729D02*
Y1137129D01*
G01X1263921D02*
Y1134729D01*
G01X1257999Y1153242D02*
Y1160674D01*
X1257273Y1161400D01*
X1256373D01*
G01X1257999Y1153242D02*
Y1146095D01*
X1258023Y1146071D01*
G01D02*
X1254729D01*
X1254200Y1146600D01*
G01X1263921Y1140279D02*
X1267921D01*
G01X1259921D02*
X1263921D01*
G01X1267921D02*
X1269741Y1142099D01*
Y1146842D01*
G01X1268593Y1157544D02*
X1269741Y1156396D01*
Y1146842D01*
G01X1266718Y1142666D02*
X1266274D01*
X1266246Y1142638D01*
X1257246D01*
X1255921Y1141313D01*
Y1140279D01*
G01X1266887Y1146842D02*
Y1142835D01*
X1266718Y1142666D01*
G01X1256373Y1161400D02*
Y1162500D01*
X1257999Y1164126D01*
Y1167808D01*
G01X1268587Y1175090D02*
Y1173978D01*
X1268104Y1173495D01*
Y1171120D01*
G01X1267104Y1167768D02*
X1268104Y1168768D01*
Y1171120D01*
G01X1269741Y1163968D02*
Y1167159D01*
X1269132Y1167768D01*
X1267104D01*
G01X1268593Y1157544D02*
X1266329D01*
X1264374Y1159499D01*
Y1170540D01*
X1264954Y1171120D01*
G01X1255439Y1167808D02*
Y1172008D01*
G01D02*
Y1172461D01*
X1254000Y1173900D01*
Y1180342D01*
X1255628Y1181970D01*
G01X1260558Y1167808D02*
Y1173670D01*
X1259802Y1174426D01*
G01X1256218Y1175987D02*
X1256617D01*
X1257600Y1176970D01*
Y1184300D01*
X1258350Y1185050D01*
X1259644D01*
G01X1271256Y1185205D02*
X1268615D01*
G01X1262605Y1187215D02*
X1264615Y1185205D01*
G01X1268615Y1182055D02*
X1264615D01*
G01X1264587Y1178240D02*
X1262799D01*
X1262298Y1178741D01*
Y1180175D01*
G01D02*
Y1181255D01*
X1263098Y1182055D01*
X1264615D01*
G01X1264587Y1175090D02*
X1268587D01*
G01X1259802Y1174426D02*
X1259800Y1174428D01*
Y1181744D01*
X1259644Y1181900D01*
G01X1255628Y1185120D02*
Y1188345D01*
G01X1268573Y1198569D02*
Y1201041D01*
X1268571Y1201043D01*
G01D02*
X1268575Y1201047D01*
Y1203443D01*
G01X1264575Y1201043D02*
Y1201151D01*
G01D02*
X1264573Y1201149D01*
Y1198569D01*
G01X1264575Y1201151D02*
Y1203443D01*
G01X1260535Y1203448D02*
Y1200817D01*
X1261538Y1199814D01*
G01X1255296Y1196056D02*
X1256015Y1195337D01*
Y1192376D01*
G01X1260800Y1191096D02*
Y1193716D01*
X1260771Y1193745D01*
G01Y1196895D02*
X1260688D01*
X1259266Y1198317D01*
Y1199486D01*
X1256752Y1202000D01*
X1255485D01*
G01D02*
Y1206419D01*
X1255916Y1206850D01*
Y1209789D01*
X1257411Y1211284D01*
G01X1265338Y1214986D02*
Y1215339D01*
X1263449Y1217228D01*
G01D02*
X1262140Y1218537D01*
X1260867D01*
G01X1263696Y1221364D02*
X1264644D01*
X1266113Y1219895D01*
G01D02*
X1268166Y1217842D01*
Y1217814D01*
G01X1260535Y1206598D02*
Y1207970D01*
X1258028Y1210477D01*
Y1210667D01*
X1257411Y1211284D01*
G01X1272351Y1230750D02*
X1271899D01*
X1269354Y1228205D01*
Y1227022D01*
G01X1270995Y1220643D02*
Y1221563D01*
X1269388Y1223170D01*
G01D02*
X1268365Y1224193D01*
X1266525D01*
G01X1257110Y1523458D02*
Y1527295D01*
X1257071Y1527334D01*
G01X1260221D02*
X1262891D01*
G01X1257071Y1539334D02*
X1254275D01*
G01X1257110Y1543558D02*
Y1539373D01*
X1257071Y1539334D01*
G01Y1531334D02*
X1254275D01*
G01X1260221Y1539334D02*
X1267183D01*
G01X1260221Y1531334D02*
X1267333D01*
G01X1260245Y1535385D02*
X1262840D01*
X1262891Y1535334D01*
G01X1281357Y92874D02*
X1286088D01*
G01D02*
Y95018D01*
X1287482Y96412D01*
X1296258D01*
X1297919Y98073D01*
Y98198D01*
G01X1281357Y99961D02*
X1277130D01*
G01X1277180Y95236D02*
X1281357D01*
G01X1285420Y330655D02*
X1289345D01*
G01X1275660Y342635D02*
Y334640D01*
X1279645Y330655D01*
X1285420D01*
G01Y333215D02*
X1289215D01*
X1291000Y335000D01*
X1292500D01*
G01X1279655Y342576D02*
Y334266D01*
X1280706Y333215D01*
X1285420D01*
G01X1272659Y382723D02*
Y384123D01*
X1273659Y385123D01*
G01D02*
X1274653Y386117D01*
Y389013D01*
G01X1280659Y382723D02*
Y385123D01*
G01D02*
Y386599D01*
X1280159Y387099D01*
X1277122D01*
X1276622Y387599D01*
Y389013D01*
G01X1279181Y391572D02*
X1284330D01*
X1284333Y391569D01*
G01D02*
Y384887D01*
X1284659Y384561D01*
Y382723D01*
G01X1280659Y379573D02*
Y377213D01*
X1280699Y377173D01*
G01X1284659Y379573D02*
Y377173D01*
G01X1274436Y377350D02*
X1276659Y379573D01*
G01X1272659D02*
X1272664Y379568D01*
Y377984D01*
X1273298Y377350D01*
X1274436D01*
G01X1281737Y461034D02*
Y458762D01*
X1280987Y458012D01*
X1278837D01*
G01Y456044D02*
X1281727D01*
X1281737Y456034D01*
G01D02*
X1283462Y454309D01*
X1284622D01*
G01Y458309D02*
Y462309D01*
G01D02*
X1283012D01*
X1281737Y461034D01*
G01X1284900Y678800D02*
X1285391D01*
X1286546Y679955D01*
X1290691D01*
X1303022Y667624D01*
X1324075D01*
X1324575Y668124D01*
Y669500D01*
G01X1283400Y719700D02*
X1286234Y722534D01*
X1327391D01*
X1329425Y720500D01*
G01X1298246Y750962D02*
X1294073D01*
X1291687Y748576D01*
X1279539D01*
G01X1298246Y766317D02*
X1289808D01*
X1287067Y763576D01*
X1279539D01*
G01X1298246Y768876D02*
X1289808D01*
X1287008Y766076D01*
X1282539D01*
G01X1298246Y761198D02*
X1290535D01*
X1287913Y758576D01*
X1279539D01*
G01X1282539Y756076D02*
X1288509D01*
X1291072Y758639D01*
X1298246D01*
G01Y753521D02*
X1293132D01*
X1290687Y751076D01*
X1282539D01*
G01Y761076D02*
X1287126D01*
X1289808Y763758D01*
X1298246D01*
G01Y756080D02*
X1292505D01*
X1290001Y753576D01*
X1279539D01*
G01X1285089Y780576D02*
Y776576D01*
G01D02*
X1291604D01*
G01X1285089Y768576D02*
Y772576D01*
G01D02*
X1287924D01*
X1289065Y771435D01*
X1291604D01*
G01X1285089Y784576D02*
X1288604D01*
X1291604Y781576D01*
G01X1287925Y827500D02*
X1285500D01*
G01X1287925Y831500D02*
X1285500D01*
X1281388Y827388D01*
G01X1287925Y823500D02*
X1281777D01*
G01X1287925Y843500D02*
X1285500D01*
G01X1281331Y843331D02*
X1285500Y847500D01*
X1287925D01*
G01X1281269Y835492D02*
X1285277Y839500D01*
X1287925D01*
G01Y835500D02*
X1285500D01*
G01X1287925Y863500D02*
X1285500D01*
G01X1287925Y859500D02*
X1285500D01*
G01X1287925Y855500D02*
X1285500D01*
G01X1287925Y851500D02*
X1285500D01*
G01X1276830Y852029D02*
X1278400D01*
X1279460Y853089D01*
Y854487D01*
G01X1276842Y859487D02*
X1279460D01*
G01X1283025Y848305D02*
X1281289D01*
X1281129Y848145D01*
X1276746D01*
G01X1282055Y857317D02*
X1281313Y856575D01*
X1278344D01*
X1277480Y855711D01*
X1271524D01*
X1270892Y856343D01*
G01X1282055Y857317D02*
X1283264Y858526D01*
Y861016D01*
X1283734Y861486D01*
X1295386D01*
X1299433Y865533D01*
X1303377D01*
X1304409Y864501D01*
X1317028D01*
X1318480Y863049D01*
Y862941D01*
G01X1287925Y867000D02*
X1287425Y867500D01*
X1285500D01*
G01X1276842Y874487D02*
X1279460D01*
G01Y869487D02*
X1276842D01*
G01X1279460D02*
Y870955D01*
X1283907Y875402D01*
X1290668D01*
X1292370Y873700D01*
X1295200D01*
X1299186Y877686D01*
X1302714D01*
X1305000Y875400D01*
X1307500D01*
X1308742Y874158D01*
X1312941D01*
X1313149Y873950D01*
X1316920D01*
X1318480Y872390D01*
G01X1276842Y879487D02*
X1279460D01*
G01Y864487D02*
X1276842D01*
G01X1279460D02*
Y866707D01*
X1281701Y868948D01*
Y871204D01*
X1284475Y873978D01*
X1289791D01*
X1291452Y872317D01*
Y871048D01*
X1292700Y869800D01*
X1294196D01*
X1300296Y875900D01*
X1302599D01*
X1304299Y874200D01*
X1307100D01*
X1308420Y872880D01*
X1312200D01*
X1312690Y872390D01*
X1315330D01*
G01X1287920Y877783D02*
X1285802D01*
X1285302Y877283D01*
G01X1301314Y873484D02*
X1299633D01*
X1294425Y868276D01*
X1292640D01*
X1291416Y869500D01*
X1284381D01*
X1283300Y868419D01*
Y866617D01*
X1282285Y865602D01*
G01X1273264Y895646D02*
X1274264Y896646D01*
Y898591D01*
G01X1276842Y884487D02*
X1279460D01*
G01X1287920Y885783D02*
X1285302D01*
G01X1279299Y898813D02*
X1278682Y897324D01*
X1277004Y895646D01*
G01X1276842Y889487D02*
X1279460D01*
G01X1287920Y881783D02*
X1285302D01*
G01X1282184Y898854D02*
X1280806Y897476D01*
Y891742D01*
X1284623Y887925D01*
X1290570D01*
X1291070Y888425D01*
Y889767D01*
G01X1284655Y898075D02*
Y900000D01*
X1285909Y901254D01*
X1288500D01*
G01X1288155Y898075D02*
X1284655D01*
G01X1280042Y902073D02*
X1279299Y901330D01*
Y898813D01*
G01X1275493Y927068D02*
Y929858D01*
G01X1279493Y927068D02*
Y929858D01*
G01X1272661D02*
Y929821D01*
X1271493Y928653D01*
Y927068D01*
G01X1283493D02*
Y929858D01*
G01X1279493Y923918D02*
X1279693Y923718D01*
Y919800D01*
G01X1279493Y923918D02*
X1275493D01*
G01D02*
X1271493D01*
G01X1283493D02*
X1279493D01*
G01X1279693Y919800D02*
X1281629D01*
X1281929Y919500D01*
X1283925D01*
G01X1271865Y918956D02*
X1273818D01*
X1274670Y919808D01*
G01X1271865Y914949D02*
X1273574D01*
X1274400Y914123D01*
G01X1283451Y933598D02*
X1294701D01*
X1295453Y932846D01*
Y930957D01*
G01X1280301Y933598D02*
X1277509Y936390D01*
Y945251D01*
X1281733Y949475D01*
G01X1296500Y967075D02*
X1290296D01*
X1280078Y977293D01*
Y996627D01*
X1283085Y999634D01*
X1287323D01*
G01X1290792Y961363D02*
Y961788D01*
X1283664Y968916D01*
X1279822D01*
G01X1303900Y1288000D02*
X1299100Y1283200D01*
Y1250174D01*
X1286137Y1237211D01*
Y1100807D01*
X1302496Y1084448D01*
Y1049004D01*
X1306740Y1044760D01*
X1321308D01*
X1324988Y1041080D01*
Y1017412D01*
X1400115Y942285D01*
X1416244D01*
G01X1271921Y1134729D02*
Y1137129D01*
G01X1275921D02*
Y1134856D01*
X1275794Y1134729D01*
G01X1275921Y1140279D02*
X1271921D01*
G01X1279921D02*
X1275921D01*
G01X1271921D02*
X1272301Y1140659D01*
Y1146842D01*
G01D02*
Y1154655D01*
X1275050Y1157404D01*
G01X1273912Y1175138D02*
X1272453D01*
X1271953Y1174638D01*
Y1171120D01*
G01X1272123Y1167768D02*
Y1170950D01*
X1271953Y1171120D01*
G01X1272301Y1163968D02*
Y1167590D01*
X1272123Y1167768D01*
G01X1275103Y1171120D02*
X1276983Y1173000D01*
X1281743D01*
X1282800Y1171943D01*
Y1159700D01*
X1280504Y1157404D01*
X1275050D01*
G01X1275965Y1187232D02*
X1273934Y1185201D01*
G01X1277902Y1185238D02*
X1280602D01*
G01X1273934Y1182051D02*
X1277865D01*
X1277902Y1182088D01*
G01D02*
X1279894D01*
X1280395Y1181587D01*
Y1180235D01*
G01D02*
Y1179038D01*
X1279645Y1178288D01*
X1277912D01*
G01Y1175138D02*
X1273912D01*
G01X1272573Y1198569D02*
Y1201011D01*
X1272541Y1201043D01*
G01D02*
X1272575Y1201077D01*
Y1203443D01*
G01X1276573Y1198569D02*
Y1200817D01*
X1276575Y1200819D01*
Y1201039D01*
G01D02*
Y1203443D01*
G01X1280575D02*
Y1200969D01*
G01D02*
Y1198571D01*
X1280573Y1198569D01*
G01X1274446Y1228226D02*
X1274726D01*
X1276652Y1226300D01*
G01X1274446Y1228226D02*
Y1228864D01*
X1272560Y1230750D01*
X1272351D01*
G01X1273824Y1223472D02*
Y1224427D01*
X1272235Y1226016D01*
G01X1302139Y26325D02*
X1304422Y28608D01*
X1306994D01*
G01X1301919Y98198D02*
X1297919D01*
G01X1302025Y259535D02*
Y256303D01*
G01X1296697Y265701D02*
X1298025Y264373D01*
Y262685D01*
G01X1301784Y265896D02*
Y264086D01*
X1302025Y263845D01*
Y262685D01*
G01X1304273Y281982D02*
X1302265Y279974D01*
Y277477D01*
G01X1298332Y281716D02*
X1300297Y279751D01*
Y277477D01*
G01Y269603D02*
Y267575D01*
X1299601Y266879D01*
X1297875D01*
X1296697Y265701D01*
G01X1302265Y269603D02*
Y267599D01*
X1301784Y267118D01*
Y265896D01*
G01X1297078Y284908D02*
X1301078D01*
G01D02*
Y283104D01*
X1299690Y281716D01*
X1298332D01*
G01X1295425Y330000D02*
Y328660D01*
X1295906Y328179D01*
X1297868D01*
X1298575Y327472D01*
Y326500D01*
G01Y333500D02*
X1299575D01*
X1301249Y335174D01*
X1308671D01*
X1313103Y339606D01*
G01X1298575Y330000D02*
X1301575Y333000D01*
X1310559D01*
X1312240Y334681D01*
G01X1295425Y330000D02*
X1294001D01*
X1293001Y329000D01*
X1291000D01*
X1289345Y330655D01*
G01X1295425Y333500D02*
Y334624D01*
X1296107Y335306D01*
X1297839D01*
X1298575Y336042D01*
Y337000D01*
G01X1295425Y333500D02*
X1293925Y335000D01*
X1292500D01*
G01X1319471Y350253D02*
X1318360D01*
X1316206Y352407D01*
Y356195D01*
X1311745Y360656D01*
X1299812D01*
X1294080Y354924D01*
Y349820D01*
G01X1295410Y373479D02*
Y371076D01*
G01Y376629D02*
X1291410D01*
Y376830D01*
G01X1287437Y379429D02*
Y375754D01*
G01X1298346Y379028D02*
X1299410Y377964D01*
Y376629D01*
G01X1293048Y379088D02*
X1291776D01*
X1291410Y378722D01*
Y376830D01*
G01X1295602Y383732D02*
Y381642D01*
X1293048Y379088D01*
G01X1308410Y379591D02*
X1306782Y381219D01*
X1303031D01*
X1301508Y382742D01*
Y383732D01*
G01X1293634D02*
Y383478D01*
X1293277Y383121D01*
X1291129D01*
X1287437Y379429D01*
G01X1297571Y383732D02*
Y379803D01*
X1298346Y379028D01*
G01X1299466Y466409D02*
X1302266D01*
G01X1295163Y472606D02*
X1295417D01*
X1295774Y472249D01*
Y470101D01*
X1299466Y466409D01*
G01X1302266Y474382D02*
Y470382D01*
G01X1299807Y472020D02*
Y470748D01*
X1300173Y470382D01*
X1302266D01*
G01X1295163Y474574D02*
X1297253D01*
X1299807Y472020D01*
G01X1302266Y478382D02*
X1300931D01*
X1299867Y477318D01*
G01X1295163Y476543D02*
X1299092D01*
X1299867Y477318D01*
G01X1302266Y487382D02*
X1299304D01*
G01X1302266D02*
Y489224D01*
X1302841Y489799D01*
X1311329D01*
X1340750Y477612D01*
X1362739Y455623D01*
Y426621D01*
X1360719Y424601D01*
G01X1295163Y480480D02*
X1296153D01*
X1297676Y482003D01*
Y485754D01*
X1299304Y487382D01*
G01X1289811Y677612D02*
X1304223Y663200D01*
X1323975D01*
X1324575Y663800D01*
Y665500D01*
G01Y649500D02*
Y648115D01*
X1323439Y646979D01*
X1311593D01*
X1298963Y659609D01*
G01X1289317Y706932D02*
X1325267D01*
X1327000Y705199D01*
Y704970D01*
X1327470Y704500D01*
X1329425D01*
G01X1291604Y781576D02*
Y780215D01*
X1294873Y776946D01*
X1298246D01*
G01X1291604Y776576D02*
X1294186Y773994D01*
X1298246D01*
G01X1291604Y771435D02*
X1298246D01*
G01X1298720Y802762D02*
Y798975D01*
G01D02*
X1298641Y798896D01*
Y796321D01*
G01X1298909Y815517D02*
X1299248D01*
X1302140Y812625D01*
G01X1305412Y807880D02*
X1305232D01*
X1302140Y810972D01*
Y812625D01*
G01X1298909Y818667D02*
Y821155D01*
X1302501Y824747D01*
G01D02*
X1304566Y826812D01*
Y840922D01*
X1309263Y845619D01*
X1316906D01*
X1318480Y847193D01*
G01X1297667Y832150D02*
X1291725D01*
X1291075Y831500D01*
G01Y827500D02*
X1293500D01*
G01X1291075Y819500D02*
Y823500D01*
G01X1296770Y828775D02*
X1295666Y826111D01*
X1293055Y823500D01*
X1291075D01*
G01X1299990Y847500D02*
X1291075D01*
G01X1299990D02*
X1304422Y851932D01*
X1316920D01*
X1318480Y853492D01*
G01X1291075Y843500D02*
X1293500D01*
G01X1291075Y835500D02*
X1293500D01*
G01X1291075Y839500D02*
X1296687D01*
G01X1291075Y851500D02*
X1293500D01*
G01X1291075Y863500D02*
X1294000D01*
G01X1312000Y856642D02*
X1301816D01*
X1301282Y857176D01*
X1299567D01*
X1297891Y855500D01*
X1295943D01*
G01D02*
X1291075D01*
G01X1315330Y862941D02*
X1300484D01*
X1299855Y862312D01*
G01D02*
X1297043Y859500D01*
X1291075D01*
G01X1299488Y868440D02*
X1300428Y867500D01*
X1302296D01*
X1304499Y869703D01*
X1307985D01*
X1309026Y868662D01*
X1312916D01*
X1313494Y869240D01*
X1315330D01*
G01X1291075Y867000D02*
X1296754D01*
X1298194Y868440D01*
X1299488D01*
G01X1295758Y877783D02*
X1291070D01*
G01X1295758D02*
X1297268Y879293D01*
X1303236D01*
X1303714Y879771D01*
X1311827D01*
X1312909Y878689D01*
X1315330D01*
G01X1301314Y873484D02*
X1302040Y872758D01*
X1306614D01*
X1308597Y870775D01*
X1310535D01*
G01X1318480Y888138D02*
X1316920Y889698D01*
X1314052D01*
X1311140Y892610D01*
X1304243D01*
X1299445Y897408D01*
X1295172D01*
X1294098Y898482D01*
Y905429D01*
X1294264Y905595D01*
G01X1315330Y884988D02*
X1310000D01*
X1308407Y886581D01*
X1304581D01*
X1301379Y889783D01*
G01D02*
X1291070D01*
Y889767D01*
G01X1292000Y894925D02*
X1291129Y894054D01*
Y892267D01*
G01X1315330Y881839D02*
X1313923Y883246D01*
X1309500D01*
X1307746Y885000D01*
X1303500D01*
X1302717Y885783D01*
X1295799D01*
G01D02*
X1291070D01*
G01X1301482Y881783D02*
X1291070D01*
G01X1301482D02*
X1306951D01*
X1307234Y881500D01*
X1312524D01*
X1313775Y880249D01*
X1316920D01*
X1318480Y878689D01*
G01X1301657Y899129D02*
X1305536Y895250D01*
X1311368D01*
X1315330Y891288D01*
G01X1292000Y898075D02*
X1288155D01*
G01X1288500Y901254D02*
Y904669D01*
G01X1292500Y930957D02*
Y928000D01*
G01X1298000Y923075D02*
Y925500D01*
X1295453Y928047D01*
G01X1302000Y923075D02*
X1298000D01*
G01X1295453Y928047D02*
Y930957D01*
G01X1291059Y913331D02*
Y917000D01*
G01X1287075Y919500D02*
X1290925D01*
G01X1291059Y917000D02*
X1290925Y917134D01*
Y919500D01*
G01X1302000Y919925D02*
Y917000D01*
G01X1300882Y930989D02*
X1304949D01*
G01X1300882Y934139D02*
Y937144D01*
G01D02*
X1303644D01*
X1306466Y939966D01*
Y948224D01*
G01X1289547Y938043D02*
Y941000D01*
G01X1289500Y943925D02*
X1291576D01*
X1292500Y943001D01*
Y938043D01*
G01X1289547Y941000D02*
X1289500Y941047D01*
Y943925D01*
G01X1301348Y948224D02*
Y950848D01*
X1301730Y951230D01*
X1308662D01*
X1309500Y950392D01*
Y940257D01*
X1313152Y936605D01*
G01X1300500Y960000D02*
Y963925D01*
G01X1301348Y956098D02*
Y959152D01*
X1300500Y960000D01*
G01X1296500Y967075D02*
Y969158D01*
X1297558Y970216D01*
G01X1306994Y28608D02*
X1315239D01*
X1318859Y32228D01*
Y39898D01*
G01X1302785Y31168D02*
X1306994D01*
G01D02*
X1315069D01*
X1317039Y33138D01*
Y37718D01*
X1314859Y39898D01*
G01X1314887Y45448D02*
X1314859Y45420D01*
Y43048D01*
G01X1322853Y43093D02*
X1321890D01*
X1318859Y40062D01*
Y39898D01*
G01X1310853Y43093D02*
X1311836D01*
X1314859Y40070D01*
Y39898D01*
G01X1307423Y97475D02*
X1304923D01*
G01X1316826Y99259D02*
X1313270D01*
X1311904Y100625D01*
G01X1316277Y112083D02*
Y112402D01*
X1318363Y114488D01*
G01X1307423Y105087D02*
Y100625D01*
G01X1311904D02*
X1307423D01*
G01X1314627Y168713D02*
Y171523D01*
G01X1317777Y168713D02*
X1322958D01*
X1323006Y168665D01*
G01X1316716Y179897D02*
Y176034D01*
X1320085Y172665D01*
G01X1320022Y179904D02*
Y180204D01*
X1318360Y181866D01*
X1316716D01*
G01Y183834D02*
X1319912D01*
G01X1316716Y185803D02*
Y189278D01*
X1317623Y190185D01*
X1319432D01*
G01X1318832Y196620D02*
Y195400D01*
X1318264Y194832D01*
X1314891D01*
X1314157Y194098D01*
Y192490D01*
G01X1323006Y196665D02*
X1318877D01*
X1318832Y196620D01*
G01X1314157Y192490D02*
Y188362D01*
G01X1315682Y196620D02*
X1311661D01*
X1310115Y195074D01*
Y192300D01*
G01X1316327Y209229D02*
X1317049D01*
X1317637Y208641D01*
Y203429D01*
X1320202Y200864D01*
G01X1316327Y211197D02*
X1317780D01*
X1320225Y208752D01*
Y207037D01*
G01X1316327Y213166D02*
X1318013D01*
X1318724Y212455D01*
X1320291D01*
G01X1316327Y217103D02*
X1318340D01*
X1323101Y221864D01*
G01X1306800Y266114D02*
Y264678D01*
X1306025Y263903D01*
Y262685D01*
G01X1304233Y269603D02*
Y268681D01*
X1306800Y266114D01*
G01X1305078Y284908D02*
Y282787D01*
X1304273Y281982D01*
G01X1319471Y342379D02*
X1315876D01*
X1313103Y339606D01*
G01X1312240Y334681D02*
Y336240D01*
X1313898Y337898D01*
X1315411Y338911D01*
X1317305Y340805D01*
X1319471D01*
G01X1322424Y353206D02*
Y355150D01*
X1318063Y359511D01*
G01D02*
X1316903Y360671D01*
Y365166D01*
G01X1312410Y376631D02*
X1308410D01*
G01Y379591D02*
Y376631D01*
G01X1320903Y365166D02*
X1316903D01*
G01X1312410Y373481D02*
Y371928D01*
X1311283Y370801D01*
G01X1313899Y467560D02*
X1312640D01*
X1309954Y470246D01*
X1309400Y471583D01*
Y472801D01*
X1307819Y474382D01*
G01X1317049Y471560D02*
Y467560D01*
G01D02*
X1319474D01*
G01X1307819Y474382D02*
X1305416D01*
G01X1317049Y479560D02*
Y475560D01*
G01X1319974D02*
X1317049D01*
G01X1321425Y594500D02*
X1318600D01*
X1316125Y596975D01*
Y638125D01*
X1319000Y641000D01*
G01X1305836Y660009D02*
X1324075D01*
X1324575Y659509D01*
Y657500D01*
G01X1313979Y677726D02*
X1316265Y675440D01*
X1327485D01*
X1329425Y673500D01*
G01X1313000Y793575D02*
Y796000D01*
G01X1317000Y793575D02*
Y799000D01*
G01Y790425D02*
Y788000D01*
G01X1313000Y790425D02*
Y788000D01*
G01X1317000Y809575D02*
Y817500D01*
G01X1313000Y814200D02*
Y809575D01*
G01X1321629Y834595D02*
X1320069Y833035D01*
Y830039D01*
X1313000Y822970D01*
Y814200D01*
G01X1317000Y806425D02*
Y804000D01*
G01X1313000Y806425D02*
Y804000D01*
G01X1318480Y831445D02*
X1316906Y829871D01*
G01X1321629Y827000D02*
X1317000Y822371D01*
Y817500D01*
G01X1318480Y834595D02*
X1316906Y833021D01*
G01X1312396Y840894D02*
X1310971Y842319D01*
G01X1315330Y834595D02*
X1313756Y833021D01*
G01X1315330Y837744D02*
X1313756Y836170D01*
G01X1318480Y840894D02*
X1316906Y839320D01*
G01X1312037Y847193D02*
X1310555Y848675D01*
G01X1318480Y837744D02*
X1316906Y836170D01*
G01X1315330Y844044D02*
X1313756Y842470D01*
G01X1318480Y850343D02*
X1316906Y848769D01*
G01X1315330Y859792D02*
X1313756Y858218D01*
G01X1316906Y855068D02*
X1318480Y856642D01*
G01X1315330Y853492D02*
X1313756Y855066D01*
G01X1318480Y859792D02*
X1316906Y858218D01*
G01X1315330Y850343D02*
X1313756Y848769D01*
G01X1315330Y866091D02*
X1311762D01*
X1310994Y866859D01*
G01X1318480Y875540D02*
X1316920Y877100D01*
X1311884D01*
X1311395Y877589D01*
X1309753D01*
G01X1315330Y875540D02*
X1309086D01*
X1307092Y877534D01*
X1305740D01*
G01X1310535Y870775D02*
X1310560Y870800D01*
X1316920D01*
X1318480Y869240D01*
G01Y884988D02*
X1316920Y886548D01*
X1311398D01*
X1310659Y887287D01*
X1310186D01*
X1308220Y889253D01*
G01X1315330Y888138D02*
X1312284D01*
X1311061Y889361D01*
G01X1304949Y928546D02*
X1307000Y926495D01*
Y905622D01*
X1311845Y900777D01*
Y897922D01*
X1315330Y894437D01*
G01X1318480D02*
X1320040Y895997D01*
Y898460D01*
X1316000Y902500D01*
Y903500D01*
X1314500Y905000D01*
G01Y911500D02*
Y919925D01*
G01X1324779Y894437D02*
X1326339Y895997D01*
Y901661D01*
X1320500Y907500D01*
X1318500D01*
X1314500Y911500D01*
G01X1309103Y917000D02*
Y906964D01*
X1318480Y897587D01*
G01X1317000Y930925D02*
Y928500D01*
X1316000Y927500D01*
X1313000D01*
X1311500Y926000D01*
Y908000D01*
X1314500Y905000D01*
G01X1318500Y919925D02*
Y917008D01*
X1320208Y915300D01*
X1322500D01*
G01X1304949Y930989D02*
Y928546D01*
G01X1309103Y930989D02*
Y917000D01*
G01X1318500Y923075D02*
X1319675D01*
X1321500Y924900D01*
Y930483D01*
X1320890Y931093D01*
Y940190D01*
X1323406Y942706D01*
Y964855D01*
X1320889Y967372D01*
Y977476D01*
X1314597Y983768D01*
Y992038D01*
X1315927Y993368D01*
X1327793D01*
X1329503Y991658D01*
Y991088D01*
G01X1314500Y923075D02*
Y924972D01*
X1313867Y925605D01*
G01X1313152Y930989D02*
X1309103D01*
G01X1313152Y936605D02*
Y934139D01*
G01X1317000Y937925D02*
X1315145D01*
X1312575Y940495D01*
Y943974D01*
G01X1317000Y934075D02*
Y937925D01*
G01X1315441Y948063D02*
Y946840D01*
X1312575Y943974D01*
G01X1306466Y956098D02*
Y958466D01*
X1307000Y959000D01*
Y960500D01*
G01D02*
Y963925D01*
G01X1315000D02*
X1315441Y963484D01*
Y960000D01*
G01D02*
Y955937D01*
G01X1311000Y967075D02*
Y970124D01*
G01X1315000Y967075D02*
X1311000D01*
G01X1331073Y30483D02*
X1330516Y31040D01*
X1329366D01*
X1328003Y32403D01*
G01D02*
X1326768Y31168D01*
X1324120D01*
G01Y28608D02*
X1327043D01*
X1328318Y27333D01*
G01D02*
X1329117Y26534D01*
X1331001D01*
G01X1334151D02*
X1336551D01*
G01X1331096Y22627D02*
X1324235D01*
X1324120Y22742D01*
G01D02*
Y25754D01*
G01X1334223Y30483D02*
X1336623D01*
G01X1318859Y45448D02*
Y43048D01*
G01X1320566Y107921D02*
Y103621D01*
G01X1323006Y168665D02*
Y172665D01*
G01X1320085D02*
X1323006D01*
G01Y176665D02*
Y180665D01*
G01D02*
X1320783D01*
X1320022Y179904D01*
G01Y178560D02*
Y179904D01*
G01X1319912Y183834D02*
X1322175D01*
X1323006Y184665D01*
G01X1319432Y190185D02*
Y191730D01*
X1320367Y192665D01*
X1323006D01*
G01X1326156D02*
X1328799D01*
G01X1326156Y196665D02*
X1328799D01*
G01X1326156Y188665D02*
X1328181D01*
X1328912Y187934D01*
Y186778D01*
G01D02*
Y185398D01*
X1328179Y184665D01*
X1326156D01*
G01X1320202Y200864D02*
X1323101D01*
G01Y204864D02*
Y208864D01*
G01X1320225Y207037D02*
X1322052Y208864D01*
X1323101D01*
G01Y212864D02*
X1322692Y212455D01*
X1320291D01*
G01X1326251Y208864D02*
X1328831D01*
G01X1323098Y225719D02*
Y221867D01*
X1323101Y221864D01*
G01X1325100Y228631D02*
X1323098Y226629D01*
Y225719D01*
G01X1332359Y322685D02*
X1330298Y324746D01*
Y329978D01*
G01X1323998Y353206D02*
Y357328D01*
X1325007Y358337D01*
Y360259D01*
G01D02*
Y365174D01*
G01X1331922Y359836D02*
X1333447Y358311D01*
Y353206D01*
G01X1329064Y365174D02*
X1325007D01*
G01X1319474Y467560D02*
X1320521Y468607D01*
X1322931D01*
G01Y471560D02*
X1320974D01*
X1319974Y472560D01*
Y475560D01*
G01X1335899Y474560D02*
Y472060D01*
X1335399Y471560D01*
X1330017D01*
G01Y474513D02*
X1332974D01*
G01D02*
X1333021Y474560D01*
X1335899D01*
G01X1329425Y558500D02*
Y557288D01*
X1328925Y556788D01*
X1326993D01*
G01D02*
X1325075D01*
X1324575Y557288D01*
Y558500D01*
G01Y562500D02*
X1327000D01*
G01X1324575Y566500D02*
Y562500D01*
G01X1327000D02*
X1329425D01*
G01Y566500D02*
X1328352D01*
X1326946Y567906D01*
G01X1332575Y558500D02*
X1338000D01*
X1343992Y564492D01*
X1346738D01*
G01X1332575Y562500D02*
X1338000D01*
G01X1332575Y566500D02*
X1337328D01*
X1339289Y568461D01*
G01X1324575Y578500D02*
X1327000D01*
G01X1324575Y582500D02*
Y578500D01*
G01X1327000D02*
X1329425D01*
G01Y574500D02*
X1328197D01*
X1327043Y573346D01*
G01D02*
X1325889Y574500D01*
X1324575D01*
G01X1329425Y582500D02*
X1328326D01*
X1327000Y583826D01*
G01X1332575Y578500D02*
X1339999D01*
X1340838Y579339D01*
X1342053D01*
G01X1332575Y574500D02*
X1333835Y575760D01*
X1339759D01*
X1340779Y576780D01*
X1346533D01*
G01X1324575Y586500D02*
X1329425D01*
G01D02*
Y588000D01*
X1329925Y588500D01*
X1338155D01*
X1340522Y586133D01*
G01X1332575Y582500D02*
X1340000D01*
X1340602Y581898D01*
X1346533D01*
G01X1329425Y594500D02*
X1327000D01*
G01X1350984Y589968D02*
X1347086D01*
X1341554Y595500D01*
X1337000D01*
X1336000Y596500D01*
X1329925D01*
X1329425Y596000D01*
Y594500D01*
G01X1327000D02*
X1324575D01*
G01Y590500D02*
X1329425D01*
G01D02*
Y592000D01*
X1329925Y592500D01*
X1341000D01*
X1343000Y590500D01*
Y590458D01*
G01X1332575Y613000D02*
X1333880D01*
X1335841Y614961D01*
X1339289D01*
G01X1324575Y609000D02*
X1327000D01*
G01X1324575Y613000D02*
Y609000D01*
G01X1327000D02*
X1329425D01*
G01Y613000D02*
X1327000D01*
G01X1324575Y605000D02*
X1327000D01*
G01D02*
X1329425D01*
G01X1332575Y609000D02*
X1338000D01*
G01X1332575Y605000D02*
X1338000D01*
X1344192Y611192D01*
X1346738D01*
G01X1332575Y629000D02*
X1340000D01*
X1340602Y628398D01*
X1346533D01*
G01X1329425Y629000D02*
X1327000D01*
G01X1324575Y625000D02*
X1325943D01*
X1327003Y623940D01*
G01X1324575Y629000D02*
Y625000D01*
G01X1327003Y623940D02*
X1328063Y625000D01*
X1329425D01*
G01X1324575Y621000D02*
X1327000D01*
G01D02*
X1329425D01*
G01X1332575Y625000D02*
X1339999D01*
X1340838Y625839D01*
X1342053D01*
G01X1332575Y621000D02*
X1333835Y622260D01*
X1335532D01*
G01X1324575Y633000D02*
X1329425D01*
G01D02*
Y634500D01*
X1329925Y635000D01*
X1338155D01*
X1340522Y632633D01*
G01X1332575Y649500D02*
X1338000D01*
X1343992Y655492D01*
X1346738D01*
G01X1324575Y641000D02*
X1327000D01*
G01X1350984Y636468D02*
X1347086D01*
X1341554Y642000D01*
X1337000D01*
X1336000Y643000D01*
X1329925D01*
X1329425Y642500D01*
Y641000D01*
G01X1327000D02*
X1329425D01*
G01X1321425D02*
Y645000D01*
G01X1319000Y641000D02*
X1321425D01*
G01X1324575Y645000D02*
X1325947D01*
X1327011Y646064D01*
G01X1324575Y637000D02*
X1329425D01*
G01D02*
Y638500D01*
X1329925Y639000D01*
X1341000D01*
X1343000Y637000D01*
Y636958D01*
G01X1329425Y649500D02*
X1324575D01*
G01X1329425Y665500D02*
X1324575D01*
G01X1332575Y657500D02*
X1337328D01*
X1339289Y659461D01*
G01X1324575Y653500D02*
X1329425D01*
G01X1324575Y657500D02*
Y653500D01*
G01X1332575Y665500D02*
X1333835Y666760D01*
X1339759D01*
X1340779Y667780D01*
X1346533D01*
G01X1329425Y657500D02*
X1327000D01*
G01X1332575Y653500D02*
X1338000D01*
G01X1332575Y673500D02*
X1340000D01*
X1340602Y672898D01*
X1346533D01*
G01X1332575Y669500D02*
X1339999D01*
X1340838Y670339D01*
X1342053D01*
G01X1324575Y677500D02*
X1329425D01*
G01D02*
Y679000D01*
X1329925Y679500D01*
X1338155D01*
X1340522Y677133D01*
G01X1324575Y681500D02*
X1329425D01*
G01D02*
Y683000D01*
X1329925Y683500D01*
X1341000D01*
X1343000Y681500D01*
Y681458D01*
G01X1329425Y669500D02*
X1324575D01*
G01D02*
Y673500D01*
G01X1329425Y696500D02*
X1328000D01*
X1327000Y695500D01*
G01D02*
X1326000Y696500D01*
X1324575D01*
G01Y704500D02*
Y700500D01*
G01X1329425D02*
X1327000D01*
G01D02*
X1324575D01*
G01X1332575Y696500D02*
X1338000D01*
X1343992Y702492D01*
X1346738D01*
G01X1332575Y700500D02*
X1338000D01*
G01X1329425Y685500D02*
X1327000D01*
G01X1350984Y680968D02*
X1347086D01*
X1343000Y685054D01*
Y686771D01*
X1341414Y688357D01*
X1330782D01*
X1329425Y687000D01*
Y685500D01*
G01X1327000D02*
X1324575D01*
G01X1321425D02*
X1319000D01*
G01X1329425Y712500D02*
X1328000D01*
X1327000Y711500D01*
G01D02*
X1326000Y712500D01*
X1324575D01*
G01X1332575Y704500D02*
X1337328D01*
X1339289Y706461D01*
G01X1332575Y716500D02*
X1339999D01*
X1340838Y717339D01*
X1342053D01*
G01X1332575Y712500D02*
X1333835Y713760D01*
X1339759D01*
X1340779Y714780D01*
X1346533D01*
G01X1324575Y720500D02*
Y716500D01*
G01X1329425D02*
X1327000D01*
G01D02*
X1324575D01*
G01X1332575Y720500D02*
X1340000D01*
X1340602Y719898D01*
X1346533D01*
G01X1329425Y732500D02*
X1327000D01*
G01X1350984Y727968D02*
X1347086D01*
X1341554Y733500D01*
X1337000D01*
X1336000Y734500D01*
X1329925D01*
X1329425Y734000D01*
Y732500D01*
G01X1327000D02*
X1324575D01*
G01X1319000D02*
X1321425D01*
G01D02*
X1321395Y732530D01*
Y736464D01*
G01X1329425Y724500D02*
X1324575D01*
G01X1329425D02*
Y726000D01*
X1329925Y726500D01*
X1338155D01*
X1340522Y724133D01*
G01X1329425Y728500D02*
X1324575D01*
G01X1329425D02*
Y730000D01*
X1329925Y730500D01*
X1341000D01*
X1343000Y728500D01*
Y728458D01*
G01X1330295Y746328D02*
X1328037D01*
X1323403Y750962D01*
X1321278D01*
G01X1339218Y741675D02*
X1333472D01*
X1330295Y744852D01*
Y746328D01*
G01X1324545Y736464D02*
X1326970D01*
G01X1336661Y745675D02*
X1334287D01*
X1331034Y748928D01*
X1329978D01*
X1325385Y753521D01*
X1321278D01*
G01Y748010D02*
X1322722D01*
X1333057Y737675D01*
X1336661D01*
G01X1321278Y766317D02*
X1332648D01*
X1333290Y765675D01*
X1336450D01*
G01X1339218Y757675D02*
X1334071D01*
G01D02*
X1332117D01*
X1328594Y761198D01*
X1321278D01*
G01Y758639D02*
X1326961D01*
X1331925Y753675D01*
X1336661D01*
G01X1339218Y761675D02*
X1332169D01*
X1330086Y763758D01*
G01D02*
X1321278D01*
G01X1339218Y749675D02*
X1335967D01*
X1334431Y751211D01*
X1330412D01*
X1330295Y751328D01*
G01D02*
X1325543Y756080D01*
X1321278D01*
G01Y773994D02*
X1325426D01*
X1327924Y776492D01*
X1331563D01*
X1336746Y781675D01*
G01X1345226Y777675D02*
X1339218D01*
X1335548Y774005D01*
X1330687D01*
X1328117Y771435D01*
X1321278D01*
G01X1339218Y769675D02*
X1337416D01*
X1336617Y768876D01*
X1334340D01*
G01D02*
X1321278D01*
G01X1329000Y793575D02*
Y796000D01*
G01X1321000Y793575D02*
Y796000D01*
G01X1325000Y793575D02*
Y799000D01*
G01X1333000Y793575D02*
Y799000D01*
G01Y790425D02*
Y788000D01*
G01X1329000Y790425D02*
Y788000D01*
G01X1321000Y790425D02*
Y788000D01*
G01X1325000Y790425D02*
Y788000D01*
G01Y817500D02*
Y809575D01*
G01X1321000Y814200D02*
Y809575D01*
G01X1327929Y834595D02*
X1326369Y833035D01*
Y828975D01*
X1321000Y823606D01*
Y814200D01*
G01X1333000Y817500D02*
Y809575D01*
G01X1329000Y814200D02*
Y809575D01*
G01X1331078Y831445D02*
X1330000Y830367D01*
Y815200D01*
X1329000Y814200D01*
G01Y806425D02*
Y804000D01*
G01X1325000Y806425D02*
Y804000D01*
G01X1333000Y806425D02*
Y804000D01*
G01X1321000Y806425D02*
Y804000D01*
G01X1334228Y827772D02*
X1335500Y826500D01*
X1335803D01*
G01X1327929Y831445D02*
Y820429D01*
X1325000Y817500D01*
G01X1334228Y834595D02*
X1332649Y833016D01*
Y826850D01*
X1333000Y826499D01*
Y817500D01*
G01X1324779Y831445D02*
X1323205Y829871D01*
G01X1327929Y840894D02*
X1326355Y839320D01*
G01X1331078Y834595D02*
X1329504Y833021D01*
G01X1334228Y844044D02*
X1332654Y842470D01*
G01X1331078Y847193D02*
X1329504Y845619D01*
G01X1334228Y847193D02*
X1332654Y845619D01*
G01X1327929Y837744D02*
X1326355Y836170D01*
G01X1331078Y837744D02*
X1329504Y836170D01*
G01X1331078Y840894D02*
X1329504Y839320D01*
G01X1324779Y837744D02*
X1323205Y836170D01*
G01X1331078Y844044D02*
X1329504Y842470D01*
G01X1324779Y834595D02*
X1323205Y833021D01*
G01X1321629Y847193D02*
X1320055Y845619D01*
G01X1327929Y847193D02*
X1326355Y845619D01*
G01X1321629Y837744D02*
X1320055Y836170D01*
G01X1327929Y844044D02*
X1326355Y842470D01*
G01X1324779Y847193D02*
X1323205Y845619D01*
G01X1321629Y840894D02*
X1320055Y839320D01*
G01X1324779Y840894D02*
X1323204Y839319D01*
G01X1324779Y844044D02*
X1323205Y842470D01*
G01X1331078Y856642D02*
X1329504Y855068D01*
G01X1331078Y859792D02*
X1329504Y858218D01*
G01X1321629Y853492D02*
X1320055Y851918D01*
G01X1334228Y856642D02*
X1332654Y855068D01*
G01X1327929Y856642D02*
X1326355Y855068D01*
G01X1321629Y850343D02*
X1320055Y848769D01*
G01X1327929Y859792D02*
X1326355Y858218D01*
G01X1331078Y862941D02*
X1329504Y861367D01*
G01X1324779Y859792D02*
X1323205Y858218D01*
G01X1321629Y859792D02*
X1320055Y858218D01*
G01X1334228Y862941D02*
X1332654Y861367D01*
G01X1331078Y853492D02*
X1329504Y851918D01*
G01X1324779Y853492D02*
X1323205Y851918D01*
G01X1334228Y850343D02*
X1332654Y848769D01*
G01X1327929Y862941D02*
X1326355Y861367D01*
G01X1327929Y850343D02*
X1326355Y848769D01*
G01X1321629Y856642D02*
X1320055Y855068D01*
G01X1324779Y850343D02*
X1323205Y848769D01*
G01X1331078Y850343D02*
X1329504Y848769D01*
G01X1334228Y859792D02*
X1332654Y858218D01*
G01X1324779Y856642D02*
X1323204Y855067D01*
G01X1327929Y853492D02*
X1326355Y851918D01*
G01X1334228Y853492D02*
X1332654Y851918D01*
G01X1327929Y878689D02*
X1326355Y880263D01*
G01X1331078Y875540D02*
X1329504Y877114D01*
G01X1327929Y866091D02*
X1326355Y867665D01*
G01X1327929Y869240D02*
X1326355Y870814D01*
G01X1324779Y869240D02*
X1323205Y870814D01*
G01X1321629Y869240D02*
X1320055Y870814D01*
G01X1331078Y866091D02*
X1329504Y867665D01*
G01X1327929Y872390D02*
X1326355Y873964D01*
G01X1334228Y878689D02*
X1332654Y880263D01*
G01X1331078Y878689D02*
X1329504Y880263D01*
G01X1334228Y875540D02*
X1332654Y877114D01*
G01X1327929Y875540D02*
X1326355Y877114D01*
G01X1331078Y869240D02*
X1329504Y870814D01*
G01X1321629Y872390D02*
X1320055Y873964D01*
G01X1334228Y869240D02*
X1332654Y870814D01*
G01X1324779Y872390D02*
X1323204Y873965D01*
G01X1334228Y866091D02*
X1332654Y867665D01*
G01X1321629Y878689D02*
X1320055Y880263D01*
G01X1321629Y866091D02*
X1320055Y867665D01*
G01X1324779Y878689D02*
X1323205Y880263D01*
G01X1324779Y875540D02*
X1323205Y877114D01*
G01X1321629Y875540D02*
X1320055Y877114D01*
G01X1334228Y872390D02*
X1332654Y873964D01*
G01X1331078Y872390D02*
X1329504Y873964D01*
G01X1324779Y866091D02*
X1323205Y867665D01*
G01X1324779Y884988D02*
X1323205Y886562D01*
G01X1331078Y894437D02*
X1332638Y895997D01*
Y899638D01*
X1333000Y900000D01*
Y902613D01*
X1331056Y904557D01*
G01X1327929Y894437D02*
X1329489Y895997D01*
Y899511D01*
X1329000Y900000D01*
Y904500D01*
X1326500Y907000D01*
Y911500D01*
G01X1327929Y888138D02*
X1326355Y889712D01*
G01X1331078Y891288D02*
X1329504Y892862D01*
G01X1334228Y888138D02*
X1332654Y889712D01*
G01X1327929Y891288D02*
X1326355Y892862D01*
G01X1331078Y888138D02*
X1329504Y889712D01*
G01X1321629Y891288D02*
X1320055Y892862D01*
G01X1324779Y891288D02*
X1323205Y892862D01*
G01X1331078Y884988D02*
X1329504Y886562D01*
G01X1334228Y881839D02*
X1332654Y883413D01*
G01X1321629Y884988D02*
X1320055Y886562D01*
G01X1327929Y881839D02*
X1326355Y883413D01*
G01X1324779Y881839D02*
X1323205Y883413D01*
G01X1334228Y884988D02*
X1332654Y886562D01*
G01X1321629Y894437D02*
X1323189Y895997D01*
Y899311D01*
X1322000Y900500D01*
Y902500D01*
X1319500Y905000D01*
G01X1321629Y888138D02*
X1320055Y889712D01*
G01X1324779Y888138D02*
X1323204Y889713D01*
G01X1331078Y881839D02*
X1329504Y883413D01*
G01X1322500Y915300D02*
Y909001D01*
X1327500Y904001D01*
Y899500D01*
X1327929Y899071D01*
Y897587D01*
G01X1334500Y919925D02*
Y911643D01*
G01X1343677Y894437D02*
X1345237Y895997D01*
Y898344D01*
X1344748Y898833D01*
Y904752D01*
X1337857Y911643D01*
X1334500D01*
G01X1326500Y911500D02*
Y919925D01*
G01X1334228Y897587D02*
Y906228D01*
X1330500Y909956D01*
Y915300D01*
G01X1319500Y901500D02*
X1320500Y900500D01*
Y900001D01*
X1321629Y898872D01*
Y897587D01*
G01X1324000Y901000D02*
X1324779Y900221D01*
Y897587D01*
G01X1331078D02*
Y900500D01*
G01X1330500Y915300D02*
Y919925D01*
G01Y923075D02*
Y925500D01*
G01X1334500Y923075D02*
Y925500D01*
G01X1326500Y923075D02*
Y925500D01*
G01X1322500Y919925D02*
X1323350D01*
X1326500Y923075D01*
G01X1336000Y934075D02*
X1335706Y933781D01*
X1333132D01*
G01X1332059Y948063D02*
Y944941D01*
X1332500Y944500D01*
X1335000D01*
X1336000Y943500D01*
G01X1326500Y937925D02*
Y934075D01*
G01D02*
X1323000D01*
G01X1326941Y948063D02*
Y945441D01*
X1326500Y945000D01*
Y943500D01*
G01D02*
Y941075D01*
G01X1332500Y961500D02*
Y960000D01*
X1332059Y959559D01*
Y955937D01*
G01X1325550Y960445D02*
Y959010D01*
X1326941Y957619D01*
Y955937D01*
G01X1327000Y963925D02*
X1325550Y962475D01*
Y960445D01*
G01X1332000Y963925D02*
X1332500Y963425D01*
Y961500D01*
G01X1319874Y989856D02*
Y985625D01*
X1345948Y959551D01*
Y949178D01*
G01X1324735Y989966D02*
Y986059D01*
X1352404Y958390D01*
Y950722D01*
X1353948Y949178D01*
G01X1322427Y988221D02*
Y985752D01*
X1349948Y958231D01*
Y949178D01*
G01X1334909Y990340D02*
X1334984Y990265D01*
Y987651D01*
X1360009Y962626D01*
Y960756D01*
X1369948Y950817D01*
Y949178D01*
G01X1332404Y988215D02*
Y986671D01*
X1358391Y960684D01*
Y957485D01*
X1365948Y949928D01*
Y949178D01*
G01X1329834Y988132D02*
X1329734Y988032D01*
Y987632D01*
X1330094Y987272D01*
Y985745D01*
X1356306Y959533D01*
Y955075D01*
X1361948Y949433D01*
Y949178D01*
G01X1327267Y988271D02*
Y986230D01*
X1354407Y959090D01*
Y952719D01*
X1357948Y949178D01*
G01X1354047Y141247D02*
X1350218D01*
G01D02*
Y142399D01*
X1351559Y143740D01*
G01X1346248Y151540D02*
Y147540D01*
G01X1351816Y149414D02*
X1350076D01*
X1348939Y148277D01*
G01D02*
X1348667D01*
X1347930Y147540D01*
X1346248D01*
G01X1338172Y329978D02*
Y324963D01*
X1339834Y323301D01*
X1347228D01*
X1347990Y322539D01*
G01X1339746Y329978D02*
Y327349D01*
X1341169Y325926D01*
G01X1342699Y340805D02*
X1346093D01*
G01X1349636Y340862D02*
X1347821Y342677D01*
X1345135D01*
X1344837Y342379D01*
X1342699D01*
G01X1383963Y366675D02*
X1383035Y367603D01*
X1352262D01*
X1339746Y355087D01*
Y353206D01*
G01X1343259Y432227D02*
X1345328D01*
X1346443Y431112D01*
G01D02*
X1350084D01*
X1350573Y431601D01*
X1354771D01*
G01X1343358Y438133D02*
X1347196D01*
X1350228Y435101D01*
X1352008D01*
G01X1343846Y456026D02*
X1339846D01*
G01X1339814Y449550D02*
Y451981D01*
X1340820Y452987D01*
G01D02*
X1339846Y453961D01*
Y456026D01*
G01X1343846Y459176D02*
Y461607D01*
G01X1346738Y564492D02*
X1348789Y566543D01*
X1350984D01*
G01X1338000Y562500D02*
X1340750Y565250D01*
X1341250D01*
X1343046Y567046D01*
X1346762D01*
X1348818Y569102D01*
X1350984D01*
G01X1339289Y568461D02*
X1342489Y571661D01*
X1350984D01*
G01X1342053Y579339D02*
X1350984D01*
G01X1346533Y576780D02*
X1350984D01*
G01X1340522Y586133D02*
X1342198Y584457D01*
X1350984D01*
G01X1343000Y590458D02*
X1346442Y587016D01*
X1350984D01*
G01X1346533Y581898D02*
X1350984D01*
G01X1339289Y614961D02*
X1340650Y616322D01*
X1340652D01*
X1340653Y616321D01*
X1346182D01*
X1348022Y618161D01*
X1350984D01*
G01X1338000Y609000D02*
X1343369Y614369D01*
X1347585D01*
X1348818Y615602D01*
X1350984D01*
G01X1346738Y611192D02*
X1346938D01*
X1348789Y613043D01*
X1350984D01*
G01X1346533Y628398D02*
X1350984D01*
G01X1342053Y625839D02*
X1350984D01*
G01X1335532Y622260D02*
X1343752D01*
X1344224Y621788D01*
X1347422D01*
X1348914Y623280D01*
X1350984D01*
G01X1340522Y632633D02*
X1342198Y630957D01*
X1350984D01*
G01X1343000Y636958D02*
X1346442Y633516D01*
X1350984D01*
G01X1339289Y659461D02*
X1342489Y662661D01*
X1350984D01*
G01X1346533Y667780D02*
X1350984D01*
G01X1346738Y655492D02*
X1348789Y657543D01*
X1350984D01*
G01X1338000Y653500D02*
X1340750Y656250D01*
X1341250D01*
X1343046Y658046D01*
X1346762D01*
X1348818Y660102D01*
X1350984D01*
G01X1346533Y672898D02*
X1350984D01*
G01X1342053Y670339D02*
X1350984D01*
G01X1340522Y677133D02*
X1342198Y675457D01*
X1350984D01*
G01X1343000Y681458D02*
X1346442Y678016D01*
X1350984D01*
G01X1338000Y700500D02*
X1340750Y703250D01*
X1341250D01*
X1343046Y705046D01*
X1346762D01*
X1348818Y707102D01*
X1350984D01*
G01X1339289Y706461D02*
X1342489Y709661D01*
X1350984D01*
G01X1342053Y717339D02*
X1350984D01*
G01X1346533Y714780D02*
X1350984D01*
G01X1346738Y702492D02*
X1348789Y704543D01*
X1350984D01*
G01X1346533Y719898D02*
X1350984D01*
G01X1340522Y724133D02*
X1342198Y722457D01*
X1350984D01*
G01X1343000Y728458D02*
X1346442Y725016D01*
X1350984D01*
G01X1336661Y745675D02*
X1339218D01*
G01X1336661Y737675D02*
X1339218D01*
G01X1336450Y765675D02*
X1339218D01*
G01X1336661Y753675D02*
X1339218D01*
G01X1342368Y781675D02*
X1342693Y781350D01*
X1344768D01*
G01X1336746Y781675D02*
X1339218D01*
G01Y773675D02*
Y769675D01*
G01X1341000Y793575D02*
Y799000D01*
G01X1337000Y793575D02*
Y796000D01*
G01X1345000Y793575D02*
Y796000D01*
G01X1341000Y790425D02*
Y788000D01*
G01X1345000Y790425D02*
Y788000D01*
G01X1337000Y790425D02*
Y788000D01*
G01X1348917Y793575D02*
Y796000D01*
G01Y790425D02*
Y788000D01*
G01X1345000Y814200D02*
Y809575D01*
G01X1343677Y834595D02*
X1342117Y833035D01*
Y830025D01*
X1343252Y828890D01*
Y821752D01*
X1345000Y820004D01*
Y814200D01*
G01X1349000Y817500D02*
Y809575D01*
G01X1341000Y817500D02*
Y809575D01*
G01X1337000Y814200D02*
Y809575D01*
G01X1340527Y834595D02*
X1338967Y833035D01*
Y826475D01*
X1337000Y824508D01*
Y814200D01*
G01X1349000Y806425D02*
Y804000D01*
G01X1337000Y806425D02*
Y804000D01*
G01X1345000Y806425D02*
Y804000D01*
G01X1341000Y806425D02*
Y804000D01*
G01X1337377Y831445D02*
X1335803Y829871D01*
G01X1346826Y831445D02*
Y825674D01*
X1353000Y819500D01*
Y814200D01*
G01X1343677Y831445D02*
X1345000Y830122D01*
Y824500D01*
X1349000Y820500D01*
Y817500D01*
G01X1340527Y831445D02*
Y829473D01*
X1341000Y829000D01*
Y817500D01*
G01X1349976Y831445D02*
Y829000D01*
G01Y834595D02*
X1348416Y833035D01*
Y829916D01*
X1348000Y829500D01*
Y827500D01*
X1350000Y825500D01*
G01X1343677Y847193D02*
X1342103Y845619D01*
G01X1346826Y837744D02*
X1345252Y836170D01*
G01X1340527Y847193D02*
X1338953Y845619D01*
G01X1346826Y834595D02*
X1345252Y833021D01*
G01X1343677Y837744D02*
X1342103Y836170D01*
G01X1337377Y840894D02*
X1335803Y839320D01*
G01X1349976Y837744D02*
X1351550Y836170D01*
G01X1337377Y844044D02*
X1335803Y842470D01*
G01X1343677Y844044D02*
X1342103Y842470D01*
G01X1346826Y847193D02*
X1345252Y845619D01*
G01X1337377Y847193D02*
X1335803Y845619D01*
G01X1343677Y840894D02*
X1342103Y839320D01*
G01X1340527Y840894D02*
X1338952Y839319D01*
G01X1346826Y844044D02*
X1345252Y842470D01*
G01X1337377Y837744D02*
X1335803Y836170D01*
G01X1340527Y844044D02*
X1338953Y842470D01*
G01X1337377Y834595D02*
X1335803Y833021D01*
G01X1340527Y837744D02*
X1338953Y836170D01*
G01X1349976Y844044D02*
X1351550Y842470D01*
G01X1349976Y847193D02*
X1351550Y845619D01*
G01X1337377Y850343D02*
X1335803Y848769D01*
G01X1340527Y850343D02*
X1338953Y848769D01*
G01X1343677Y850343D02*
X1342103Y848769D01*
G01X1346826Y850343D02*
X1345252Y848769D01*
G01X1349976Y850343D02*
X1351550Y848769D01*
G01X1340527Y878689D02*
X1338953Y880263D01*
G01X1349976Y878689D02*
X1351550Y880263D01*
G01X1346826Y878689D02*
X1345252Y880263D01*
G01X1337377Y878689D02*
X1335803Y880263D01*
G01X1340527Y881839D02*
X1338953Y883413D01*
G01X1337377Y894437D02*
X1338937Y895997D01*
Y898563D01*
X1338000Y899500D01*
Y903138D01*
X1336096Y905042D01*
G01X1346826Y888138D02*
X1345252Y889712D01*
G01X1346826Y884988D02*
X1345252Y886562D01*
G01X1337377Y881839D02*
X1335803Y883413D01*
G01X1343677Y881839D02*
X1342103Y883413D01*
G01X1346826Y881839D02*
X1345252Y883413D01*
G01X1340527Y888138D02*
X1338952Y889713D01*
G01X1346826Y894437D02*
X1348386Y895997D01*
Y898755D01*
X1347588Y899553D01*
Y906912D01*
X1347000Y907500D01*
Y909000D01*
X1344500Y911500D01*
G01X1337377Y891288D02*
X1335803Y892862D01*
G01X1340527Y891288D02*
X1338953Y892862D01*
G01X1337377Y888138D02*
X1335803Y889712D01*
G01X1343677Y884988D02*
X1342103Y886562D01*
G01X1343677Y891288D02*
X1342103Y892862D01*
G01X1343677Y888138D02*
X1342103Y889712D01*
G01X1340527Y884988D02*
X1338953Y886562D01*
G01X1340000Y903000D02*
X1342087Y900913D01*
Y895997D01*
X1340527Y894437D01*
G01X1349976Y881839D02*
X1351550Y883413D01*
G01X1349976Y888138D02*
X1351550Y889712D01*
G01X1349976Y884988D02*
X1351550Y886562D01*
G01X1351511Y900000D02*
X1351536Y899975D01*
Y895997D01*
X1349976Y894437D01*
G01X1337377Y884988D02*
X1335803Y886562D01*
G01X1340000Y900000D02*
Y898860D01*
X1340527Y897587D01*
G01X1338500Y915300D02*
Y913500D01*
X1345900Y906100D01*
Y899155D01*
X1346826Y898229D01*
Y897587D01*
G01X1336000Y900500D02*
Y898964D01*
X1337377Y897587D01*
G01X1344500Y911500D02*
X1342500Y913500D01*
Y919925D01*
G01X1343677Y897587D02*
Y902323D01*
X1340000Y906000D01*
G01X1346500Y925500D02*
Y921160D01*
X1348500Y911104D01*
X1349500Y910104D01*
Y898999D01*
X1349976Y898523D01*
Y897587D01*
G01X1338500Y919925D02*
Y915300D01*
G01X1351380Y915164D02*
Y916620D01*
X1350500Y917500D01*
Y919925D01*
G01Y923075D02*
Y925500D01*
G01X1338500Y923075D02*
Y925500D01*
G01X1342500Y923075D02*
Y925500D01*
G01X1345948Y946028D02*
Y943603D01*
G01X1349948Y946028D02*
Y936855D01*
X1349848Y936755D01*
G01X1336000Y937925D02*
Y934075D01*
G01Y943500D02*
Y941075D01*
G01X1337514Y988259D02*
X1361860Y963913D01*
Y961266D01*
X1373948Y949178D01*
G01X1360122Y141247D02*
X1357197D01*
G01X1360122D02*
X1362922D01*
X1363769Y140400D01*
X1373771D01*
X1376019Y142648D01*
X1377541D01*
G01X1369100Y157500D02*
Y148325D01*
X1368600Y147825D01*
X1364278D01*
X1363709Y147256D01*
Y145768D01*
G01X1366859D02*
Y143868D01*
X1366509Y143518D01*
X1364609D01*
G01X1377541Y139695D02*
X1378993D01*
X1379600Y140302D01*
Y144200D01*
X1379100Y144700D01*
X1375600D01*
X1373065Y142165D01*
X1364836D01*
X1364609Y142392D01*
Y143518D01*
G01X1351559Y143740D02*
Y146204D01*
X1351816Y146461D01*
G01X1358902Y149414D02*
X1363355D01*
X1363709Y149768D01*
G01X1358902Y152367D02*
X1363703D01*
X1363709Y152373D01*
G01D02*
Y149768D01*
G01X1360719Y424601D02*
X1357921D01*
G01X1354771D02*
Y428101D01*
G01D02*
Y431601D01*
G01X1352008Y435101D02*
X1354771D01*
G01X1352817Y793575D02*
Y796000D01*
G01Y790425D02*
Y788000D01*
G01X1365000Y817500D02*
Y809575D01*
G01X1353000Y814200D02*
Y809575D01*
G01X1357000Y817500D02*
Y809575D01*
G01X1353125Y831445D02*
Y829376D01*
X1361000Y821501D01*
Y814200D01*
G01D02*
Y809575D01*
G01X1367000Y811620D02*
Y802800D01*
X1371803Y797997D01*
X1413291D01*
X1418856Y792432D01*
X1433715D01*
X1435647Y790500D01*
X1437425D01*
G01X1365000Y806425D02*
Y804000D01*
G01X1353000Y806425D02*
Y804000D01*
G01X1357000Y806425D02*
Y804000D01*
G01X1361000Y806425D02*
Y804000D01*
G01X1356275Y831445D02*
Y829225D01*
X1365000Y820500D01*
Y817500D01*
G01X1362574Y831445D02*
X1364148Y829871D01*
G01X1368381Y814312D02*
X1369000Y814931D01*
Y822500D01*
X1361000Y830500D01*
Y833020D01*
X1359425Y834595D01*
G01X1353125D02*
X1351565Y833035D01*
Y830703D01*
X1352093Y830175D01*
Y827407D01*
X1357000Y822500D01*
Y817500D01*
G01X1365724Y831445D02*
X1367298Y829871D01*
G01X1359425Y831445D02*
Y829000D01*
G01X1353125Y844044D02*
X1354699Y842470D01*
G01X1362574Y847193D02*
X1364148Y845619D01*
G01X1353125Y837744D02*
X1354699Y836170D01*
G01X1356275Y834595D02*
X1357849Y833021D01*
G01X1365724Y847193D02*
X1367298Y845619D01*
G01X1362574Y844044D02*
X1364148Y842470D01*
G01X1356275Y840894D02*
X1357850Y839319D01*
G01X1356275Y837744D02*
X1357849Y836170D01*
G01X1359425Y844044D02*
X1360999Y842470D01*
G01X1353125Y847193D02*
X1354699Y845619D01*
G01X1356275Y847193D02*
X1357849Y845619D01*
G01X1359425Y840894D02*
X1360999Y839320D01*
G01X1365724Y844044D02*
X1367298Y842470D01*
G01X1359425Y847193D02*
X1360999Y845619D01*
G01X1365724Y834595D02*
X1367298Y833021D01*
G01X1353125Y840894D02*
X1354699Y839320D01*
G01X1359425Y837744D02*
X1360999Y836170D01*
G01X1356275Y844044D02*
X1357849Y842470D01*
G01X1362574Y834595D02*
X1364148Y833021D01*
G01X1365724Y837744D02*
X1367298Y836170D01*
G01X1365724Y840894D02*
X1367298Y839320D01*
G01X1353125Y850343D02*
X1354699Y848769D01*
G01X1356275Y850343D02*
X1357849Y848769D01*
G01X1362574Y853492D02*
X1364148Y851918D01*
G01X1365724Y862941D02*
X1367298Y861367D01*
G01X1362574Y859792D02*
X1364148Y858218D01*
G01X1362574Y856642D02*
X1364148Y855068D01*
G01X1362574Y862941D02*
X1364148Y861367D01*
G01X1365724Y859792D02*
X1367298Y858218D01*
G01X1359425Y850343D02*
X1360999Y848769D01*
G01X1365724Y853492D02*
X1367298Y851918D01*
G01X1365724Y850343D02*
X1367298Y848769D01*
G01X1365724Y856642D02*
X1367298Y855068D01*
G01X1362574Y850343D02*
X1364148Y848769D01*
G01X1362574Y866091D02*
X1364148Y867665D01*
G01X1365724Y875540D02*
X1367298Y877114D01*
G01X1362574Y869240D02*
X1364148Y870814D01*
G01X1365724Y872390D02*
X1367298Y873964D01*
G01X1362574Y872390D02*
X1364148Y873964D01*
G01X1362574Y875540D02*
X1364148Y877114D01*
G01X1365724Y869240D02*
X1367298Y870814D01*
G01X1362574Y878689D02*
X1364148Y880263D01*
G01X1365724Y878689D02*
X1367298Y880263D01*
G01X1356275Y878689D02*
X1357849Y880263D01*
G01X1359425Y878689D02*
X1360999Y880263D01*
G01X1365724Y866091D02*
X1367298Y867665D01*
G01X1365724Y881839D02*
X1367298Y883413D01*
G01X1353125Y891288D02*
X1354699Y892862D01*
G01X1359425Y891288D02*
X1360999Y892862D01*
G01X1365724Y891288D02*
X1367298Y892862D01*
G01X1359425Y881839D02*
X1360999Y883413D01*
G01X1356275Y888138D02*
X1357850Y889713D01*
G01X1362574Y888138D02*
X1364148Y889712D01*
G01X1356275Y881839D02*
X1357849Y883413D01*
G01X1359425Y894437D02*
X1360985Y895997D01*
Y901525D01*
X1362480Y903020D01*
Y906520D01*
X1364500Y908540D01*
Y915300D01*
G01X1365724Y888138D02*
X1367298Y889712D01*
G01X1353125Y894437D02*
X1354685Y895997D01*
Y901815D01*
X1354000Y902500D01*
Y904000D01*
X1351500Y906500D01*
G01X1353125Y888138D02*
X1354699Y889712D01*
G01X1365724Y894437D02*
X1367284Y895997D01*
Y898475D01*
X1367000Y898759D01*
Y900500D01*
G01X1356500Y915000D02*
X1357835Y913665D01*
Y895997D01*
X1356275Y894437D01*
G01Y884988D02*
X1357849Y886562D01*
G01X1362574Y884988D02*
X1364148Y886562D01*
G01X1356275Y891288D02*
X1357849Y892862D01*
G01X1359425Y888138D02*
X1360999Y889712D01*
G01X1353125Y881839D02*
X1354699Y883413D01*
G01X1359425Y884988D02*
X1360999Y886562D01*
G01X1362574Y881839D02*
X1364148Y883413D01*
G01X1365724Y884988D02*
X1367298Y886562D01*
G01X1353125Y884988D02*
X1354699Y886562D01*
G01X1368000Y911500D02*
Y909205D01*
X1365000Y906205D01*
Y898311D01*
X1365724Y897587D01*
G01X1353125D02*
Y899125D01*
X1353500Y899500D01*
Y901000D01*
X1351500Y903000D01*
G01X1367000Y904500D02*
X1368146Y903354D01*
X1368873Y901599D01*
Y897587D01*
G01X1351380Y915164D02*
X1351811D01*
X1356110Y910865D01*
Y899890D01*
X1356275Y899725D01*
Y897587D01*
G01X1362574D02*
Y899471D01*
X1363000Y900500D01*
G01X1358500Y919925D02*
Y917000D01*
X1361000Y914500D01*
Y911500D01*
G01D02*
Y907780D01*
X1359425Y906205D01*
Y897587D01*
G01X1366500Y919925D02*
Y918000D01*
X1368000Y916500D01*
Y911500D01*
G01X1362500Y919925D02*
Y917300D01*
X1364500Y915300D01*
G01X1354500Y919925D02*
Y917000D01*
X1356500Y915000D01*
G01X1354500Y923075D02*
Y925500D01*
G01X1366500Y923075D02*
Y925500D01*
G01X1358500Y923075D02*
Y925500D01*
G01X1362500Y923075D02*
Y925500D01*
G01X1353948Y946028D02*
Y943603D01*
G01X1365948Y946028D02*
Y939475D01*
G01X1357948Y946028D02*
Y938842D01*
G01X1361948Y946028D02*
Y943603D01*
G01X1382215Y113684D02*
Y110794D01*
X1382205Y110784D01*
G01D02*
X1380480Y109059D01*
Y107899D01*
G01X1382505Y130898D02*
X1382600Y130993D01*
Y145082D01*
X1379932Y147754D01*
X1375694D01*
G01X1380247Y121558D02*
Y123126D01*
X1379090Y124283D01*
X1376696D01*
G01D02*
X1376728Y124315D01*
Y125971D01*
X1378505Y127748D01*
G01X1382215Y121558D02*
Y123785D01*
X1381762Y124879D01*
G01D02*
Y127005D01*
X1382505Y127748D01*
G01X1372354Y157370D02*
Y148980D01*
X1373583Y147754D01*
X1375694D01*
G01Y150904D02*
Y154865D01*
G01X1390346Y161958D02*
Y158209D01*
X1389846Y157709D01*
X1383475D01*
X1380631Y154865D01*
G01D02*
X1375694D01*
G01X1369100Y157500D02*
X1369525Y158525D01*
X1376544Y165544D01*
X1403559D01*
X1410908Y158195D01*
X1471495D01*
G01X1384975Y242078D02*
X1377703D01*
X1375215Y244566D01*
Y252370D01*
X1377251Y254406D01*
X1387088D01*
X1388458Y255776D01*
X1395952Y258880D01*
X1429247D01*
G01X1381026Y320871D02*
X1384265D01*
G01X1381026Y325371D02*
X1384265D01*
G01X1387876Y338871D02*
X1384614D01*
X1383551Y337808D01*
G01D02*
X1382488Y338871D01*
X1381026D01*
G01Y329871D02*
X1384265D01*
G01X1387876Y343371D02*
X1385484D01*
X1384879Y342766D01*
X1383634D01*
G01D02*
X1381631D01*
X1381026Y343371D01*
G01Y334371D02*
X1384265D01*
G01X1391026Y361371D02*
Y359969D01*
X1390526Y359469D01*
X1382928D01*
X1381026Y361371D01*
G01X1391026Y356871D02*
Y355469D01*
X1390526Y354969D01*
X1382928D01*
X1381026Y356871D01*
G01Y347871D02*
Y349026D01*
X1381437Y349437D01*
X1383505D01*
G01D02*
X1383746Y349196D01*
X1385397Y348511D01*
X1386037Y347871D01*
X1387876D01*
G01X1381026Y352371D02*
X1384265D01*
G01X1374016Y561032D02*
X1377488D01*
X1378415Y560105D01*
Y558795D01*
G01D02*
X1380620Y561000D01*
X1385166D01*
G01X1374016Y563984D02*
X1378415D01*
G01D02*
X1384150D01*
X1385166Y565000D01*
G01X1374016Y566543D02*
X1377630D01*
X1378415Y567328D01*
Y569776D01*
G01D02*
X1382413D01*
X1383189Y569000D01*
X1385166D01*
G01X1374016Y584457D02*
X1378957D01*
G01X1374016Y587016D02*
X1380484D01*
X1383000Y584500D01*
G01X1374016Y581898D02*
X1377194D01*
X1377604Y581488D01*
X1382826D01*
X1382997Y581317D01*
G01D02*
X1385512D01*
G01X1374016Y607532D02*
X1377488D01*
X1378415Y606605D01*
Y605295D01*
G01D02*
X1380620Y607500D01*
X1385166D01*
G01X1374016Y610484D02*
X1378415D01*
G01D02*
X1384150D01*
X1385166Y611500D01*
G01X1374016Y613043D02*
X1377630D01*
X1378415Y613828D01*
Y616276D01*
G01D02*
X1382413D01*
X1383189Y615500D01*
X1385166D01*
G01X1374016Y630957D02*
X1378957D01*
G01X1374016Y633516D02*
X1377671D01*
X1379933Y632579D01*
X1380200Y632400D01*
X1380925Y631675D01*
X1384602D01*
X1384657Y631620D01*
G01X1385512Y627817D02*
X1385341Y627988D01*
X1378957D01*
G01D02*
X1377604D01*
X1377194Y628398D01*
X1374016D01*
G01X1391425Y652000D02*
X1380620D01*
X1378415Y649795D01*
G01D02*
Y651105D01*
X1377488Y652032D01*
X1374016D01*
G01X1391425Y660000D02*
X1383189D01*
X1382413Y660776D01*
X1378415D01*
G01D02*
Y658328D01*
X1377630Y657543D01*
X1374016D01*
G01X1391425Y656000D02*
X1385166D01*
X1384150Y654984D01*
X1378415D01*
G01D02*
X1374016D01*
G01Y672898D02*
X1377194D01*
X1378838Y671254D01*
X1385055D01*
X1386289Y672488D01*
G01X1374016Y675457D02*
X1378957D01*
G01X1374016Y678016D02*
X1380484D01*
X1383000Y675500D01*
G01X1374016Y699032D02*
X1377488D01*
X1378415Y698105D01*
Y696795D01*
G01D02*
X1380620Y699000D01*
X1391425D01*
G01X1374016Y701984D02*
X1378415D01*
G01D02*
X1384150D01*
X1385166Y703000D01*
X1391425D01*
G01X1374016Y704543D02*
X1377630D01*
X1378415Y705328D01*
Y707776D01*
G01D02*
X1382413D01*
X1383189Y707000D01*
X1391425D01*
G01X1374016Y719898D02*
X1377194D01*
X1377604Y719488D01*
X1378957D01*
G01D02*
X1393167D01*
X1394075Y720396D01*
Y722000D01*
G01X1374016Y722457D02*
X1378957D01*
G01X1385290Y722400D02*
X1382674Y725016D01*
X1374016D01*
G01X1381000Y809575D02*
X1379500Y811075D01*
Y814204D01*
X1380544Y815248D01*
G01X1375173Y834595D02*
X1376733Y833035D01*
Y830585D01*
X1377000Y830318D01*
Y816900D01*
X1378652Y815248D01*
X1380544D01*
G01X1369000Y809575D02*
Y813693D01*
X1368381Y814312D01*
G01X1373000Y809575D02*
Y816002D01*
X1371604Y817398D01*
G01X1381000Y806425D02*
Y804000D01*
G01X1373000Y806425D02*
Y804000D01*
G01X1369000Y806425D02*
Y804000D01*
G01X1377017Y809573D02*
Y809900D01*
X1375193Y811724D01*
G01D02*
X1375600Y812131D01*
Y814702D01*
G01D02*
Y828573D01*
X1375173Y829000D01*
Y831445D01*
G01X1603251Y797012D02*
X1598974Y801289D01*
Y821808D01*
X1570413Y850369D01*
X1441634D01*
X1436068Y855935D01*
X1431127D01*
X1422491Y847299D01*
Y812040D01*
X1411021Y800570D01*
X1379181D01*
X1377017Y802734D01*
Y806423D01*
G01X1368873Y831445D02*
X1370447Y829871D01*
G01X1371604Y817398D02*
X1373000Y818794D01*
Y830468D01*
X1372023Y831445D01*
G01X1378322D02*
X1380187Y829580D01*
Y821280D01*
X1384090Y817377D01*
G01X1368873Y840894D02*
X1370447Y839320D01*
G01X1381472Y847193D02*
X1383046Y845619D01*
G01X1378322Y847193D02*
X1379896Y845619D01*
G01X1384600Y837744D02*
X1395998D01*
G01X1378322D02*
X1379911Y836155D01*
X1383845D01*
X1384900Y835100D01*
X1398974D01*
X1401583Y832491D01*
G01X1372023Y847193D02*
X1373597Y845619D01*
G01X1372023Y844044D02*
X1373597Y842470D01*
G01X1378322Y840894D02*
X1379896Y839320D01*
G01X1372023Y834595D02*
X1373597Y833021D01*
G01X1368873Y834595D02*
X1370447Y833021D01*
G01X1372023Y837744D02*
X1373597Y836170D01*
G01X1368873Y837744D02*
X1370447Y836170D01*
G01X1372023Y840894D02*
X1373598Y839319D01*
G01X1368873Y844044D02*
X1370447Y842470D01*
G01X1368873Y847193D02*
X1370447Y845619D01*
G01X1381472Y844044D02*
X1383046Y842470D01*
G01X1375173Y837744D02*
X1376747Y836170D01*
G01X1378322Y834595D02*
X1379896Y833021D01*
G01X1381472Y840894D02*
X1383046Y839320D01*
G01X1375173Y847193D02*
X1376747Y845619D01*
G01X1381472Y834595D02*
X1382601Y833466D01*
X1387905D01*
X1388674Y832697D01*
X1395955D01*
G01X1375173Y840894D02*
X1376747Y839320D01*
G01X1379896Y855068D02*
X1378322Y856642D01*
G01Y862941D02*
X1379896Y861367D01*
G01X1375173Y859792D02*
X1376747Y858218D01*
G01X1375173Y853492D02*
X1376747Y851918D01*
G01X1372023Y862941D02*
X1373597Y861367D01*
G01X1375173Y856642D02*
X1376747Y855068D01*
G01X1372023Y859792D02*
X1373597Y858218D01*
G01X1381472Y856642D02*
X1382917Y855197D01*
X1396486D01*
X1397289Y856000D01*
X1402500D01*
G01X1375173Y862941D02*
X1376747Y861367D01*
G01X1381472Y853492D02*
X1383046Y851918D01*
G01X1372023Y853492D02*
X1373597Y851918D01*
G01X1384600Y850343D02*
X1397000D01*
G01X1368873D02*
X1370447Y848769D01*
G01X1372023Y856642D02*
X1373598Y855067D01*
G01X1378322Y850343D02*
X1379896Y848769D01*
G01X1378322Y853492D02*
X1379896Y851918D01*
G01X1368873Y853492D02*
X1370447Y851918D01*
G01X1368873Y859792D02*
X1370447Y858218D01*
G01X1372023Y850343D02*
X1373597Y848769D01*
G01X1375173Y850343D02*
X1376747Y848769D01*
G01X1381472Y859792D02*
X1383046Y858218D01*
G01X1381472Y862941D02*
X1383046Y861367D01*
G01X1368873Y856642D02*
X1370447Y855068D01*
G01X1381472Y872390D02*
X1383046Y873964D01*
G01X1375173Y878689D02*
X1376747Y880263D01*
G01X1368873Y875540D02*
X1370447Y877114D01*
G01X1372023Y872390D02*
X1373598Y873965D01*
G01X1381472Y866091D02*
X1387833D01*
X1393742Y872000D01*
X1398909D01*
G01X1368873Y872390D02*
X1370447Y873964D01*
G01X1378322Y875540D02*
X1379896Y877114D01*
G01X1372023Y878689D02*
X1373597Y880263D01*
G01X1381472Y875540D02*
X1383046Y877114D01*
G01X1368873Y878689D02*
X1370447Y880263D01*
G01X1375173Y872390D02*
X1376747Y873964D01*
G01X1381472Y878689D02*
X1383046Y880263D01*
G01X1368873Y869240D02*
X1370447Y870814D01*
G01X1375173Y869240D02*
X1376747Y870814D01*
G01X1372023Y869240D02*
X1373597Y870814D01*
G01X1375173Y866091D02*
X1376747Y867665D01*
G01X1375173Y875540D02*
X1376747Y877114D01*
G01X1372023Y866091D02*
X1373597Y867665D01*
G01X1378322Y866091D02*
X1379896Y867665D01*
G01X1381472Y869240D02*
X1383046Y870814D01*
G01X1378322Y878689D02*
X1379896Y880263D01*
G01X1372023Y875540D02*
X1373597Y877114D01*
G01X1378322Y872390D02*
X1379896Y873964D01*
G01X1381472Y891288D02*
X1383046Y892862D01*
G01X1378322Y884988D02*
X1379896Y886562D01*
G01X1368873Y881839D02*
X1370447Y883413D01*
G01X1372023Y888138D02*
X1373598Y889713D01*
G01X1375173Y884988D02*
X1376747Y886562D01*
G01X1381472Y881839D02*
X1383046Y883413D01*
G01X1375173Y888138D02*
X1376747Y889712D01*
G01X1381472Y888138D02*
X1383046Y889712D01*
G01X1378322Y888138D02*
X1379896Y889712D01*
G01X1372023Y881839D02*
X1373597Y883413D01*
G01X1372023Y884988D02*
X1373597Y886562D01*
G01X1378322Y894437D02*
X1379882Y895997D01*
Y899785D01*
X1381609Y901512D01*
X1383725D01*
X1387520Y905307D01*
G01X1368873Y894437D02*
X1370433Y895997D01*
Y904932D01*
X1371500Y905999D01*
Y915300D01*
G01X1368873Y891288D02*
X1370447Y892862D01*
G01X1372023Y894437D02*
X1373583Y895997D01*
Y903582D01*
X1378500Y908499D01*
Y915300D01*
G01X1375173Y891288D02*
X1376747Y892862D01*
G01X1368873Y888138D02*
X1370447Y889712D01*
G01X1372023Y891288D02*
X1373597Y892862D01*
G01X1376708Y901000D02*
X1376733Y900975D01*
Y895997D01*
X1375173Y894437D01*
G01X1381472Y884988D02*
X1383046Y886562D01*
G01X1378322Y891288D02*
X1379896Y892862D01*
G01X1375173Y897587D02*
Y898963D01*
X1374755Y899381D01*
Y902254D01*
X1382000Y909499D01*
Y911500D01*
G01D02*
Y917000D01*
X1382500Y917500D01*
Y919925D01*
G01X1372023Y897587D02*
Y904522D01*
X1375000Y907499D01*
Y911500D01*
G01D02*
Y915500D01*
X1374500Y916000D01*
Y919925D01*
G01X1378322Y897587D02*
X1378504Y897769D01*
Y900553D01*
X1384978Y907027D01*
Y926542D01*
X1385656Y927220D01*
X1388346D01*
G01X1370500Y919925D02*
Y918463D01*
X1371500Y917463D01*
Y915300D01*
G01X1378500Y919925D02*
Y915300D01*
G01Y923075D02*
Y925500D01*
G01D02*
X1376438Y927562D01*
Y932234D01*
X1378449Y934245D01*
X1378503D01*
G01X1374500Y923075D02*
Y925368D01*
X1374369Y925499D01*
G01X1370500Y923075D02*
Y925500D01*
G01X1382500D02*
X1380844Y927156D01*
Y932667D01*
X1382423Y934246D01*
X1382560D01*
G01X1382500Y923075D02*
Y925500D01*
G01X1373948Y946028D02*
Y940103D01*
G01X1369948Y946028D02*
Y943603D01*
G01X1382775Y930281D02*
X1387288D01*
X1388346Y929223D01*
Y927220D01*
G01X1389192Y992568D02*
X1385639D01*
X1383597Y994610D01*
Y997941D01*
X1383135Y998403D01*
Y1003752D01*
X1384157Y1004774D01*
Y1007854D01*
G01X1381519Y996280D02*
Y1004999D01*
X1382582Y1006062D01*
Y1007854D01*
G01X1369918Y1043140D02*
X1374725D01*
X1376071Y1041794D01*
G01X1388882Y1026752D02*
Y1027880D01*
X1389700Y1028698D01*
Y1038009D01*
X1386223Y1041486D01*
X1385008D01*
X1383334Y1039812D01*
X1380888D01*
X1378906Y1041794D01*
X1376071D01*
G01X1369841Y1047047D02*
X1377362D01*
X1382052Y1042357D01*
G01D02*
X1383568Y1043873D01*
X1385628D01*
X1390832Y1038669D01*
Y1028343D01*
X1390456Y1027433D01*
Y1026752D01*
G01X1399249Y102495D02*
Y106495D01*
G01D02*
X1403165D01*
X1403231Y106561D01*
G01X1384480Y107899D02*
X1388480D01*
G01X1384183Y113684D02*
Y111534D01*
X1384933Y110784D01*
X1387205D01*
G01D02*
X1388480Y109509D01*
Y107899D01*
G01X1390559Y130903D02*
X1390528Y130934D01*
Y134838D01*
G01X1390559Y127753D02*
Y126313D01*
X1391765Y125107D01*
G01X1384183Y121558D02*
Y124163D01*
X1384683Y124663D01*
X1386784D01*
G01D02*
Y126008D01*
X1386505Y126287D01*
Y127748D01*
G01X1397149Y143762D02*
X1400379D01*
G01X1386606Y153296D02*
Y150265D01*
X1388154Y148717D01*
X1394279D01*
G01D02*
X1396432D01*
X1397149Y148000D01*
Y146912D01*
G01X1384627Y136742D02*
Y138338D01*
X1385127Y138838D01*
X1388128D01*
G01X1390528Y134838D02*
Y138838D01*
G01X1388128D02*
X1390528D01*
G01X1399374Y225055D02*
Y229782D01*
X1398600Y230556D01*
G01X1389824Y232859D02*
Y232681D01*
X1393859Y228646D01*
G01X1395437Y225055D02*
Y227068D01*
X1393859Y228646D01*
G01X1398600Y230556D02*
Y232333D01*
X1399226Y232959D01*
G01X1391954Y242078D02*
X1388125D01*
G01X1389723Y247292D02*
X1389466Y247035D01*
Y244571D01*
G01D02*
X1388125Y243230D01*
Y242078D01*
G01X1384155Y252371D02*
Y248371D01*
G01X1389723Y250245D02*
X1387983D01*
X1386846Y249108D01*
G01D02*
X1386574D01*
X1385837Y248371D01*
X1384155D01*
G01X1401616Y250599D02*
X1401812Y250795D01*
Y253923D01*
X1399341Y256394D01*
X1396809D01*
G01D02*
Y253198D01*
G01X1401616Y250599D02*
X1401262Y250245D01*
X1396809D01*
G01X1384265Y320871D02*
X1387876D01*
G01X1384265Y325371D02*
X1387876D01*
G01X1404362Y328996D02*
X1400825D01*
X1400042Y328213D01*
Y324845D01*
X1395726Y320529D01*
G01D02*
X1393542D01*
X1393200Y320871D01*
X1391026D01*
G01Y325371D02*
X1395410D01*
X1395568Y325529D01*
G01D02*
X1398005Y327966D01*
Y329668D01*
X1399892Y331555D01*
X1404362D01*
G01X1384265Y329871D02*
X1387876D01*
G01X1384265Y334371D02*
X1387876D01*
G01X1404362Y336673D02*
X1396870D01*
X1395736Y335539D01*
Y335529D01*
G01D02*
X1395726D01*
X1394568Y334371D01*
X1391026D01*
G01Y338871D02*
X1394068D01*
X1395726Y340529D01*
G01D02*
X1397023Y339232D01*
X1404362D01*
G01Y341792D02*
X1399463D01*
X1395726Y345529D01*
G01D02*
X1393184D01*
X1391026Y343371D01*
G01X1404362Y334114D02*
X1399311D01*
X1395726Y330529D01*
G01D02*
X1391684D01*
X1391026Y329871D01*
G01X1404362Y352028D02*
X1401618D01*
X1400074Y353572D01*
Y358901D01*
X1398446Y360529D01*
X1395726D01*
G01D02*
X1392068Y356871D01*
X1391026D01*
G01X1384265Y352371D02*
X1387876D01*
G01X1404362Y344351D02*
X1401004D01*
X1397139Y348216D01*
Y349116D01*
X1395726Y350529D01*
G01D02*
X1393684D01*
X1391026Y347871D01*
G01X1395726Y355529D02*
X1394596Y354399D01*
X1393054D01*
X1391026Y352371D01*
G01X1404362Y346910D02*
X1401489D01*
X1399860Y348539D01*
Y351139D01*
X1395726Y355273D01*
Y355529D01*
G01X1404362Y354587D02*
Y358991D01*
X1397824Y365529D01*
X1391896D01*
G01D02*
X1391026Y364659D01*
Y361371D01*
G01X1399659Y527726D02*
X1397079D01*
G01X1399659Y544726D02*
X1397079D01*
G01D02*
X1393745Y548060D01*
Y620110D01*
X1398946Y625311D01*
G01X1388316Y561000D02*
X1390741D01*
G01Y569000D02*
X1388316D01*
G01X1390741Y565000D02*
X1388316D01*
G01X1385511Y577192D02*
Y581316D01*
X1385512Y581317D01*
G01X1390741Y611500D02*
X1388316D01*
G01Y607500D02*
X1390741D01*
G01Y615500D02*
X1388316D01*
G01X1401377Y625311D02*
X1398946D01*
G01X1573383Y694797D02*
Y690054D01*
X1572506Y689177D01*
X1565177D01*
X1526030Y650030D01*
X1405265D01*
X1393770Y638535D01*
Y630487D01*
X1398946Y625311D01*
G01X1385511Y623692D02*
Y627816D01*
X1385512Y627817D01*
G01X1399425Y652000D02*
Y656000D01*
G01X1394575Y652000D02*
X1397000D01*
G01X1399425Y656000D02*
X1397000D01*
G01D02*
X1394575D01*
G01X1399425Y660000D02*
X1397000D01*
G01D02*
X1394575D01*
G01X1398925Y675000D02*
X1394075D01*
G01X1386289Y672488D02*
X1392735D01*
X1394075Y673828D01*
Y675000D01*
G01X1399425Y699000D02*
Y703000D01*
G01X1394575Y699000D02*
X1397000D01*
G01X1394575Y707000D02*
X1397000D01*
G01D02*
X1399425D01*
G01X1394575Y703000D02*
X1397000D01*
G01D02*
X1399425D01*
G01X1398925Y722000D02*
X1394075D01*
G01X1386335Y809279D02*
Y810782D01*
X1385360Y811757D01*
G01X1390537Y809254D02*
X1391040Y809757D01*
Y812027D01*
G01X1386335Y806129D02*
Y803704D01*
G01X1390537Y806104D02*
Y803679D01*
G01X1394537Y806104D02*
Y803653D01*
G01X1384090Y817377D02*
X1386470Y814997D01*
X1392488D01*
X1394537Y812948D01*
Y809254D01*
G01X1602595Y802852D02*
X1600108Y805339D01*
Y822278D01*
X1570897Y851489D01*
X1442118D01*
X1436538Y857069D01*
X1430657D01*
X1421357Y847769D01*
Y812682D01*
X1411090Y802415D01*
X1400161D01*
X1398517Y804059D01*
Y806142D01*
G01Y809292D02*
Y811704D01*
X1398530Y811717D01*
G01X1400069Y827515D02*
X1403650Y823934D01*
X1407874D01*
G01X1395998Y837744D02*
X1400150D01*
X1405894Y832000D01*
X1407925D01*
G01X1397000Y850343D02*
X1399000D01*
X1400657Y852000D01*
X1407925D01*
G01X1398909Y872000D02*
X1407925D01*
G01X1387520Y905307D02*
X1388807D01*
X1401000Y917500D01*
Y919925D01*
G01X1392534Y964473D02*
X1400624D01*
X1402064Y965913D01*
G01X1396756Y1007854D02*
Y1006406D01*
X1397471Y1005691D01*
X1401901D01*
X1405180Y1002412D01*
Y1000497D01*
G01X1395181Y1007854D02*
Y1005950D01*
X1397552Y1003579D01*
Y1002585D01*
X1398671Y1001466D01*
G01X1402265Y995341D02*
Y997872D01*
X1398671Y1001466D01*
G01X1386322Y996052D02*
X1387952Y997682D01*
Y1002112D01*
X1387307Y1002757D01*
Y1007854D01*
G01X1385617Y1001144D02*
X1385732Y1001258D01*
Y1007854D01*
G01X1394885Y999941D02*
Y1004351D01*
X1393606Y1005630D01*
Y1007854D01*
G01X1392031Y1004375D02*
Y1007854D01*
G01X1391422Y996052D02*
X1389087Y998387D01*
Y1002491D01*
X1388882Y1002696D01*
Y1007854D01*
G01X1391422Y1001052D02*
X1390157Y1002317D01*
Y1005083D01*
X1390196Y1005122D01*
Y1005136D01*
X1390456Y1005396D01*
Y1007854D01*
G01X1406216Y1020491D02*
X1403892Y1022815D01*
X1399118D01*
G01Y1024390D02*
X1407690D01*
X1410397Y1027097D01*
G01X1399118Y1013366D02*
X1404418D01*
X1405821Y1011963D01*
G01X1399118Y1010216D02*
X1400072D01*
X1412698Y997590D01*
G01X1399118Y1014941D02*
X1406434D01*
X1412609Y1008766D01*
G01X1399118Y1011791D02*
X1402133D01*
X1409748Y1004176D01*
G01X1399118Y1016516D02*
X1407191D01*
X1409837Y1015420D01*
G01X1399118Y1018090D02*
X1410935D01*
X1412759Y1016266D01*
G01X1399118Y1021240D02*
X1401415D01*
X1402215Y1020440D01*
G01X1399118Y1019665D02*
X1401440D01*
X1402215Y1020440D01*
G01X1385732Y1026752D02*
Y1029482D01*
G01X1387813Y1030952D02*
Y1028854D01*
X1387307Y1028348D01*
Y1026752D01*
G01X1413248Y99961D02*
X1408473D01*
X1406308Y102126D01*
Y103411D01*
G01X1403433Y97667D02*
X1406702D01*
G01X1413248Y97599D02*
X1406770D01*
X1406702Y97667D01*
G01X1413248Y90512D02*
X1417360D01*
X1417498Y90650D01*
G01X1413248Y88150D02*
X1420345D01*
X1422810Y90615D01*
G01X1417248Y95236D02*
X1413248D01*
G01Y92874D02*
X1404335D01*
X1402098Y95111D01*
G01X1406308Y103411D02*
X1403231D01*
G01Y106561D02*
X1406467D01*
G01X1401343Y225055D02*
Y226212D01*
X1402855Y227724D01*
Y227824D01*
G01D02*
Y230574D01*
X1403461Y231180D01*
Y232984D01*
G01X1405162Y241681D02*
Y244297D01*
G01X1402012Y241681D02*
X1401371Y241040D01*
Y233522D01*
X1401909Y232984D01*
X1403461D01*
G01X1408854Y381207D02*
Y349939D01*
X1408384Y349469D01*
X1404362D01*
G01X1417903Y445494D02*
X1415615D01*
X1414903Y446206D01*
Y451376D01*
G01X1410903Y467494D02*
Y470419D01*
G01X1414903Y464344D02*
X1410903D01*
G01X1411950Y458462D02*
Y460872D01*
X1410903Y461919D01*
G01D02*
Y464344D01*
G01X1414903Y458462D02*
Y460419D01*
X1415903Y461419D01*
X1418903D01*
G01X1412640Y487982D02*
Y489422D01*
X1413258Y490040D01*
X1413621D01*
X1415623Y492042D01*
Y492268D01*
G01X1415823Y482165D02*
X1412640Y478982D01*
G01X1419414Y489743D02*
X1418492D01*
X1416265Y487516D01*
Y484974D01*
X1415823Y484532D01*
Y482165D01*
G01X1415064Y500202D02*
X1412860D01*
X1412640Y499982D01*
G01X1419414Y497617D02*
X1419211D01*
X1416626Y500202D01*
X1415064D01*
G01X1415623Y492268D02*
X1416328D01*
X1417740Y493680D01*
X1419414D01*
G01X1412640Y491982D02*
Y495982D01*
G01X1416413Y495649D02*
X1414845D01*
X1414512Y495982D01*
X1412640D01*
G01X1409490Y491982D02*
X1406910D01*
G01X1402809Y527726D02*
Y531726D01*
G01X1405992Y534909D02*
X1402809Y531726D01*
G01X1409583Y536487D02*
X1407570D01*
X1405992Y534909D01*
G01X1402809Y544726D02*
Y548726D01*
G01X1405685Y546553D02*
Y548226D01*
X1405185Y548726D01*
X1402809D01*
G01X1409583Y542393D02*
X1408130D01*
X1405685Y544838D01*
Y546553D01*
G01X1402809Y540726D02*
X1403903D01*
X1404312Y541135D01*
X1405619D01*
G01X1409583Y540424D02*
X1407565D01*
X1406854Y541135D01*
X1405619D01*
G01X1402809Y552726D02*
X1405708D01*
G01X1409583Y544361D02*
X1408861D01*
X1408273Y544949D01*
Y550161D01*
X1405708Y552726D01*
G01X1404527Y621311D02*
X1406592D01*
X1407566Y622285D01*
G01X1404527Y625311D02*
Y621311D01*
G01X1407566Y622285D02*
X1408572Y621279D01*
X1411003D01*
G01X1415575Y685000D02*
X1418000D01*
G01X1415575Y689000D02*
Y685000D01*
G01Y681000D02*
X1418000D01*
G01X1415575Y697000D02*
X1417000D01*
X1418000Y696000D01*
G01X1415575Y701000D02*
X1418000D01*
G01X1415575Y705000D02*
Y701000D01*
G01Y717000D02*
X1418000D01*
G01X1412425D02*
X1410000D01*
G01X1412394Y720894D02*
Y717031D01*
X1412425Y717000D01*
G01X1415575Y709000D02*
X1420425D01*
G01X1415575Y713000D02*
X1420425D01*
G01X1415575Y725000D02*
X1417000D01*
X1418000Y724000D01*
G01X1415575Y729000D02*
X1418000D01*
G01X1415575Y733000D02*
Y729000D01*
G01X1415544Y720894D02*
X1417969D01*
G01X1415575Y741000D02*
X1417000D01*
X1418000Y740000D01*
G01X1415575Y745000D02*
X1418000D01*
G01X1415575Y749000D02*
Y745000D01*
G01X1407482Y750853D02*
X1407629Y751000D01*
X1416594D01*
X1418594Y749000D01*
X1420425D01*
G01X1415575Y757000D02*
X1420425D01*
G01X1415575Y753000D02*
X1420425D01*
G01X1412425Y761000D02*
X1410000D01*
G01X1412448Y765343D02*
Y761023D01*
X1412425Y761000D01*
G01X1415575D02*
X1418000D01*
G01X1415598Y765343D02*
X1418023D01*
G01X1409115Y773520D02*
X1423347D01*
X1426981Y777154D01*
X1433418D01*
X1435000Y775572D01*
Y774970D01*
X1435470Y774500D01*
X1437425D01*
G01X1406867Y783273D02*
X1421243D01*
X1425352Y779164D01*
X1431779D01*
X1432575Y779960D01*
Y782500D01*
G01X1414597Y792375D02*
X1418426Y788546D01*
X1430461D01*
X1432415Y790500D01*
X1432575D01*
G01X1402517Y809292D02*
X1402417Y809392D01*
Y811692D01*
G01X1606190Y803774D02*
X1601414Y808550D01*
Y822819D01*
X1571624Y852609D01*
X1442845D01*
X1437079Y858375D01*
X1430116D01*
X1420051Y848310D01*
Y813175D01*
X1410593Y803717D01*
X1404942D01*
X1402517Y806142D01*
G01X1603966Y816799D02*
Y821901D01*
X1572138Y853729D01*
X1443359D01*
X1437558Y859530D01*
X1429637D01*
X1418896Y848789D01*
Y814479D01*
X1410559Y806142D01*
X1406483D01*
G01Y809292D02*
Y811717D01*
G01X1401583Y832491D02*
X1404574Y829500D01*
X1406425D01*
X1407925Y828000D01*
G01X1411075D02*
X1413500D01*
G01X1411024Y823934D02*
X1413449D01*
G01X1411173Y815683D02*
X1414659D01*
X1417762Y818786D01*
Y849259D01*
X1429167Y860664D01*
X1438028D01*
X1443843Y854849D01*
X1572622D01*
X1605938Y821533D01*
Y819936D01*
X1606709Y819165D01*
G01X1401300Y820485D02*
X1401230Y820415D01*
Y819388D01*
X1404435Y816183D01*
X1407523D01*
X1408023Y815683D01*
G01X1602862Y829738D02*
X1576631Y855969D01*
X1444357D01*
X1438507Y861819D01*
X1428688D01*
X1416607Y849738D01*
Y821140D01*
X1415284Y819817D01*
X1410977D01*
G01X1407827D02*
X1405502D01*
X1405402Y819917D01*
G01X1407925Y840000D02*
X1402000D01*
G01X1407925Y844000D02*
X1405500D01*
G01X1407925Y836000D02*
X1405500D01*
G01X1411075Y840000D02*
X1413500D01*
G01X1411075Y836000D02*
X1413500D01*
G01X1411075Y832000D02*
X1413500D01*
G01X1411075Y844000D02*
X1413500D01*
G01X1407925Y848000D02*
X1402000D01*
G01X1402500Y856000D02*
X1407925D01*
G01Y860000D02*
X1405500D01*
G01X1411075Y848000D02*
X1413500D01*
G01X1411075Y860000D02*
X1413500D01*
G01X1411075Y856000D02*
X1413500D01*
G01X1411075Y852000D02*
X1413500D01*
G01X1407925Y880000D02*
X1405500D01*
G01X1407925Y868000D02*
X1405500D01*
G01X1407925Y876000D02*
X1402000D01*
G01X1407925Y864000D02*
X1402000D01*
G01X1411075Y876000D02*
X1413500D01*
G01X1417797Y879501D02*
X1411574D01*
X1411075Y880000D01*
G01Y872000D02*
X1413500D01*
G01X1411075Y868000D02*
X1413500D01*
G01X1411075Y864000D02*
X1413500D01*
G01X1407925Y888000D02*
X1405500D01*
G01X1407925Y884000D02*
X1402000D01*
G01X1407925Y896000D02*
X1405500D01*
G01X1407925Y892000D02*
X1402000D01*
G01X1411075Y896000D02*
X1417081D01*
G01X1411075Y892000D02*
X1413500D01*
G01X1411075Y884000D02*
X1413500D01*
G01X1411075Y888000D02*
X1413500D01*
G01X1407925Y904000D02*
X1405500D01*
G01X1407925Y900000D02*
X1402000D01*
G01X1407739Y915186D02*
Y911137D01*
G01X1411075Y904000D02*
X1413500D01*
G01X1411075Y900000D02*
X1413500D01*
G01X1407739Y915186D02*
X1404760D01*
G01X1401000Y923075D02*
Y925789D01*
G01X1416244Y942285D02*
Y946598D01*
X1421209Y951563D01*
X1425006D01*
G01X1402265Y992191D02*
Y990465D01*
X1401265Y989465D01*
G01X1406265Y992191D02*
Y990465D01*
X1407265Y989465D01*
G01X1410993Y988403D02*
X1410994Y988404D01*
Y992307D01*
G01X1407265Y989465D02*
X1408505Y990705D01*
X1409392D01*
X1410994Y992307D01*
G01X1414143Y988403D02*
Y985486D01*
G01X1406265Y995341D02*
X1405180Y996426D01*
Y1000497D01*
G01X1423190Y1004766D02*
Y1003480D01*
X1422383Y1002673D01*
X1417356D01*
X1415263Y1004766D01*
X1415190D01*
G01X1405821Y1011963D02*
X1413018Y1004766D01*
X1415190D01*
G01X1412698Y997590D02*
X1413522Y996766D01*
X1415190D01*
G01X1412609Y1008766D02*
X1415190D01*
G01X1422563Y998754D02*
X1416022D01*
X1415190Y999586D01*
Y1000766D01*
G01X1409748Y1004176D02*
X1413158Y1000766D01*
X1415190D01*
G01X1406216Y1020491D02*
X1406457Y1020250D01*
X1415194D01*
G01X1409837Y1015420D02*
X1412991Y1012266D01*
X1415190D01*
G01Y1016266D02*
Y1014753D01*
X1415690Y1014253D01*
X1422690D01*
X1423190Y1014753D01*
Y1016266D01*
G01X1412759D02*
X1415190D01*
G01X1423190Y1030766D02*
Y1032518D01*
X1422471Y1033237D01*
X1415690D01*
X1415190Y1032737D01*
Y1030766D01*
G01X1410397Y1027097D02*
X1414066Y1030766D01*
X1415190D01*
G01X1426593Y1503302D02*
X1424960Y1504935D01*
X1416748D01*
X1413583Y1508100D01*
Y1513375D01*
X1414932Y1514724D01*
X1416684D01*
G01X1411686Y1539557D02*
X1413100Y1538143D01*
X1416396D01*
G01X1411586Y1543379D02*
X1407753D01*
X1407747Y1543385D01*
G01X1404239Y1543378D02*
X1407740D01*
X1407747Y1543385D01*
G01X1416319Y1543379D02*
X1411586D01*
G01X1416589Y1548217D02*
Y1543649D01*
X1416319Y1543379D01*
G01X1411194Y1562235D02*
Y1557969D01*
X1412747Y1556416D01*
X1415241D01*
G01X1420995Y1558072D02*
X1419339Y1556416D01*
X1415241D01*
G01X1436448Y1549610D02*
X1433959Y1552099D01*
X1417156D01*
X1411586Y1546529D01*
G01X1411094Y1566057D02*
X1407261D01*
X1407255Y1566063D01*
G01D02*
X1403754D01*
X1403747Y1566056D01*
G01X1411094Y1566057D02*
X1412831Y1564320D01*
X1415962D01*
G01X1415947Y1569486D02*
Y1567704D01*
X1415962Y1567689D01*
Y1564320D01*
G01X1428081Y1563978D02*
Y1569225D01*
X1425283Y1572023D01*
X1418484D01*
X1415947Y1569486D01*
G01X1444598Y1566170D02*
X1439468Y1571300D01*
X1427708D01*
X1425481Y1573527D01*
X1415414D01*
X1411094Y1569207D01*
G01X1431358Y92874D02*
X1436089D01*
G01X1431358Y99961D02*
X1427131D01*
G01X1427181Y95236D02*
X1431358D01*
G01X1426410Y328996D02*
X1430531D01*
X1434166Y325361D01*
G01X1426410Y326437D02*
X1428692D01*
X1434268Y320861D01*
X1437064D01*
G01X1426410Y339232D02*
X1434164D01*
G01X1426410Y336673D02*
X1439712D01*
G01X1426410Y341792D02*
X1433273D01*
X1438314Y346833D01*
X1440420D01*
G01X1426410Y331555D02*
X1432016D01*
X1433710Y329861D01*
X1438829D01*
G01X1426410Y334114D02*
X1434038D01*
G01X1426410Y346910D02*
X1430390D01*
X1430890Y347410D01*
Y350921D01*
X1434878Y354909D01*
X1441180D01*
G01X1416912Y386903D02*
X1420438Y383377D01*
Y354102D01*
X1422512Y352028D01*
X1426410D01*
G01X1416470Y381397D02*
X1418677Y379190D01*
Y353030D01*
X1422238Y349469D01*
X1426410D01*
G01Y344351D02*
X1430652D01*
X1432621Y346320D01*
Y347840D01*
X1433557Y350100D01*
X1435818Y352361D01*
G01X1431019Y440069D02*
X1435019D01*
G01X1427117Y443071D02*
X1427019Y442973D01*
Y440069D01*
G01X1417856Y451376D02*
Y448419D01*
G01D02*
X1417903Y448372D01*
Y445494D01*
G01X1432414Y459371D02*
Y456431D01*
G01Y448557D02*
Y445505D01*
X1429980Y443071D01*
X1427117D01*
G01X1427484Y462004D02*
X1430446Y459042D01*
Y456431D01*
G01X1431484Y467634D02*
Y470045D01*
G01X1422903Y464344D02*
X1418903D01*
G01Y461419D02*
Y464344D01*
G01X1431484Y464484D02*
Y460301D01*
X1432414Y459371D01*
G01X1427484Y464484D02*
Y462004D01*
G01X1419414Y495649D02*
X1416413D01*
G01X1430944Y599650D02*
Y594976D01*
X1435119Y590801D01*
G01X1430944Y602800D02*
Y605443D01*
G01X1428952Y636236D02*
Y632038D01*
X1430175Y630815D01*
Y627852D01*
G01X1432452Y636236D02*
X1428952D01*
G01X1435952D02*
X1432452D01*
G01X1430175Y627852D02*
X1428326Y626003D01*
Y624724D01*
G01X1422420Y624823D02*
Y628661D01*
X1425452Y631693D01*
Y633473D01*
G01D02*
Y636236D01*
G01X1485075Y693630D02*
X1487801Y690904D01*
Y675720D01*
X1482911Y670830D01*
X1467375D01*
X1461765Y676440D01*
X1442778D01*
X1440450Y674112D01*
X1426615D01*
G01X1441984Y691602D02*
X1439818D01*
X1437762Y689546D01*
X1434046D01*
X1432250Y687750D01*
X1431750D01*
X1429000Y685000D01*
G01D02*
X1423575D01*
G01Y681000D02*
X1429000D01*
X1434992Y686992D01*
X1437738D01*
G01X1418000Y685000D02*
X1420425D01*
G01X1418000Y681000D02*
X1420425D01*
G01X1418000Y696000D02*
X1419000Y697000D01*
X1420425D01*
G01X1418000Y701000D02*
X1420425D01*
G01X1433464Y692658D02*
X1431986D01*
X1428328Y689000D01*
X1423575D01*
G01X1420425D02*
X1418000D01*
G01X1423575Y701000D02*
X1430999D01*
X1431838Y701839D01*
X1433053D01*
G01X1423575Y697000D02*
X1424835Y698260D01*
X1430759D01*
X1431779Y699280D01*
X1437533D01*
G01X1423575Y705000D02*
X1431000D01*
X1431602Y704398D01*
X1437533D01*
G01X1420425Y705000D02*
X1418000D01*
G01X1441984Y712468D02*
X1438086D01*
X1432554Y718000D01*
X1428000D01*
X1427000Y719000D01*
X1420925D01*
X1420425Y718500D01*
Y717000D01*
G01X1418000D02*
X1420425D01*
G01Y709000D02*
Y710500D01*
X1420925Y711000D01*
X1429155D01*
X1431522Y708633D01*
G01D02*
X1433198Y706957D01*
X1441984D01*
G01X1420425Y713000D02*
Y714500D01*
X1420925Y715000D01*
X1432000D01*
X1434000Y713000D01*
Y712958D01*
G01X1418000Y724000D02*
X1419000Y725000D01*
X1420425D01*
G01X1418000Y729000D02*
X1420425D01*
G01X1430289Y734961D02*
X1428328Y733000D01*
X1423575D01*
G01X1420425D02*
X1418000D01*
G01X1441984Y735602D02*
X1439818D01*
X1437762Y733546D01*
X1434046D01*
X1432250Y731750D01*
X1431750D01*
X1429000Y729000D01*
G01D02*
X1423575D01*
G01Y725000D02*
X1429000D01*
X1434992Y730992D01*
X1437738D01*
G01X1418000Y740000D02*
X1419000Y741000D01*
X1420425D01*
G01X1418000Y745000D02*
X1420425D01*
G01X1441984Y738161D02*
X1433489D01*
X1430289Y734961D01*
G01X1423575Y741000D02*
X1429499D01*
X1431779Y743280D01*
X1437533D01*
G01X1423575Y745000D02*
X1430999D01*
X1431838Y745839D01*
X1433153D01*
G01X1423575Y749000D02*
X1431000D01*
X1431602Y748398D01*
X1437533D01*
G01X1420425Y757000D02*
Y758500D01*
X1420925Y759000D01*
X1432000D01*
X1434000Y757000D01*
Y756958D01*
G01X1420425Y753000D02*
Y754500D01*
X1420925Y755000D01*
X1430958D01*
X1434000Y751958D01*
G01X1420425Y761000D02*
Y762500D01*
X1420925Y763000D01*
X1427000D01*
X1428000Y762000D01*
X1436282D01*
X1437314Y760968D01*
Y757100D01*
X1437946Y756468D01*
X1441984D01*
G01X1418000Y761000D02*
X1420425D01*
G01X1429425Y802500D02*
X1427000D01*
G01X1429425Y846500D02*
X1427000D01*
G01X1435043Y874694D02*
X1433592Y875295D01*
X1430247D01*
G01X1435082Y869475D02*
X1434262Y870295D01*
X1430247D01*
G01X1423190Y905295D02*
X1429617D01*
G01X1418139Y939292D02*
Y938182D01*
X1416802Y936845D01*
G01X1428212Y933016D02*
X1422466D01*
X1421289Y934193D01*
Y939292D01*
G01X1439234Y940850D02*
X1436322D01*
X1433342Y937870D01*
Y934688D01*
X1431670Y933016D01*
X1428212D01*
G01X1428096Y947595D02*
Y943402D01*
X1428108Y943390D01*
G01D02*
X1430059Y941439D01*
X1432818D01*
G01X1419337Y942285D02*
Y946635D01*
X1420297Y947595D01*
X1424946D01*
G01X1430839Y965546D02*
Y956944D01*
X1435881Y951902D01*
G01X1432806Y947059D02*
X1428302Y951563D01*
X1428156D01*
G01X1419446Y977192D02*
X1421947Y979693D01*
Y983544D01*
X1427415Y989012D01*
X1428977D01*
X1432519Y992554D01*
Y1001519D01*
G01X1423190Y1000766D02*
Y999381D01*
X1422563Y998754D01*
G01D02*
X1423190Y998127D01*
Y996766D01*
G01X1426340D02*
X1428864D01*
G01X1432519Y1001519D02*
X1431187Y1002851D01*
X1428255D01*
X1426340Y1004766D01*
G01D02*
X1429058D01*
X1431749Y1007457D01*
Y1023511D01*
X1426340Y1028920D01*
Y1030766D01*
G01X1423190Y1016266D02*
Y1020266D01*
G01X1426340D02*
X1428823D01*
G01X1426340Y1030766D02*
X1428341D01*
X1435061Y1037486D01*
X1443459D01*
G01X1432258Y1410890D02*
Y1414600D01*
G01X1426253Y1410852D02*
X1432220D01*
X1432258Y1410890D01*
G01X1426552Y1498545D02*
Y1494712D01*
X1426546Y1494706D01*
G01D02*
Y1491205D01*
X1426553Y1491198D01*
G01X1429546Y1515413D02*
Y1513119D01*
X1427959Y1511532D01*
X1421560D01*
G01D02*
X1416726D01*
X1416684Y1511574D01*
G01X1429546Y1508327D02*
Y1505563D01*
X1431788Y1503321D01*
Y1503314D01*
G01D02*
Y1500059D01*
X1430374Y1498645D01*
G01X1432499Y1508327D02*
X1429546D01*
G01X1426552Y1498545D02*
X1426593Y1498586D01*
Y1503302D01*
G01X1421964Y1502813D02*
Y1499983D01*
X1423402Y1498545D01*
G01X1429516Y1524252D02*
Y1520366D01*
X1429514Y1520364D01*
G01D02*
Y1515445D01*
X1429546Y1515413D01*
G01X1429516Y1524252D02*
Y1527379D01*
X1429587Y1527450D01*
G01X1426593Y1515413D02*
X1425202Y1516804D01*
X1418764D01*
X1416684Y1514724D01*
G01X1433405Y1540417D02*
X1428486D01*
X1428454Y1540385D01*
G01X1424573Y1548351D02*
X1426307Y1546617D01*
Y1541680D01*
X1427602Y1540385D01*
X1428454D01*
G01X1416396Y1538143D02*
Y1538177D01*
X1418604Y1540385D01*
X1421368D01*
G01D02*
Y1537432D01*
G01X1428454Y1543338D02*
Y1548642D01*
X1426210Y1550886D01*
X1419258D01*
X1416589Y1548217D01*
G01X1424573Y1548351D02*
X1419873D01*
X1419739Y1548217D01*
G01X1423817Y1569486D02*
X1425738Y1567565D01*
Y1562801D01*
X1427490Y1561049D01*
X1428057D01*
X1428081Y1561025D01*
G01D02*
X1430843D01*
X1432913Y1563095D01*
G01X1420995Y1561025D02*
Y1558072D01*
G01X1419097Y1569486D02*
X1423817D01*
G01X1451920Y98198D02*
X1447920D01*
G01X1436089Y92874D02*
Y95018D01*
X1437483Y96412D01*
X1446259D01*
X1447920Y98073D01*
Y98198D01*
G01X1448610Y151540D02*
Y147540D01*
G01X1451301Y148277D02*
X1451029D01*
X1450292Y147540D01*
X1448610D01*
G01X1446698Y265701D02*
X1448026Y264373D01*
Y262685D01*
G01X1450298Y269603D02*
Y267575D01*
X1449602Y266879D01*
X1447876D01*
X1446698Y265701D01*
G01X1447079Y284908D02*
X1451079D01*
G01X1450298Y277477D02*
Y279751D01*
X1448333Y281716D01*
G01X1451079Y284908D02*
Y283104D01*
X1449691Y281716D01*
X1448333D01*
G01X1446282Y325361D02*
X1447861D01*
X1448948Y326448D01*
G01X1446282Y320861D02*
X1449060D01*
G01X1434166Y325361D02*
X1443132D01*
G01X1437064Y320861D02*
X1443132D01*
G01X1446282Y329861D02*
X1449060D01*
G01X1446282Y343361D02*
X1448275D01*
X1448822Y343908D01*
Y345324D01*
G01X1446282Y334361D02*
X1447283D01*
X1448734Y332910D01*
G01D02*
X1450185Y334361D01*
X1453132D01*
G01Y338861D02*
X1450214D01*
X1448500Y340575D01*
G01D02*
X1446606D01*
X1446282Y340251D01*
Y338861D01*
G01X1434164Y339232D02*
X1438293Y343361D01*
X1443132D01*
G01X1439712Y336673D02*
X1441900Y338861D01*
X1443132D01*
G01X1438829Y329861D02*
X1443132D01*
G01X1434038Y334114D02*
X1442885D01*
X1443132Y334361D01*
G01Y356861D02*
Y355234D01*
X1443632Y354734D01*
X1451005D01*
X1453132Y356861D01*
G01X1441180Y354909D02*
X1443132Y356861D01*
G01X1446282Y347861D02*
Y349051D01*
X1446672Y349441D01*
X1448572D01*
G01D02*
X1450152Y347861D01*
X1453132D01*
G01X1448822Y345324D02*
X1450785Y343361D01*
X1453132D01*
G01X1446282Y352361D02*
X1449060D01*
G01X1440420Y346833D02*
X1441448Y347861D01*
X1443132D01*
G01X1435818Y352361D02*
X1443132D01*
G01X1506457Y346798D02*
X1503851D01*
X1498709Y351940D01*
X1469808D01*
X1460963Y360785D01*
X1447502D01*
G01X1434997Y442603D02*
X1435019Y442581D01*
Y440069D01*
G01X1434382Y448557D02*
Y445560D01*
X1434997Y444945D01*
Y442603D01*
G01X1436930Y461818D02*
Y460694D01*
X1434382Y458146D01*
Y456431D01*
G01X1435484Y464484D02*
X1436930Y463038D01*
Y461818D01*
G01X1442944Y599650D02*
X1443775Y598819D01*
Y596089D01*
G01D02*
Y593360D01*
G01X1445743D02*
Y595251D01*
X1447274Y596782D01*
X1448994D01*
G01X1446944Y599650D02*
X1450944D01*
G01X1447712Y593360D02*
X1451575D01*
X1454944Y596729D01*
G01X1435119Y590801D02*
X1439247D01*
G01X1434944Y602800D02*
Y605443D01*
G01X1441806Y593360D02*
Y594108D01*
X1441064Y594850D01*
X1437224D01*
X1434944Y597130D01*
G01D02*
Y599650D01*
G01X1438944Y602800D02*
Y605637D01*
G01X1442944Y602800D02*
X1438944D01*
G01X1435952Y639386D02*
Y642184D01*
G01X1441984Y694161D02*
X1434967D01*
X1433464Y692658D01*
G01X1437738Y686992D02*
X1439789Y689043D01*
X1441984D01*
G01X1437533Y699280D02*
X1441984D01*
G01X1437533Y704398D02*
X1441984D01*
G01X1434000Y712958D02*
X1437442Y709516D01*
X1441984D01*
G01X1433053Y701839D02*
X1441984D01*
G01X1437738Y730992D02*
X1439789Y733043D01*
X1441984D01*
G01X1437533Y743280D02*
X1441984D01*
G01X1433153Y745839D02*
X1441984D01*
G01X1437533Y748398D02*
X1441984D01*
G01X1432575Y766500D02*
X1434000D01*
X1435000Y765500D01*
G01D02*
X1436000Y766500D01*
X1437425D01*
G01X1434000Y756958D02*
X1434042D01*
X1437484Y753516D01*
X1441984D01*
G01X1434000Y751958D02*
X1435001Y750957D01*
X1441984D01*
G01X1440575Y766500D02*
X1446000D01*
X1451992Y772492D01*
X1454738D01*
G01X1432575Y770500D02*
X1435000D01*
G01X1432575Y774500D02*
Y770500D01*
G01X1435000D02*
X1437425D01*
G01Y782500D02*
X1432575D01*
G01X1440575Y774500D02*
X1445328D01*
X1447289Y776461D01*
G01D02*
X1450489Y779661D01*
X1458984D01*
G01X1454533Y784780D02*
X1448779D01*
X1446499Y782500D01*
X1440575D01*
G01Y770500D02*
X1446000D01*
G01D02*
X1448750Y773250D01*
X1449250D01*
X1451046Y775046D01*
X1454762D01*
X1456818Y777102D01*
X1458984D01*
G01X1432575Y786500D02*
Y790500D01*
G01X1437425Y786500D02*
X1432575D01*
G01X1440575Y790500D02*
X1448000D01*
X1448602Y789898D01*
X1454533D01*
G01X1437425Y794500D02*
Y796000D01*
X1437925Y796500D01*
X1447958D01*
X1451000Y793458D01*
G01X1432575Y794500D02*
X1437425D01*
G01Y798500D02*
Y800000D01*
X1437925Y800500D01*
X1449000D01*
X1451000Y798500D01*
Y798458D01*
G01X1432575Y798500D02*
X1437425D01*
G01X1450253Y787339D02*
X1448838D01*
X1447999Y786500D01*
X1440575D01*
G01X1432575Y814500D02*
X1435000D01*
G01X1432575Y818500D02*
Y814500D01*
G01X1435000D02*
X1437425D01*
G01X1432575Y810500D02*
X1434000D01*
X1435000Y809500D01*
G01D02*
X1436000Y810500D01*
X1437425D01*
G01X1432575Y802500D02*
X1435000D01*
G01X1458984Y797968D02*
X1454946D01*
X1449414Y803500D01*
X1445000D01*
X1444000Y804500D01*
X1437925D01*
X1437425Y804000D01*
Y802500D01*
G01X1435000D02*
X1437425D01*
G01X1440575Y814500D02*
X1446500D01*
X1453102Y821102D01*
G01X1458984Y818543D02*
X1455043D01*
X1447000Y810500D01*
G01D02*
X1440575D01*
G01X1432575Y830500D02*
X1434975D01*
G01X1432575Y834500D02*
Y830500D01*
G01X1434975D02*
X1437425D01*
G01X1432575Y826500D02*
X1434000D01*
X1435000Y825500D01*
G01D02*
X1436000Y826500D01*
X1437425D01*
G01Y818500D02*
X1435000D01*
G01X1440575Y830500D02*
X1446841D01*
X1447680Y831339D01*
X1454541D01*
G01X1440575Y826500D02*
X1453102D01*
G01X1440575Y818500D02*
X1447000D01*
G01D02*
X1452161Y823661D01*
X1458984D01*
G01X1437425Y834500D02*
X1435000D01*
G01X1437425Y846500D02*
X1435000D01*
G01D02*
X1432575D01*
G01X1437425D02*
Y847900D01*
X1437925Y848400D01*
X1449114D01*
X1455546Y841968D01*
X1458984D01*
G01X1432575Y842500D02*
X1437425D01*
G01D02*
X1437500D01*
X1439500Y844500D01*
X1449000D01*
G01X1432575Y838500D02*
X1437425D01*
G01D02*
Y840000D01*
X1437925Y840500D01*
X1448576D01*
X1452619Y836457D01*
G01X1458984Y833898D02*
X1450532D01*
X1449930Y834500D01*
X1448000D01*
G01D02*
X1440575D01*
G01X1448726Y864400D02*
X1453771Y859355D01*
X1495926D01*
X1503989Y867418D01*
X1512712D01*
G01X1491656Y930359D02*
X1488641D01*
X1487500Y931500D01*
Y933500D01*
X1486438Y934562D01*
X1480930D01*
X1474170Y927802D01*
X1467697D01*
X1462520Y922625D01*
X1442026D01*
X1435482Y929169D01*
Y935966D01*
X1435516Y936000D01*
G01X1432818Y941439D02*
X1434283D01*
X1436254Y943410D01*
X1439234D01*
G01Y945969D02*
X1433896D01*
X1432806Y947059D01*
G01X1435669Y1001519D02*
X1435670Y1001518D01*
X1440037D01*
G01X1435669Y1005366D02*
Y1001519D01*
G01X1443187Y1001518D02*
Y1007938D01*
X1440869Y1010256D01*
G01X1443428Y1029000D02*
Y1023064D01*
G01X1440869Y1010256D02*
Y1014402D01*
G01X1443459Y1034336D02*
Y1029031D01*
X1443428Y1029000D01*
G01X1436258Y1410890D02*
Y1412858D01*
X1438000Y1414600D01*
X1439258D01*
G01X1443103Y1527201D02*
X1443066Y1527238D01*
Y1542992D01*
X1436448Y1549610D01*
G01X1437293Y1540415D02*
X1433407D01*
X1433405Y1540417D01*
G01X1437293Y1540415D02*
X1441145D01*
G01X1446135Y1530876D02*
Y1564633D01*
X1444598Y1566170D01*
G01X1443769Y1562173D02*
X1440112Y1558516D01*
X1436792D01*
G01X1436801Y1563093D02*
X1432915D01*
X1432913Y1563095D01*
G01X1436801Y1563093D02*
X1440153D01*
G01X1734069Y1710189D02*
X1440740D01*
X1436250Y1714679D01*
Y1715699D01*
X1440740Y1720189D01*
X1734069D01*
G01X1451510Y30393D02*
Y32845D01*
X1452717Y34052D01*
G01X1462675Y32645D02*
X1458474D01*
X1457347Y31518D01*
G01D02*
X1456222Y30393D01*
X1454660D01*
G01X1462675Y27645D02*
X1459049D01*
X1457829Y26425D01*
G01D02*
X1457797Y26393D01*
X1454660D01*
G01X1451510D02*
X1449685Y28218D01*
Y34228D01*
G01X1451226Y39193D02*
Y35769D01*
X1449685Y34228D01*
G01X1454376Y39193D02*
Y42231D01*
X1455013Y42868D01*
Y43128D01*
G01X1460466Y76587D02*
X1462866D01*
G01X1460466Y72615D02*
X1460494Y72587D01*
X1462866D01*
G01X1462821Y68581D02*
Y69564D01*
X1465844Y72587D01*
X1466016D01*
G01X1462821Y80581D02*
Y79618D01*
X1465852Y76587D01*
X1466016D01*
G01X1461905Y100625D02*
X1463271Y99259D01*
X1466827D01*
G01X1457424Y97475D02*
X1454924D01*
G01X1457424Y100625D02*
X1461905D01*
G01X1457424Y105087D02*
Y100625D01*
G01X1462484Y141247D02*
X1459559D01*
G01X1479903Y142648D02*
X1478381D01*
X1476233Y140500D01*
X1466031D01*
X1465284Y141247D01*
X1462484D01*
G01X1456409D02*
X1452580D01*
G01X1454178Y146461D02*
X1453921Y146204D01*
Y143740D01*
G01D02*
X1452580Y142399D01*
Y141247D01*
G01X1454178Y149414D02*
X1452438D01*
X1451301Y148277D01*
G01X1466071Y152373D02*
X1466065Y152367D01*
X1461264D01*
G01X1466071Y149768D02*
X1465717Y149414D01*
X1461264D01*
G01X1464628Y168713D02*
Y171523D01*
G01X1464158Y188362D02*
Y192490D01*
G01D02*
Y193902D01*
X1466921Y196665D01*
X1473007D01*
G01X1452026Y259535D02*
Y256303D01*
G01X1451785Y265896D02*
Y264086D01*
X1452026Y263845D01*
Y262685D01*
G01X1456801Y266114D02*
Y264678D01*
X1456026Y263903D01*
Y262685D01*
G01X1452266Y269603D02*
Y267599D01*
X1451785Y267118D01*
Y265896D01*
G01X1454274Y281982D02*
X1452266Y279974D01*
Y277477D01*
G01X1454234Y269603D02*
Y268681D01*
X1456801Y266114D01*
G01X1455079Y284908D02*
Y282787D01*
X1454274Y281982D01*
G01X1448948Y326448D02*
X1450035Y325361D01*
X1453132D01*
G01X1449060Y320861D02*
X1453132D01*
G01X1449060Y329861D02*
X1453132D01*
G01X1449060Y352361D02*
X1453132D01*
G01X1448994Y596782D02*
X1450444D01*
X1450944Y597282D01*
Y599650D01*
G01X1458944D02*
X1454944D01*
G01Y596729D02*
Y599650D01*
G01X1465016Y727532D02*
X1465048Y727500D01*
X1472000D01*
G01X1454738Y772492D02*
X1456789Y774543D01*
X1458984D01*
G01X1454533Y789898D02*
X1458984D01*
G01X1451000Y793458D02*
X1452001Y792457D01*
X1458984D01*
G01X1451000Y798458D02*
X1451042D01*
X1454484Y795016D01*
X1458984D01*
G01Y787339D02*
X1450253D01*
G01X1458984Y784780D02*
X1454533D01*
G01X1453102Y821102D02*
X1458984D01*
G01X1454541Y831339D02*
X1458984D01*
G01X1453102Y826500D02*
X1455382Y828780D01*
X1458984D01*
G01X1449000Y844500D02*
X1454484Y839016D01*
X1458984D01*
G01X1452619Y836457D02*
X1458984D01*
G01X1468043Y905295D02*
X1462500D01*
G01X1461773Y932887D02*
Y928179D01*
X1461771Y928177D01*
G01X1453800Y940850D02*
X1457832D01*
X1459139Y939543D01*
X1461585D01*
G01D02*
X1466625D01*
G01X1461441Y944864D02*
X1459500D01*
X1458046Y943410D01*
X1453800D01*
G01X1466422Y943496D02*
X1464642D01*
X1463274Y944864D01*
X1461441D01*
G01X1453800Y938291D02*
Y936570D01*
X1456669Y933701D01*
G01D02*
X1457483Y932887D01*
X1461773D01*
G01X1461888Y936055D02*
Y936040D01*
X1464923Y933005D01*
Y932887D01*
G01X1455939Y1009260D02*
X1458392D01*
X1458892Y1008760D01*
Y1007522D01*
G01D02*
Y1004270D01*
X1459813Y1003349D01*
X1461918D01*
G01X1455959Y1004541D02*
X1454325D01*
X1453358Y1005508D01*
Y1011581D01*
X1453990Y1012213D01*
X1455939D01*
G01X1462696Y1021177D02*
X1462317Y1021556D01*
Y1025227D01*
G01X1463025Y1015166D02*
Y1018307D01*
G01D02*
Y1020848D01*
X1462696Y1021177D01*
G01X1463025Y1012213D02*
X1464781D01*
X1465258Y1012690D01*
Y1014690D01*
X1464782Y1015166D01*
X1463025D01*
G01X1455939Y1012213D02*
X1457802D01*
X1459267Y1013678D01*
G01D02*
Y1017124D01*
X1458551Y1017840D01*
Y1021048D01*
G01X1456280Y1023405D02*
X1455401Y1022526D01*
Y1021048D01*
G01X1459683Y1028377D02*
X1462317D01*
G01X1474746Y60513D02*
Y64722D01*
G01D02*
Y72553D01*
X1472532Y74767D01*
X1468196D01*
X1466016Y72587D01*
G01X1477606Y60438D02*
Y64422D01*
X1477306Y64722D01*
G01D02*
Y72967D01*
X1473686Y76587D01*
X1466016D01*
G01X1474874Y85731D02*
X1474746Y85603D01*
Y81848D01*
G01X1478428Y86046D02*
X1477306Y84924D01*
Y81848D01*
G01X1480160D02*
Y82885D01*
X1483287Y86012D01*
G01X1475431Y88801D02*
X1474874Y88244D01*
Y85731D01*
G01X1479380Y88729D02*
Y86998D01*
X1478428Y86046D01*
G01X1475431Y91951D02*
Y94351D01*
G01X1479380Y91879D02*
Y94279D01*
G01X1466278Y112083D02*
Y112402D01*
X1468364Y114488D01*
G01X1470567Y107921D02*
Y103621D01*
G01X1482609Y121558D02*
Y123126D01*
X1481452Y124283D01*
X1479058D01*
G01D02*
X1479090Y124315D01*
Y127525D01*
X1478867Y127748D01*
G01X1474716Y157370D02*
Y148980D01*
X1475945Y147754D01*
X1478056D01*
G01X1484867Y130898D02*
X1485000Y131031D01*
Y145044D01*
X1482294Y147754D01*
X1478056D01*
G01X1471495Y158195D02*
Y148325D01*
X1470995Y147825D01*
X1466640D01*
X1466071Y147256D01*
Y145768D01*
G01X1469221D02*
Y143868D01*
X1468871Y143518D01*
X1466971D01*
G01D02*
Y142392D01*
X1467198Y142165D01*
X1475365D01*
X1478000Y144800D01*
X1481337D01*
X1481900Y144237D01*
Y140240D01*
X1481355Y139695D01*
X1479903D01*
G01X1478056Y150904D02*
Y154865D01*
G01D02*
X1482993D01*
G01X1574100Y158400D02*
X1513065D01*
X1505921Y165544D01*
X1478844D01*
X1471495Y158195D01*
G01X1466071Y152373D02*
Y149768D01*
G01X1470023Y178560D02*
Y179904D01*
G01D02*
X1470784Y180665D01*
X1473007D01*
G01Y176665D02*
Y180665D01*
G01X1470023Y179904D02*
Y180204D01*
X1468361Y181866D01*
X1466717D01*
G01X1467778Y168713D02*
X1472959D01*
X1473007Y168665D01*
G01D02*
Y172665D01*
G01D02*
X1470086D01*
G01D02*
X1466717Y176034D01*
Y179897D01*
G01Y185803D02*
Y189278D01*
X1467624Y190185D01*
X1469433D01*
G01D02*
Y191730D01*
X1470368Y192665D01*
X1473007D01*
G01Y184665D02*
X1472176Y183834D01*
X1469913D01*
G01D02*
X1466717D01*
G01X1476157Y192665D02*
X1478800D01*
G01X1476157Y196665D02*
X1478800D01*
G01X1476157Y188665D02*
X1478182D01*
X1478913Y187934D01*
Y186778D01*
G01D02*
Y185398D01*
X1478180Y184665D01*
X1476157D01*
G01X1473102Y212864D02*
X1472693Y212455D01*
X1470292D01*
G01X1466328Y213166D02*
X1468014D01*
X1468725Y212455D01*
X1470292D01*
G01X1473102Y204864D02*
Y208864D01*
G01X1470226Y207037D02*
X1472053Y208864D01*
X1473102D01*
G01X1466328Y211197D02*
X1467781D01*
X1470226Y208752D01*
Y207037D01*
G01X1470203Y200864D02*
X1473102D01*
G01X1466328Y209229D02*
X1467050D01*
X1467638Y208641D01*
Y203429D01*
X1470203Y200864D01*
G01X1476252Y208864D02*
X1478832D01*
G01X1466328Y217103D02*
X1468341D01*
X1473102Y221864D01*
G01X1473099Y225719D02*
Y221867D01*
X1473102Y221864D01*
G01X1475101Y228631D02*
X1473099Y226629D01*
Y225719D01*
G01X1487337Y242078D02*
X1480065D01*
X1477577Y244566D01*
Y255458D01*
X1480999Y258880D01*
X1531609D01*
G01X1480702Y368516D02*
X1485142Y364076D01*
X1500184D01*
X1516838Y347422D01*
G01X1468372Y673812D02*
X1483403D01*
X1485075Y675484D01*
Y677630D01*
G01X1465016Y683532D02*
X1472665D01*
X1475264Y680933D01*
G01D02*
X1478567Y677630D01*
X1481925D01*
G01X1485075Y689630D02*
Y690760D01*
X1484183Y691652D01*
X1476999D01*
X1476794Y691447D01*
G01X1479500Y689630D02*
X1481925D01*
G01X1465016Y686484D02*
X1471984D01*
X1473700Y688200D01*
X1478070D01*
X1479500Y689630D01*
G01X1465016Y689043D02*
X1470913D01*
X1479500Y697630D01*
G01D02*
X1481925D01*
G01X1465016Y704398D02*
X1476716D01*
G01D02*
X1484575D01*
X1485075Y704898D01*
Y706500D01*
G01X1465016Y706957D02*
X1469957D01*
G01X1465016Y709516D02*
X1470050D01*
X1472566Y707000D01*
X1474000D01*
G01X1479759Y720885D02*
X1485075D01*
X1485575Y721385D01*
Y723500D01*
G01X1472000Y727500D02*
X1476000Y723500D01*
X1482425D01*
G01X1465016Y730484D02*
X1478984D01*
X1480000Y731500D01*
G01D02*
X1482425D01*
G01X1480000Y739500D02*
X1473543Y733043D01*
X1465016D01*
G01X1476716Y748398D02*
X1484575D01*
X1485075Y748898D01*
Y750500D01*
G01X1476716Y748398D02*
X1475018Y746700D01*
X1469997D01*
X1468299Y748398D01*
X1465016D01*
G01X1482425Y739500D02*
X1480000D01*
G01X1479665Y754555D02*
X1494112D01*
X1502575Y763018D01*
Y765000D01*
G01X1465016Y750957D02*
X1469957D01*
G01X1474000Y753093D02*
X1471907D01*
X1471484Y753516D01*
X1465016D01*
G01X1473489Y861354D02*
X1473986Y861851D01*
X1495766D01*
X1521929Y888014D01*
Y893216D01*
X1528025Y899312D01*
Y903110D01*
X1527685Y903450D01*
X1525015D01*
G01X1474883Y868206D02*
X1472794Y870295D01*
X1468043D01*
G01Y880295D02*
X1476683D01*
X1482195Y885807D01*
G01X1473387Y897425D02*
X1470517Y900295D01*
X1468043D01*
G01X1480109Y943496D02*
X1478950D01*
X1474997Y939543D01*
X1469775D01*
G01X1466589Y943496D02*
X1466422D01*
G01X1466542Y947600D02*
Y943616D01*
X1466422Y943496D01*
G01X1480144Y946880D02*
X1477839D01*
X1474455Y943496D01*
X1469739D01*
G01X1647763Y919268D02*
Y929383D01*
X1654546Y936166D01*
Y962349D01*
X1632968Y983927D01*
X1539959D01*
X1533762Y977730D01*
X1522869D01*
X1520956Y979643D01*
X1484993D01*
X1480414Y975064D01*
G01X1467096Y991956D02*
Y988813D01*
G01D02*
Y986106D01*
G01X1479096Y991956D02*
Y988813D01*
G01D02*
Y986106D01*
G01X1471096Y991956D02*
Y989013D01*
X1471296Y988813D01*
G01D02*
X1471096Y988613D01*
Y986106D01*
G01X1475096Y991956D02*
Y988813D01*
G01D02*
Y986106D01*
G01X1468869Y1010822D02*
X1468636D01*
X1465658Y1007844D01*
Y1006648D01*
G01D02*
Y1003349D01*
G01X1483024Y1210110D02*
X1480196Y1212938D01*
G01D02*
X1481630Y1214372D01*
X1483308D01*
G01X1477014Y1216120D02*
X1479063Y1218169D01*
G01X1488688Y1228380D02*
X1488168Y1228900D01*
X1485795D01*
X1483496Y1226601D01*
X1480861D01*
G01X1506807Y1234921D02*
X1503274D01*
X1492703Y1230543D01*
X1480803D01*
X1476861Y1226601D01*
G01X1493047Y15043D02*
Y19043D01*
G01D02*
X1490954D01*
X1489556Y17645D01*
G01D02*
X1483541D01*
G01X1493047Y31043D02*
X1491448D01*
X1489829Y29424D01*
G01X1493047Y35043D02*
Y31043D01*
G01X1489829Y29424D02*
X1488050Y27645D01*
X1483541D01*
G01Y22645D02*
X1488113D01*
X1488511Y23043D01*
X1490563D01*
G01X1493047Y27043D02*
Y23043D01*
G01X1490563D02*
X1493047D01*
G01X1483287Y86012D02*
Y88824D01*
G01X1486842Y107899D02*
X1490842D01*
G01X1486545Y113684D02*
Y111534D01*
X1487295Y110784D01*
X1489567D01*
G01D02*
X1490842Y109509D01*
Y107899D01*
G01X1484577Y113684D02*
Y110794D01*
X1484567Y110784D01*
G01D02*
X1482842Y109059D01*
Y107899D01*
G01X1492921Y130903D02*
X1492890Y130934D01*
Y134838D01*
G01X1492921Y127753D02*
Y126313D01*
X1494127Y125107D01*
G01X1486545Y121558D02*
Y124163D01*
X1487045Y124663D01*
X1489146D01*
G01D02*
Y126008D01*
X1488867Y126287D01*
Y127748D01*
G01X1484577Y121558D02*
Y123785D01*
X1484124Y124879D01*
G01D02*
Y127005D01*
X1484867Y127748D01*
G01X1488968Y153296D02*
Y150265D01*
X1490516Y148717D01*
X1496641D01*
G01D02*
X1498794D01*
X1499511Y148000D01*
Y146912D01*
G01X1486989Y136742D02*
Y138338D01*
X1487489Y138838D01*
X1490490D01*
G01X1492890Y134838D02*
Y138838D01*
G01X1490490D02*
X1492890D01*
G01X1482993Y154865D02*
X1485837Y157709D01*
X1492208D01*
X1492708Y158209D01*
Y161958D01*
G01X1492186Y232859D02*
Y232681D01*
X1496221Y228646D01*
G01X1497799Y225055D02*
Y227068D01*
X1496221Y228646D01*
G01X1492085Y247292D02*
X1491828Y247035D01*
Y244571D01*
G01X1494316Y242078D02*
X1490487D01*
G01X1491828Y244571D02*
X1490487Y243230D01*
Y242078D01*
G01X1486517Y252371D02*
Y248371D01*
G01D02*
X1488199D01*
X1488936Y249108D01*
X1489208D01*
G01D02*
X1490345Y250245D01*
X1492085D01*
G01X1483121Y327200D02*
X1486860D01*
G01D02*
X1489971D01*
G01X1493121D02*
X1495717D01*
X1498541Y330024D01*
X1500659D01*
G01X1495605Y322700D02*
X1493121D01*
G01X1506457Y328884D02*
X1502683D01*
X1501899Y328100D01*
X1499503D01*
X1495605Y324202D01*
Y322700D01*
G01X1487318Y318200D02*
X1494333D01*
X1499230Y323097D01*
Y324796D01*
X1500759Y326325D01*
X1506457D01*
G01X1483121Y322700D02*
X1486360D01*
G01D02*
X1489971D01*
G01X1486913Y340327D02*
X1483494D01*
X1483121Y340700D01*
G01X1489971D02*
X1489598Y340327D01*
X1486913D01*
G01X1489971Y331700D02*
X1489543Y331272D01*
X1487152D01*
G01D02*
X1483549D01*
X1483121Y331700D01*
G01X1506457Y334002D02*
X1497157D01*
X1495689Y332534D01*
G01D02*
X1494855Y331700D01*
X1493121D01*
G01X1506457Y339121D02*
X1498188D01*
X1496609Y340700D01*
X1495521D01*
G01D02*
X1493121D01*
G01X1483121Y349700D02*
X1486360D01*
G01D02*
X1489971D01*
G01X1483121Y345200D02*
X1486360D01*
G01D02*
X1489971D01*
G01X1506457Y344239D02*
X1503658D01*
X1498216Y349681D01*
X1495521D01*
G01D02*
X1495382D01*
X1495363Y349700D01*
X1493121D01*
G01Y345200D02*
X1498361D01*
X1498919Y344642D01*
X1500386D01*
G01X1506457Y351916D02*
X1503578D01*
X1502919Y352575D01*
Y355226D01*
X1499445Y358700D01*
X1495925D01*
G01X1483121D02*
X1485646Y361225D01*
X1492428D01*
X1493121Y360532D01*
Y358700D01*
G01X1495925D02*
X1493121D01*
G01Y354200D02*
X1499640D01*
X1499839Y354001D01*
G01X1483121Y354200D02*
X1485091Y356170D01*
X1492752D01*
X1493121Y355801D01*
Y354200D01*
G01X1489938Y368576D02*
X1486890D01*
G01X1493088D02*
X1501934D01*
X1503210Y367300D01*
X1503874D01*
X1506327Y369753D01*
X1506991D01*
X1508074Y368670D01*
Y368006D01*
X1505621Y365553D01*
Y364889D01*
X1506704Y363806D01*
X1507568D01*
X1514751Y370989D01*
X1515415D01*
X1516498Y369906D01*
Y369242D01*
X1509215Y361959D01*
Y361295D01*
X1515909Y354601D01*
G01X1485075Y681630D02*
Y685630D01*
G01Y693630D02*
Y697630D01*
G01Y685630D02*
Y689630D01*
G01X1489925Y706500D02*
X1485075D01*
G01X1485575Y731500D02*
X1488000D01*
G01X1485575Y727500D02*
Y731500D01*
G01D02*
Y735500D01*
G01Y739500D02*
X1488731D01*
G01X1485575Y743500D02*
Y739500D01*
G01X1499425Y765000D02*
X1496629D01*
G01D02*
X1493000D01*
X1489000Y769000D01*
X1482048D01*
X1482016Y769032D01*
G01X1489925Y750500D02*
X1485075D01*
G01X1493301Y776911D02*
X1495255Y778865D01*
X1502075D01*
X1502575Y778365D01*
Y777000D01*
G01X1499425Y773000D02*
X1496814D01*
G01D02*
X1495798Y771984D01*
X1482016D01*
G01X1499425Y781000D02*
X1497000D01*
G01D02*
X1491613D01*
X1485156Y774543D01*
X1482016D01*
G01Y789898D02*
X1493716D01*
G01D02*
X1501575D01*
X1502075Y790398D01*
Y792000D01*
G01X1482016Y792457D02*
X1486957D01*
G01X1495170Y796670D02*
X1493516Y795016D01*
X1482016D01*
G01X1487050Y809413D02*
X1490016Y806447D01*
X1501932D01*
X1502575Y807090D01*
Y809000D01*
G01X1482016Y813032D02*
X1482048Y813000D01*
X1489000D01*
X1493000Y809000D01*
X1496845D01*
G01D02*
X1499425D01*
G01X1486386Y825296D02*
X1489237D01*
X1495585Y831644D01*
X1501240D01*
X1502575Y830309D01*
Y829000D01*
G01Y821000D02*
Y822381D01*
X1501851Y823105D01*
X1495753D01*
X1493092Y820444D01*
G01X1482016Y815984D02*
X1495790D01*
X1496806Y817000D01*
G01D02*
X1499425D01*
G01Y825000D02*
X1495240D01*
G01D02*
X1492707D01*
X1486250Y818543D01*
X1482016D01*
G01Y836457D02*
X1486957D01*
G01X1482016Y839016D02*
X1490637D01*
X1492329Y837324D01*
X1492625D01*
G01X1502075Y836000D02*
Y834398D01*
X1501575Y833898D01*
X1493038D01*
G01D02*
X1482016D01*
G01X1485500Y932500D02*
Y930500D01*
X1487610Y928390D01*
X1491656D01*
G01X1484824Y927324D02*
X1485726Y926422D01*
X1491656D01*
G01X1489500Y972500D02*
X1485300Y968300D01*
Y950899D01*
X1488124Y948075D01*
X1491656D01*
G01X1517148Y961756D02*
Y965852D01*
X1516772Y966228D01*
X1512272D01*
X1506000Y972500D01*
X1495500D01*
G01X1487096Y991956D02*
Y988813D01*
G01D02*
Y986106D01*
G01X1491096Y991956D02*
Y988813D01*
G01D02*
Y986106D01*
G01X1495096Y991956D02*
Y988813D01*
G01D02*
Y986106D01*
G01X1483096Y991956D02*
Y988813D01*
G01D02*
Y986106D01*
G01X1488681Y1204453D02*
X1485853Y1207281D01*
G01X1494344Y1222724D02*
X1497172Y1219896D01*
G01X1485853Y1207281D02*
X1487697Y1209125D01*
X1488405D01*
X1489793Y1207737D01*
G01X1488688Y1228380D02*
X1495666D01*
X1497693Y1230407D01*
G01X1500675Y1227300D02*
X1497362Y1223987D01*
X1495607D01*
X1494344Y1222724D01*
G01D02*
X1494342D01*
G01X1507058Y1229402D02*
X1499788D01*
X1497210Y1226824D01*
X1492787D01*
X1491515Y1225552D01*
G01X1515610Y99961D02*
X1510835D01*
X1508670Y102126D01*
Y103411D01*
G01X1505795Y97667D02*
X1509064D01*
G01X1515610Y97599D02*
X1509132D01*
X1509064Y97667D01*
G01X1515610Y92874D02*
X1506697D01*
X1504460Y95111D01*
G01X1508670Y103411D02*
X1505593D01*
G01X1501611Y102495D02*
Y106495D01*
G01D02*
X1505527D01*
X1505593Y106561D01*
G01D02*
X1508829D01*
G01X1499511Y143762D02*
X1502741D01*
G01X1501736Y225055D02*
Y229782D01*
X1500962Y230556D01*
G01X1503705Y225055D02*
Y226212D01*
X1505217Y227724D01*
Y227824D01*
G01D02*
Y230574D01*
X1505823Y231180D01*
Y232984D01*
G01X1507524Y241681D02*
Y244297D01*
G01X1501588Y232959D02*
X1500962Y232333D01*
Y230556D01*
G01X1504374Y241681D02*
X1503733Y241040D01*
Y233500D01*
X1504249Y232984D01*
X1505823D01*
G01X1499171Y250245D02*
X1503624D01*
X1503978Y250599D01*
G01X1499171Y253198D02*
Y256394D01*
G01D02*
X1501703D01*
X1504174Y253923D01*
Y250795D01*
X1503978Y250599D01*
G01X1500386Y344642D02*
Y342968D01*
X1501674Y341680D01*
X1506457D01*
G01X1501684Y336561D02*
X1506457D01*
G01X1500659Y330024D02*
X1502078Y331443D01*
X1506457D01*
G01X1499839Y354001D02*
X1501377Y352463D01*
Y351667D01*
X1503687Y349357D01*
X1506457D01*
G01X1519436Y458711D02*
Y458807D01*
X1518054Y460189D01*
Y461010D01*
X1514405Y464659D01*
X1501064D01*
X1498495Y462090D01*
Y455656D01*
G01Y452506D02*
X1500204D01*
X1501960Y450750D01*
X1504355D01*
G01X1498495Y452506D02*
Y448656D01*
G01X1516636Y458711D02*
X1512200Y463147D01*
X1505238D01*
X1504355Y462264D01*
Y450750D01*
G01X1517660Y455375D02*
X1515272D01*
X1511235Y459412D01*
X1508095D01*
G01X1502575Y773000D02*
Y769000D01*
G01Y773000D02*
Y777000D01*
G01Y781000D02*
Y785000D01*
G01X1499633Y787794D02*
X1501240D01*
X1502575Y786459D01*
Y785000D01*
G01X1506925Y792000D02*
X1502075D01*
G01X1502575Y813000D02*
Y817000D01*
G01Y825000D02*
Y829000D01*
G01Y817000D02*
Y821000D01*
G01X1506925Y836000D02*
X1502075D01*
G01X1505183Y902240D02*
X1512891D01*
X1514032Y901099D01*
Y897236D01*
X1511621Y894825D01*
X1511365D01*
G01X1502703Y888133D02*
X1503357D01*
X1506482Y891258D01*
Y898012D01*
X1505029Y899465D01*
X1502158D01*
G01X1504208Y907240D02*
Y909740D01*
G01Y907240D02*
Y903215D01*
X1505183Y902240D01*
G01X1504208Y909740D02*
Y912664D01*
X1503368Y913504D01*
Y916678D01*
G01X1501400D02*
Y913352D01*
X1500358Y912310D01*
Y907240D01*
G01X1499383Y902240D02*
Y904733D01*
X1500358Y905708D01*
Y907240D01*
G01X1502158Y899465D02*
X1499383Y902240D01*
G01X1502158Y899465D02*
Y899479D01*
G01X1509274Y921226D02*
Y916678D01*
G01X1505337Y921240D02*
Y916678D01*
G01X1509500Y937000D02*
X1513000D01*
X1525547Y924453D01*
X1536734D01*
G01X1509500Y944138D02*
X1536734D01*
G01X1499431Y961756D02*
Y958569D01*
X1504000Y954000D01*
X1506000D01*
X1509500Y950500D01*
G01X1511096Y991956D02*
Y988813D01*
G01D02*
Y986106D01*
G01X1507096Y991956D02*
Y988813D01*
G01D02*
Y986106D01*
G01X1499096D02*
Y988813D01*
G01D02*
Y991956D01*
G01X1503096D02*
Y988813D01*
G01D02*
Y986106D01*
G01X1502829Y1214239D02*
X1505657Y1211411D01*
X1505658D01*
G01X1508356Y1220068D02*
Y1219766D01*
X1502829Y1214239D01*
G01X1507692Y1224472D02*
X1507405D01*
X1500000Y1217067D01*
G01X1515610Y88150D02*
X1522707D01*
X1525172Y90615D01*
G01X1515610Y90512D02*
X1519722D01*
X1519860Y90650D01*
G01X1533720Y99961D02*
X1529493D01*
G01X1529543Y95236D02*
X1533720D01*
G01X1519610D02*
X1515610D01*
G01X1528505Y323766D02*
X1532746D01*
X1540149Y316363D01*
X1545583D01*
G01X1528505Y326325D02*
X1533678D01*
X1539140Y320863D01*
G01X1528505Y328884D02*
X1532909D01*
X1533325Y328468D01*
X1540203D01*
X1543308Y325363D01*
X1545636D01*
G01X1528505Y331443D02*
X1531231D01*
X1531681Y330993D01*
X1541667D01*
X1542797Y329863D01*
G01X1528505Y334002D02*
X1538069D01*
X1538430Y334363D01*
X1545846D01*
G01X1647565Y981432D02*
X1648600Y980397D01*
Y974368D01*
X1667156Y955812D01*
Y832051D01*
X1648064Y812959D01*
Y701993D01*
X1642997Y696926D01*
X1611596D01*
X1603204Y688534D01*
Y456835D01*
X1590067Y443698D01*
Y374472D01*
X1583774Y368179D01*
X1583020D01*
X1582227Y368972D01*
X1581473D01*
X1580940Y368439D01*
Y367685D01*
X1581733Y366892D01*
Y366138D01*
X1581200Y365605D01*
X1580446D01*
X1579653Y366398D01*
X1578899D01*
X1578366Y365865D01*
Y365111D01*
X1579159Y364318D01*
Y363564D01*
X1566530Y350935D01*
Y340578D01*
X1565075Y339123D01*
X1557700D01*
X1557477Y338900D01*
X1536202D01*
X1533863Y336561D01*
X1528505D01*
G01Y339121D02*
X1532962D01*
X1537204Y343363D01*
X1544951D01*
G01X1551175Y347283D02*
X1538649D01*
X1533046Y341680D01*
X1528505D01*
G01Y344239D02*
X1532448D01*
X1538032Y349823D01*
X1542894D01*
X1545434Y352363D01*
G01X1515909Y354601D02*
X1521153Y349357D01*
X1528505D01*
G01X1516838Y347422D02*
X1518919D01*
X1519543Y346798D01*
X1528505D01*
G01X1519321Y378600D02*
X1522285D01*
G01X1525435Y382600D02*
X1530189D01*
G01X1525435Y378600D02*
Y382600D01*
G01X1522285Y459600D02*
Y458038D01*
X1522785Y457538D01*
X1533842D01*
X1536639Y460335D01*
X1577953D01*
X1582377Y455911D01*
X1592635D01*
G01X1520200Y455921D02*
X1518206D01*
X1517660Y455375D01*
G01X1519436Y458711D02*
X1520325Y459600D01*
X1522285D01*
G01X1525435Y463600D02*
X1527012Y465177D01*
X1530280D01*
G01X1525435Y459600D02*
Y463600D01*
G01X1518523Y554555D02*
X1522373D01*
G01D02*
Y553175D01*
X1522874Y552674D01*
X1530304D01*
G01X1522373Y558555D02*
Y559667D01*
X1523131Y560425D01*
X1527006D01*
X1528060Y559371D01*
X1530242D01*
G01X1518523Y558555D02*
X1522373D01*
G01X1522405Y562567D02*
X1522393Y562555D01*
X1518523D01*
G01X1522405Y562567D02*
Y563931D01*
X1523048Y564574D01*
X1530039D01*
X1530242Y564371D01*
G01X1552529Y604567D02*
X1543445D01*
X1535199Y596321D01*
X1529458D01*
G01D02*
X1527260D01*
X1526527Y595588D01*
X1524803D01*
G01Y599588D02*
X1528633D01*
X1530302Y601257D01*
G01X1524803Y591588D02*
X1530080D01*
X1530280Y591388D01*
G01X1524835Y603600D02*
X1526890D01*
X1529480Y606190D01*
G01X1524803Y607588D02*
Y603632D01*
X1524835Y603600D01*
G01Y611600D02*
X1526995D01*
X1527469Y611126D01*
X1530309D01*
G01X1524835Y615600D02*
X1526411D01*
X1526880Y616069D01*
X1529502D01*
G01D02*
X1540567D01*
X1542620Y614016D01*
X1552529D01*
G01X1524835Y619600D02*
X1528901D01*
X1530306Y621005D01*
G01X1529480Y606190D02*
X1537180D01*
X1540281Y609291D01*
X1552529D01*
G01X1524835Y627600D02*
X1526997D01*
X1530283Y630886D01*
G01X1552529Y618740D02*
X1545878D01*
X1538668Y625950D01*
X1529479D01*
G01D02*
X1527129Y623600D01*
X1524835D01*
G01X1521685Y627600D02*
Y631421D01*
G01X1520729Y634190D02*
X1521685Y633234D01*
Y631421D01*
G01X1524835Y637969D02*
X1529805D01*
X1529815Y637979D01*
G01X1524835Y641974D02*
Y637969D01*
G01X1529815Y637979D02*
X1531963Y635831D01*
X1535868D01*
X1548234Y623465D01*
X1552529D01*
G01X1521685Y641974D02*
Y643583D01*
X1524200Y646098D01*
G01X1551163Y952888D02*
Y911567D01*
X1553272Y909458D01*
Y902205D01*
X1549750Y898683D01*
X1529672D01*
X1524207Y893218D01*
Y877135D01*
X1520852Y873780D01*
X1518452D01*
G01X1548080Y910757D02*
X1550396Y908441D01*
Y902696D01*
X1548525Y900825D01*
X1535236D01*
X1528959Y907102D01*
Y916678D01*
G01X1525015Y906600D02*
Y909551D01*
X1525022Y909558D01*
G01D02*
Y916678D01*
G01X1519116Y961756D02*
Y949884D01*
X1521500Y947500D01*
G01X1523096Y991956D02*
Y988813D01*
G01D02*
Y986106D01*
G01X1519096Y991956D02*
Y988813D01*
G01D02*
Y986106D01*
G01X1515096Y991956D02*
Y988813D01*
G01D02*
Y986106D01*
G01X1527096Y995106D02*
Y997860D01*
G01X1523819Y1075196D02*
X1521949Y1073326D01*
G01X1531299Y1075196D02*
X1529429Y1073326D01*
G01X1531299Y1078936D02*
X1529429Y1077066D01*
G01X1527559Y1086417D02*
X1525689Y1084547D01*
G01X1516338Y1090157D02*
X1514468Y1088287D01*
G01X1520078Y1090157D02*
X1518208Y1088287D01*
G01X1527559Y1082677D02*
X1525689Y1080807D01*
G01X1516338Y1101377D02*
X1514468Y1099507D01*
G01X1520078Y1101377D02*
X1518208Y1099507D01*
G01X1531299Y1093897D02*
X1529429Y1092027D01*
G01X1527559Y1101377D02*
X1525689Y1099507D01*
G01X1531299Y1097637D02*
X1529429Y1095767D01*
G01X1527559Y1105117D02*
X1525689Y1103247D01*
G01X1520078Y1108858D02*
X1518208Y1106988D01*
G01X1523819Y1093897D02*
X1521949Y1092027D01*
G01X1523819Y1097637D02*
X1521949Y1095767D01*
G01X1516338Y1108858D02*
X1514468Y1106988D01*
G01X1523819Y1112598D02*
X1521949Y1110728D01*
G01X1520078Y1116338D02*
X1518208Y1114468D01*
G01X1527559Y1112598D02*
X1525689Y1110728D01*
G01X1520078Y1123818D02*
X1518208Y1121948D01*
G01X1516338Y1123818D02*
X1514468Y1121948D01*
G01X1516338Y1116338D02*
X1514468Y1114468D01*
G01X1523819Y1120078D02*
X1521949Y1118208D01*
G01X1527559Y1120078D02*
X1525689Y1118208D01*
G01X1527559Y1127558D02*
X1525689Y1125688D01*
G01X1520078Y1131299D02*
X1518208Y1129429D01*
G01X1523819Y1127558D02*
X1521949Y1125688D01*
G01X1516338Y1131299D02*
X1514468Y1129429D01*
G01X1520078Y1138779D02*
X1518208Y1136909D01*
G01X1523819Y1135039D02*
X1521949Y1133169D01*
G01X1516338Y1138779D02*
X1514468Y1136909D01*
G01X1520078Y1149999D02*
X1518208Y1148129D01*
G01X1516338Y1149999D02*
X1514468Y1148129D01*
G01X1520078Y1157480D02*
X1518208Y1155610D01*
G01X1516338Y1157480D02*
X1514468Y1155610D01*
G01X1533720Y92874D02*
X1538451D01*
G01D02*
Y95018D01*
X1539845Y96412D01*
X1548621D01*
X1550282Y98073D01*
Y98198D01*
G01X1545583Y316363D02*
X1548304D01*
G01X1545636Y325363D02*
X1548304D01*
G01X1542797Y329863D02*
X1548304D01*
G01X1545846Y334363D02*
X1548304D01*
G01X1544951Y343363D02*
X1548304D01*
G01X1545434Y352363D02*
X1548304D01*
G01X1530189Y382600D02*
X1538406D01*
X1538939Y382067D01*
X1552529D01*
G01X1530280Y465177D02*
X1552529D01*
G01X1530304Y552674D02*
X1534185Y556555D01*
X1552529D01*
G01X1530242Y559371D02*
X1532923D01*
X1533377Y558917D01*
X1552529D01*
G01X1530242Y564371D02*
X1535520D01*
X1538611Y561280D01*
X1552529D01*
G01X1530302Y601257D02*
X1536526D01*
X1542198Y606929D01*
X1552529D01*
G01X1530280Y591388D02*
X1538925D01*
X1540293Y592756D01*
X1552529D01*
G01X1530309Y611126D02*
X1537555D01*
X1538083Y611654D01*
X1552529D01*
G01X1530306Y621005D02*
X1530316Y620995D01*
X1539789D01*
X1544406Y616378D01*
X1552529D01*
G01X1530283Y630886D02*
X1537161D01*
X1546945Y621102D01*
X1552529D01*
G01X1547644Y903060D02*
X1544289Y906415D01*
Y938711D01*
X1540830Y942170D01*
X1536734D01*
G01X1543572Y969737D02*
X1541367Y967532D01*
X1537655D01*
X1535221Y969966D01*
Y971822D01*
G01D02*
Y974187D01*
X1541434Y980400D01*
X1552266D01*
G01X1531096Y991956D02*
Y988813D01*
G01D02*
Y986106D01*
G01X1608283Y809127D02*
X1611203D01*
X1611673Y809597D01*
Y809657D01*
X1614232Y812216D01*
X1624925D01*
X1627943Y815234D01*
X1646800D01*
X1665091Y833525D01*
Y954720D01*
X1634205Y985606D01*
X1531596D01*
X1531096Y986106D01*
G01X1538779Y1075196D02*
X1536909Y1073326D01*
G01X1535039Y1082677D02*
X1533169Y1080807D01*
G01X1535039Y1086417D02*
X1533169Y1084547D01*
G01X1542519Y1082677D02*
X1540649Y1080807D01*
G01X1538779Y1078936D02*
X1536909Y1077066D01*
G01X1542519Y1086417D02*
X1540649Y1084547D01*
G01X1538779Y1097637D02*
X1536909Y1095767D01*
G01X1535039Y1101377D02*
X1533169Y1099507D01*
G01X1542519Y1105117D02*
X1540649Y1103247D01*
G01X1538779Y1093897D02*
X1536909Y1092027D01*
G01X1535039Y1105117D02*
X1533169Y1103247D01*
G01X1546259Y1116338D02*
X1544389Y1114468D01*
G01X1538779Y1112598D02*
X1536909Y1110728D01*
G01X1535039Y1112598D02*
X1533169Y1110728D01*
G01X1542519Y1116338D02*
X1540649Y1114468D01*
G01X1538779Y1153740D02*
X1536909Y1151870D01*
G01X1538779Y1149999D02*
X1536909Y1148129D01*
G01X1542519Y1157480D02*
X1540649Y1155610D01*
G01X1542519Y1153740D02*
X1540649Y1151870D01*
G01X1542519Y1149999D02*
X1540649Y1148129D01*
G01X1538779Y1146259D02*
X1536909Y1144389D01*
G01X1538779Y1157480D02*
X1536909Y1155610D01*
G01X1538779Y1161220D02*
X1536909Y1159350D01*
G01X1542519Y1161220D02*
X1540649Y1159350D01*
G01X1538779Y1172440D02*
X1540649Y1174310D01*
G01X1538779Y1168700D02*
X1540649Y1170570D01*
G01X1538779Y1176180D02*
X1540649Y1178050D01*
G01X1554282Y98198D02*
X1550282D01*
G01X1559786Y97475D02*
X1557286D01*
G01X1559786Y105087D02*
Y100625D01*
G01D02*
X1564267D01*
G01X1561921Y141247D02*
X1564846D01*
G01X1558771D02*
X1554942D01*
G01X1556540Y146461D02*
X1556283Y146204D01*
Y143740D01*
G01D02*
X1554942Y142399D01*
Y141247D01*
G01X1556540Y149414D02*
X1554800D01*
X1553663Y148277D01*
G01X1550972Y151540D02*
Y147540D01*
G01X1553663Y148277D02*
X1553391D01*
X1552654Y147540D01*
X1550972D01*
G01X1554388Y259535D02*
Y256303D01*
G01X1559163Y266114D02*
Y264678D01*
X1558388Y263903D01*
Y262685D01*
G01X1549060Y265701D02*
X1550388Y264373D01*
Y262685D01*
G01X1554147Y265896D02*
Y264086D01*
X1554388Y263845D01*
Y262685D01*
G01X1556596Y269603D02*
Y268681D01*
X1559163Y266114D01*
G01X1552660Y269603D02*
Y267575D01*
X1551964Y266879D01*
X1550238D01*
X1549060Y265701D01*
G01X1556636Y281982D02*
X1554628Y279974D01*
Y277477D01*
G01Y269603D02*
Y267599D01*
X1554147Y267118D01*
Y265896D01*
G01X1550695Y281716D02*
X1552660Y279751D01*
Y277477D01*
G01X1557441Y284908D02*
Y282787D01*
X1556636Y281982D01*
G01X1549441Y284908D02*
X1553441D01*
G01D02*
Y283104D01*
X1552053Y281716D01*
X1550695D01*
G01X1554403Y316363D02*
X1558304D01*
G01X1551454D02*
X1554403D01*
G01X1551454Y325363D02*
X1551560D01*
X1553534Y327337D01*
G01D02*
X1555508Y325363D01*
X1558304D01*
G01Y329863D02*
X1555845D01*
X1553910Y331798D01*
G01D02*
Y330538D01*
X1553235Y329863D01*
X1551454D01*
G01X1553597Y336601D02*
X1553692D01*
G01D02*
X1551454Y334363D01*
G01X1553692Y336601D02*
X1553718D01*
X1555956Y334363D01*
X1558304D01*
G01X1651443Y981515D02*
X1650700Y980772D01*
Y975326D01*
X1669220Y956806D01*
Y831392D01*
X1649823Y811995D01*
Y701264D01*
X1643726Y695167D01*
X1612325D01*
X1604963Y687805D01*
Y456106D01*
X1591826Y442969D01*
Y373743D01*
X1568289Y350206D01*
Y339849D01*
X1565804Y337364D01*
X1559404D01*
X1558304Y336264D01*
Y334363D01*
G01Y343363D02*
X1555366D01*
X1553862Y344867D01*
G01D02*
X1551816D01*
X1551454Y344505D01*
Y343363D01*
G01X1548304Y352363D02*
Y350575D01*
X1549001Y349878D01*
X1557197D01*
X1558304Y350985D01*
Y352363D01*
G01X1552529Y554193D02*
X1555039D01*
X1564085Y563239D01*
Y576478D01*
X1565323Y577716D01*
G01X1552529Y549469D02*
X1554478D01*
X1556588Y547359D01*
Y545528D01*
G01X1558107Y655720D02*
X1561033D01*
X1563449Y658136D01*
Y663348D01*
X1565132Y665031D01*
Y668153D01*
G01X1551139Y956600D02*
Y952912D01*
X1551163Y952888D01*
G01X1554289Y956600D02*
X1556835Y954054D01*
X1562810D01*
G01X1552000Y969850D02*
X1548471D01*
X1548358Y969737D01*
X1546722D01*
G01X1561220Y1116338D02*
X1559350Y1114468D01*
G01X1557480Y1116338D02*
X1555610Y1114468D01*
G01X1557480Y1217322D02*
X1555610Y1215452D01*
G01X1561220Y1217322D02*
X1563090Y1215452D01*
G01X1561220Y1213582D02*
X1559350Y1215452D01*
G01X1577108Y60513D02*
Y64722D01*
G01D02*
Y72193D01*
X1574534Y74767D01*
X1570558D01*
X1568378Y72587D01*
G01X1562828Y72615D02*
X1562856Y72587D01*
X1565228D01*
G01X1562828Y76587D02*
X1565228D01*
G01X1577236Y85731D02*
X1577108Y85603D01*
Y81848D01*
G01X1565183Y80581D02*
Y79618D01*
X1568214Y76587D01*
X1568378D01*
G01D02*
X1576048D01*
X1579668Y72967D01*
Y64722D01*
G01X1565183Y68581D02*
Y69564D01*
X1568206Y72587D01*
X1568378D01*
G01X1577793Y88801D02*
X1577236Y88244D01*
Y85731D01*
G01X1577793Y91951D02*
Y94351D01*
G01X1564267Y100625D02*
X1565633Y99259D01*
X1569189D01*
G01X1568640Y112083D02*
Y112402D01*
X1570726Y114488D01*
G01X1572929Y107921D02*
Y103621D01*
G01X1582265Y142648D02*
X1580847D01*
X1578599Y140400D01*
X1568493D01*
X1567646Y141247D01*
X1564846D01*
G01X1577078Y157370D02*
Y148980D01*
X1578307Y147754D01*
X1580418D01*
G01X1574100Y158400D02*
Y148325D01*
X1573600Y147825D01*
X1569002D01*
X1568433Y147256D01*
Y145768D01*
G01X1571583D02*
Y143868D01*
X1571233Y143518D01*
X1569333D01*
G01X1582265Y139695D02*
X1583717D01*
X1584400Y140378D01*
Y144083D01*
X1583683Y144800D01*
X1580702D01*
X1578067Y142165D01*
X1569560D01*
X1569333Y142392D01*
Y143518D01*
G01X1670795Y145768D02*
Y147256D01*
X1671364Y147825D01*
X1675981D01*
X1676481Y148325D01*
Y156884D01*
X1675170Y158195D01*
X1615632D01*
X1608283Y165544D01*
X1581244D01*
X1574100Y158400D01*
G01X1563626Y149414D02*
X1568079D01*
X1568433Y149768D01*
G01X1563626Y152367D02*
X1568427D01*
X1568433Y152373D01*
G01D02*
Y149768D01*
G01X1566990Y168713D02*
Y171523D01*
G01X1575369Y176665D02*
Y180665D01*
G01X1572385Y178560D02*
Y179904D01*
G01X1575369Y180665D02*
X1573146D01*
X1572385Y179904D01*
G01D02*
Y180204D01*
X1570723Y181866D01*
X1569079D01*
G01X1570140Y168713D02*
X1575321D01*
X1575369Y168665D01*
G01D02*
Y172665D01*
G01X1569079Y179897D02*
Y176034D01*
X1572448Y172665D01*
G01D02*
X1575369D01*
G01Y184665D02*
X1574538Y183834D01*
X1572275D01*
G01D02*
X1569079D01*
G01X1575369Y192665D02*
X1572730D01*
X1571795Y191730D01*
Y190185D01*
G01D02*
X1569986D01*
X1569079Y189278D01*
Y185803D01*
G01X1575369Y196665D02*
X1569243D01*
X1566520Y193942D01*
Y192490D01*
G01D02*
Y188362D01*
G01X1578519Y192665D02*
X1581162D01*
G01X1578519Y196665D02*
X1581162D01*
G01X1578519Y188665D02*
X1580544D01*
X1581275Y187934D01*
Y186778D01*
G01D02*
Y185398D01*
X1580542Y184665D01*
X1578519D01*
G01X1575464Y212864D02*
X1575055Y212455D01*
X1572654D01*
G01X1568690Y213166D02*
X1570376D01*
X1571087Y212455D01*
X1572654D01*
G01X1572565Y200864D02*
X1575464D01*
G01X1568690Y209229D02*
X1569412D01*
X1570000Y208641D01*
Y203429D01*
X1572565Y200864D01*
G01X1575464Y204864D02*
Y208864D01*
G01X1572588Y207037D02*
X1574415Y208864D01*
X1575464D01*
G01X1568690Y211197D02*
X1570143D01*
X1572588Y208752D01*
Y207037D01*
G01X1578614Y208864D02*
X1581194D01*
G01X1568690Y217103D02*
X1570703D01*
X1575464Y221864D01*
G01X1575461Y225719D02*
Y221867D01*
X1575464Y221864D01*
G01X1577463Y228631D02*
X1575461Y226629D01*
Y225719D01*
G01X1582437Y340869D02*
X1579505D01*
X1578587Y341787D01*
G01X1582437Y338309D02*
X1578420D01*
G01X1582437Y343723D02*
X1579481D01*
X1579077Y344127D01*
X1574775D01*
G01D02*
Y341600D01*
G01X1575935Y382109D02*
X1575893Y382067D01*
X1570640D01*
G01Y465177D02*
X1579217D01*
X1581594Y462800D01*
X1584854D01*
G01X1570640Y549469D02*
X1584922D01*
G01X1577862Y554121D02*
X1575572Y551831D01*
X1570640D01*
G01Y556555D02*
X1578488D01*
X1580445Y554598D01*
X1584944D01*
G01X1589685Y562800D02*
X1580076D01*
X1578696Y561420D01*
X1575934D01*
G01X1570640Y561280D02*
X1574388D01*
X1574726Y561420D01*
X1575934D01*
G01Y558917D02*
X1570640D01*
G01X1575934D02*
X1579183D01*
X1580600Y557500D01*
X1588385D01*
X1589685Y558800D01*
G01X1570640Y592756D02*
X1577016D01*
X1579760Y595500D01*
G01X1570640Y616378D02*
X1574220D01*
X1574720Y616878D01*
Y618400D01*
G01X1570640Y611654D02*
X1574063D01*
X1575001Y612592D01*
G01X1570640Y621102D02*
X1576158D01*
X1577760Y619500D01*
X1585260D01*
G01X1570640Y609291D02*
X1573846D01*
X1574627Y610072D01*
X1580418D01*
G01X1570640Y606929D02*
X1574760D01*
G01X1570640Y604567D02*
X1579260D01*
G01X1570640Y614016D02*
X1573655D01*
X1574923Y615284D01*
X1579321D01*
X1580354Y616317D01*
G01X1570640Y623465D02*
X1581725D01*
X1583660Y625400D01*
X1585260D01*
G01X1574880Y645891D02*
X1576238Y647249D01*
Y653161D01*
G01X1571888Y649380D02*
Y652811D01*
X1572238Y653161D01*
G01X1576238Y656311D02*
X1572238D01*
G01D02*
X1570326D01*
X1569679Y655664D01*
Y653752D01*
X1569088Y653161D01*
X1566769D01*
G01X1576238Y656311D02*
X1583066D01*
X1586978Y652399D01*
G01X1565132Y668153D02*
Y672360D01*
G01X1578000Y678776D02*
X1578106D01*
X1582148Y682818D01*
Y688629D01*
X1581083Y689694D01*
X1579312D01*
G01X1572612Y682006D02*
X1576667D01*
X1578448Y683787D01*
G01D02*
Y685928D01*
X1576162Y688214D01*
Y689694D01*
G01X1568872Y682006D02*
Y686971D01*
G01X1576162Y689694D02*
X1575942Y689914D01*
Y694797D01*
G01X1573383Y702277D02*
Y705701D01*
X1572042Y707042D01*
Y710129D01*
G01D02*
X1569470D01*
X1566655Y707314D01*
G01D02*
Y703374D01*
X1567752Y702277D01*
X1570824D01*
G01X1573280Y916608D02*
X1620909D01*
X1623564Y919263D01*
X1635000D01*
G01X1562810Y954054D02*
X1568517D01*
X1571970Y957507D01*
Y969072D01*
X1570642Y970400D01*
X1563762D01*
G01X1576181Y1116338D02*
X1574311Y1114468D01*
G01X1572441Y1116338D02*
X1570571Y1114468D01*
G01X1564960Y1116338D02*
X1563090Y1114468D01*
G01X1579921Y1116338D02*
X1578051Y1114468D01*
G01X1568700Y1116338D02*
X1566830Y1114468D01*
G01X1564960Y1131299D02*
X1563090Y1129429D01*
G01X1564960Y1135039D02*
X1563090Y1133169D01*
G01X1564960Y1142519D02*
X1563090Y1140649D01*
G01X1568700Y1142519D02*
X1566830Y1140649D01*
G01X1579921Y1217322D02*
X1578051Y1215452D01*
G01X1568700Y1213582D02*
X1566830Y1215452D01*
G01X1572441Y1213582D02*
X1570571Y1211712D01*
G01X1568700Y1217322D02*
X1566830Y1219192D01*
G01X1572441Y1217322D02*
X1570571Y1215452D01*
G01X1578051Y1211712D02*
X1579921Y1213582D01*
G01X1574311Y1211712D02*
X1576181Y1213582D01*
G01X1579668Y64722D02*
X1579968Y64422D01*
Y60438D01*
G01X1580790Y86046D02*
X1579668Y84924D01*
Y81848D01*
G01X1585649Y86012D02*
X1582522Y82885D01*
Y81848D01*
G01X1581742Y88729D02*
Y86998D01*
X1580790Y86046D01*
G01X1581742Y91879D02*
Y94279D01*
G01X1585649Y88824D02*
Y86012D01*
G01X1586939Y113684D02*
Y110794D01*
X1586929Y110784D01*
G01D02*
X1585204Y109059D01*
Y107899D01*
G01X1589204D02*
X1593204D01*
G01X1588907Y113684D02*
Y111534D01*
X1589657Y110784D01*
X1591929D01*
G01D02*
X1593204Y109509D01*
Y107899D01*
G01X1580418Y147754D02*
X1584656D01*
X1587229Y145177D01*
Y135472D01*
X1587400Y135301D01*
Y132499D01*
X1587229Y132328D01*
Y130898D01*
G01X1584971Y121558D02*
Y123126D01*
X1583814Y124283D01*
X1581420D01*
G01D02*
X1581452Y124315D01*
Y125971D01*
X1583229Y127748D01*
G01X1586939Y121558D02*
Y123785D01*
X1586486Y124879D01*
G01D02*
Y127005D01*
X1587229Y127748D01*
G01X1588907Y121558D02*
Y124163D01*
X1589407Y124663D01*
X1591508D01*
G01D02*
Y126008D01*
X1591229Y126287D01*
Y127748D01*
G01X1591330Y153296D02*
Y150265D01*
X1592878Y148717D01*
X1599003D01*
G01X1595252Y138838D02*
X1592852D01*
G01D02*
X1589851D01*
X1589351Y138338D01*
Y136742D01*
G01X1580418Y150904D02*
Y154865D01*
G01D02*
X1585355D01*
G01D02*
X1588199Y157709D01*
X1594570D01*
X1595070Y158209D01*
Y161958D01*
G01X1589699Y242078D02*
X1582427D01*
X1579939Y244566D01*
Y255458D01*
X1583361Y258880D01*
X1633971D01*
G01X1594548Y232859D02*
Y232681D01*
X1598583Y228646D01*
G01X1596678Y242078D02*
X1592849D01*
G01X1594447Y247292D02*
X1594190Y247035D01*
Y244571D01*
G01D02*
X1592849Y243230D01*
Y242078D01*
G01X1588879Y252371D02*
Y248371D01*
G01X1594447Y250245D02*
X1592707D01*
X1591570Y249108D01*
G01D02*
X1591298D01*
X1590561Y248371D01*
X1588879D01*
G01X1592635Y455911D02*
Y458800D01*
G01X1589485D02*
Y462800D01*
G01X1584854D02*
X1589485D01*
G01X1592835Y545800D02*
Y541000D01*
X1593335Y540500D01*
X1596260D01*
G01X1584944Y554598D02*
X1588760D01*
X1590995Y552363D01*
X1595622D01*
X1598285Y549700D01*
G01X1589685Y545800D02*
Y549800D01*
G01X1584922Y549469D02*
X1587654D01*
X1587985Y549800D01*
X1589685D01*
G01X1594760Y568000D02*
X1601435Y561325D01*
Y557700D01*
G01X1585260Y619500D02*
X1588185D01*
X1590085Y621400D01*
G01X1593235D02*
Y625400D01*
G01X1586978Y652399D02*
X1593235Y646142D01*
Y625400D01*
G01X1585260D02*
X1590085D01*
G01X1584776Y906608D02*
X1624808D01*
X1627463Y909263D01*
X1644718D01*
G01X1594882Y1116338D02*
X1593012Y1114468D01*
G01X1591141Y1116338D02*
X1589271Y1114468D01*
G01X1583661Y1116338D02*
X1581791Y1114468D01*
G01X1583661Y1213582D02*
X1581791Y1215452D01*
G01X1587401Y1217322D02*
X1589271Y1215452D01*
G01X1587401Y1213582D02*
X1585531Y1211712D01*
G01X1590733Y1442557D02*
Y1440791D01*
X1592410Y1439114D01*
X1593942D01*
G01X1590707Y1446488D02*
Y1442583D01*
X1590733Y1442557D01*
G01X1590707Y1451470D02*
Y1446488D01*
G01X1593883Y1442557D02*
X1596790D01*
G01X1587746Y1460707D02*
Y1465452D01*
G01Y1460707D02*
X1592643D01*
G01X1587746Y1457557D02*
Y1454431D01*
X1590707Y1451470D01*
G01X1587746Y1457557D02*
X1593019D01*
G01X1587746Y1465452D02*
X1590317Y1468023D01*
X1599291D01*
G01X1601537Y1471973D02*
X1605295Y1475731D01*
Y1483683D01*
X1603451Y1485527D01*
X1601624D01*
X1599953Y1483856D01*
X1591689D01*
X1588502Y1487043D01*
Y1532139D01*
X1593671Y1537308D01*
X1604704D01*
X1606678Y1535334D01*
X1609348D01*
G01X1598000Y1508925D02*
X1594500D01*
G01X1598142Y1527310D02*
X1594681D01*
X1590748Y1523377D01*
G01X1608157Y97667D02*
X1611426D01*
G01X1617972Y92874D02*
X1609059D01*
X1606822Y95111D01*
G01X1617972Y99961D02*
X1613197D01*
X1611032Y102126D01*
Y103411D01*
G01D02*
X1607955D01*
G01Y106561D02*
X1611191D01*
G01X1603973Y106495D02*
X1607889D01*
X1607955Y106561D01*
G01X1603973Y102495D02*
Y106495D01*
G01X1595283Y130903D02*
X1595252Y130934D01*
Y134838D01*
G01X1595283Y127753D02*
Y126313D01*
X1596489Y125107D01*
G01X1601873Y143762D02*
X1605103D01*
G01X1599003Y148717D02*
X1601156D01*
X1601873Y148000D01*
Y146912D01*
G01X1595252Y134838D02*
Y138838D01*
G01X1604098Y225055D02*
Y229782D01*
X1603324Y230556D01*
G01X1606067Y225055D02*
Y226212D01*
X1607579Y227724D01*
Y227824D01*
G01D02*
Y230574D01*
X1608185Y231180D01*
Y232984D01*
G01X1600161Y225055D02*
Y227068D01*
X1598583Y228646D01*
G01X1609886Y241681D02*
Y244297D01*
G01X1603950Y232959D02*
X1603324Y232333D01*
Y230556D01*
G01X1606736Y241681D02*
X1606095Y241040D01*
Y233798D01*
X1606909Y232984D01*
X1608185D01*
G01X1601533Y253198D02*
X1604677D01*
G01X1601533Y250245D02*
X1605986D01*
X1606340Y250599D01*
G01X1604677Y253198D02*
X1606181D01*
X1606536Y252843D01*
Y250795D01*
X1606340Y250599D01*
G01X1595069Y337361D02*
X1596017Y338309D01*
X1599563D01*
G01X1608722Y340252D02*
X1606779Y338309D01*
X1599563D01*
G01X1595109Y342663D02*
X1596903Y340869D01*
X1599563D01*
G01X1608722Y344252D02*
Y343722D01*
X1605500Y340500D01*
X1599932D01*
X1599563Y340869D01*
G01X1601949Y380718D02*
Y373081D01*
X1604330Y370700D01*
X1617925D01*
G01X1601949Y380718D02*
Y384718D01*
G01X1605099Y392718D02*
X1615080D01*
X1616220Y393858D01*
G01X1605099Y396718D02*
Y392718D01*
G01X1601949Y388718D02*
Y390011D01*
X1602449Y390511D01*
X1618989D01*
X1619974Y391496D01*
X1624446D01*
G01X1605099Y380718D02*
X1613085D01*
G01X1605099Y388718D02*
X1613329D01*
X1614163Y387884D01*
X1617401D01*
G01X1605099Y384718D02*
X1623264D01*
G01X1605099Y404718D02*
X1613658D01*
G01X1605099Y408718D02*
X1622861D01*
G01X1605099Y400718D02*
X1624079D01*
G01X1605099Y412718D02*
X1613821D01*
G01X1601435Y549700D02*
Y553700D01*
G01D02*
Y557700D01*
G01X1611027Y699917D02*
Y704127D01*
X1612800Y705900D01*
G01X1611027Y717817D02*
Y722427D01*
G01X1603251Y797012D02*
X1604206Y796057D01*
Y763722D01*
X1611225Y756703D01*
X1621397D01*
X1624517Y753583D01*
X1627455D01*
G01X1608483Y780327D02*
X1611627D01*
G01X1616655Y777783D02*
X1611183D01*
X1609500Y776100D01*
G01X1608383Y795127D02*
X1611873D01*
G01X1608750Y788150D02*
X1612550D01*
X1613170Y787530D01*
X1616455D01*
G01X1608750Y788150D02*
X1607500Y786900D01*
Y784460D01*
X1608483Y783477D01*
G01X1609400Y803800D02*
X1608383Y802783D01*
Y798277D01*
G01X1602595Y802852D02*
X1606068Y799379D01*
Y792815D01*
X1606983Y791900D01*
X1609700D01*
X1611117Y790483D01*
X1616455D01*
G01X1616155Y801630D02*
X1614271D01*
X1612101Y803800D01*
X1609400D01*
G01X1608283Y812277D02*
X1608300Y812294D01*
Y815800D01*
X1609800Y817300D01*
G01X1616155Y804583D02*
X1614017D01*
X1611867Y806733D01*
X1606769D01*
X1603966Y809536D01*
Y816799D01*
G01X1609800Y817300D02*
X1612000D01*
X1613570Y815730D01*
X1616255D01*
G01Y818683D02*
X1613917D01*
X1602862Y829738D01*
G01X1598622Y1116338D02*
X1596752Y1114468D01*
G01X1598622Y1217322D02*
X1600492Y1215452D01*
G01X1611712D02*
X1609842Y1213582D01*
G01X1600333Y1446560D02*
Y1449068D01*
G01X1613790Y1523334D02*
X1616734Y1520390D01*
Y1473146D01*
X1609375Y1465787D01*
X1601788D01*
X1600410Y1464409D01*
Y1463362D01*
G01D02*
Y1459939D01*
X1598831Y1458360D01*
X1595968D01*
X1595029Y1457421D01*
Y1451752D01*
X1596181Y1450600D01*
X1598779D01*
X1599356Y1451177D01*
X1601189D01*
X1601645Y1450721D01*
X1623339D01*
X1625364Y1448696D01*
Y1426872D01*
X1633872Y1418364D01*
X1752980D01*
X1761426Y1426810D01*
Y1440061D01*
X1765050Y1443685D01*
X1774339D01*
G01X1600410Y1456276D02*
X1603363D01*
G01X1601968Y1453442D02*
X1603363Y1454837D01*
Y1456276D01*
G01X1597457Y1463362D02*
Y1460662D01*
G01X1599291Y1468023D02*
Y1469727D01*
X1601537Y1471973D01*
G01X1597166Y1479190D02*
Y1475227D01*
X1597039Y1475100D01*
G01X1599726Y1479190D02*
Y1474990D01*
G01X1608500Y1506000D02*
Y1503628D01*
X1602580Y1497708D01*
Y1496316D01*
G01X1600008Y1488492D02*
Y1491492D01*
X1599726Y1491774D01*
Y1496316D01*
G01X1601500Y1508925D02*
Y1502970D01*
X1599726Y1498686D01*
Y1496316D01*
G01X1597166D02*
Y1499166D01*
X1597500Y1499500D01*
Y1505001D01*
X1598000Y1505501D01*
Y1508925D01*
G01X1597166Y1496316D02*
X1597165Y1496315D01*
Y1493127D01*
X1596038Y1492000D01*
G01X1604000Y1519000D02*
X1602500D01*
X1598000Y1514500D01*
Y1512075D01*
G01X1601500D02*
Y1514500D01*
G01X1608500Y1508925D02*
Y1506000D01*
G01X1601500Y1508925D02*
X1605000D01*
G01X1603528Y1527334D02*
X1598166D01*
X1598142Y1527310D01*
G01X1606678Y1527334D02*
X1609348D01*
G01X1610858Y1523390D02*
X1613734D01*
X1613790Y1523334D01*
G01X1603528Y1539334D02*
X1600732D01*
G01X1606678D02*
X1607658Y1540314D01*
X1611522D01*
G01X1612310Y1535258D02*
X1609424D01*
X1609348Y1535334D01*
G01X1606666Y1543373D02*
X1609393Y1546100D01*
X1634774D01*
X1640581Y1551907D01*
G01X1603516Y1543373D02*
X1598574D01*
G01X1617972Y97599D02*
X1611494D01*
X1611426Y97667D01*
G01X1617972Y90512D02*
X1622084D01*
X1622222Y90650D01*
G01X1617972Y88150D02*
X1625069D01*
X1627534Y90615D01*
G01X1621972Y95236D02*
X1617972D01*
G01X1616722Y344252D02*
Y345397D01*
X1618285Y346960D01*
X1622490D01*
X1631243Y338207D01*
Y333456D01*
X1629514Y331727D01*
G01X1629553Y329067D02*
X1625933D01*
X1616722Y338278D01*
Y340252D01*
G01X1611872D02*
X1616722D01*
G01Y344252D02*
X1611872D01*
G01X1617925Y370700D02*
X1626401D01*
X1632454Y364647D01*
X1690566D01*
X1695664Y359549D01*
Y343727D01*
X1694256Y342319D01*
X1692676D01*
G01X1624446Y391496D02*
X1641565D01*
G01X1613085Y380718D02*
X1636493D01*
X1637822Y382047D01*
X1641565D01*
G01X1617401Y387884D02*
X1628978D01*
X1630228Y389134D01*
X1641565D01*
G01X1623264Y384718D02*
X1630816D01*
X1631124Y384410D01*
X1641565D01*
G01X1616220Y393858D02*
X1641565D01*
G01X1613658Y404718D02*
X1627330D01*
X1633465Y398583D01*
X1641565D01*
G01X1622861Y408718D02*
X1626895D01*
X1631637Y403976D01*
Y403961D01*
X1634653Y400945D01*
X1641565D01*
G01X1624079Y400718D02*
X1626965D01*
X1631462Y396221D01*
X1641565D01*
G01X1613821Y412718D02*
X1613859Y412756D01*
X1641565D01*
G01X1620385Y453873D02*
Y449873D01*
G01Y445873D02*
Y443426D01*
X1620855Y442956D01*
X1623955D01*
G01X1620385Y449873D02*
Y445873D01*
G01X1623535Y453873D02*
X1630831D01*
X1632439Y452265D01*
G01X1620385Y465874D02*
Y462859D01*
G01X1623535Y458859D02*
X1629007D01*
X1629411Y458455D01*
X1633225D01*
G01X1623535Y462859D02*
Y458859D01*
G01X1619570Y546712D02*
X1616622D01*
G01X1689920Y545912D02*
Y547154D01*
X1689100Y547974D01*
X1678363D01*
X1675566Y545177D01*
X1634252D01*
X1630553Y548876D01*
X1620622D01*
X1619570Y547824D01*
Y546712D01*
G01X1622720Y542712D02*
X1627351D01*
G01X1622720Y546712D02*
Y542712D01*
G01X1627351D02*
X1630611D01*
X1632988Y540335D01*
X1641565D01*
G01X1614538Y620788D02*
Y618288D01*
G01X1617291Y633786D02*
Y631449D01*
X1614538Y628696D01*
G01D02*
Y623938D01*
G01X1620244Y633786D02*
Y628670D01*
G01X1622538Y623938D02*
X1618538D01*
G01X1620244Y628670D02*
X1618538Y626964D01*
Y623938D01*
G01X1622538Y620788D02*
X1627380D01*
G01D02*
X1629774D01*
X1632431Y623445D01*
X1641565D01*
G01X1621362Y650671D02*
Y646176D01*
X1621127Y645941D01*
G01D02*
X1619386Y644200D01*
X1618236D01*
X1617291Y643255D01*
Y640872D01*
G01X1617362Y650671D02*
X1613362D01*
G01D02*
Y648871D01*
X1614338Y647895D01*
Y645900D01*
G01D02*
Y640872D01*
G01X1621362Y653821D02*
Y656321D01*
G01X1617362Y653821D02*
Y656321D01*
G01X1621843Y669913D02*
Y672917D01*
X1623100Y674174D01*
Y675889D01*
G01D02*
Y685058D01*
X1621111Y687047D01*
G01D02*
X1615913Y692245D01*
G01X1627155Y699930D02*
X1620600D01*
G01D02*
X1614190D01*
X1614177Y699917D01*
G01X1620500Y717830D02*
X1614190D01*
X1614177Y717817D01*
G01X1627155Y702883D02*
X1623617D01*
X1620600Y705900D01*
G01X1611327Y732417D02*
Y735973D01*
G01X1627455Y732430D02*
X1621200D01*
G01D02*
X1614490D01*
X1614477Y732417D01*
G01X1627155Y717830D02*
X1620500D01*
G01X1627155Y720783D02*
X1622917D01*
X1620500Y723200D01*
G01X1616683Y747427D02*
Y744517D01*
G01X1627455Y735383D02*
X1623017D01*
X1620100Y738300D01*
G01X1616583Y761427D02*
X1612573D01*
G01X1627455Y750630D02*
X1621700D01*
G01D02*
X1616736D01*
X1616683Y750577D01*
G01X1616655Y769300D02*
Y764649D01*
X1616583Y764577D01*
G01X1623741Y777783D02*
X1623724Y777800D01*
X1621600D01*
X1621100Y778300D01*
Y780200D01*
X1621636Y780736D01*
X1623741D01*
G01X1629500Y782300D02*
X1628600D01*
X1627036Y780736D01*
X1623741D01*
G01X1616655Y774830D02*
Y769300D01*
G01X1623541Y793436D02*
X1621336D01*
X1620800Y792900D01*
Y791100D01*
X1621417Y790483D01*
X1623541D01*
G01X1629700Y795700D02*
X1627600D01*
X1625336Y793436D01*
X1623541D01*
G01X1623241Y804583D02*
X1621217D01*
X1621000Y804800D01*
Y806900D01*
X1621636Y807536D01*
X1623241D01*
G01X1628400Y809400D02*
X1625105D01*
X1623241Y807536D01*
G01X1623341Y821636D02*
X1623277Y821700D01*
X1621000D01*
X1620600Y821300D01*
Y819200D01*
X1621117Y818683D01*
X1623341D01*
G01Y821636D02*
X1625236D01*
X1625500Y821900D01*
Y826900D01*
G01D02*
X1623600D01*
X1622383Y828117D01*
X1619577D01*
G01X1623653Y881353D02*
X1629768D01*
X1635176Y886761D01*
G01X1623084Y952120D02*
X1637771D01*
G01X1617322Y1116338D02*
X1617323D01*
X1619193Y1118208D01*
G01X1617322Y1112598D02*
X1617323D01*
X1619193Y1114468D01*
G01X1624803Y1112598D02*
X1626673Y1114468D01*
G01X1624803Y1116338D02*
X1626673Y1118208D01*
G01X1619192Y1215451D02*
X1617322Y1217322D01*
G01X1624803D02*
X1626673Y1215452D01*
G01X1615452D02*
X1613582Y1213582D01*
G01X1619192Y1211711D02*
X1617322Y1213582D01*
G01X1622933Y1211711D02*
X1621063Y1213582D01*
G01X1612610Y1528558D02*
X1616239Y1524929D01*
X1619886D01*
X1626571Y1518244D01*
Y1427372D01*
X1634372Y1419571D01*
X1752480D01*
X1760219Y1427310D01*
Y1473240D01*
X1762854Y1475875D01*
X1774216D01*
G01X1612610Y1528558D02*
Y1530154D01*
X1613790Y1531334D01*
G01X1611522Y1540314D02*
X1615254D01*
X1616210Y1539358D01*
G01X1636082Y92874D02*
X1640813D01*
G01D02*
Y95018D01*
X1642207Y96412D01*
X1650983D01*
X1652644Y98073D01*
Y98198D01*
G01X1631905Y95236D02*
X1636082D01*
G01Y99961D02*
X1631855D01*
G01X1632439Y452265D02*
X1635747Y448957D01*
X1641565D01*
G01X1633225Y458455D02*
X1635637Y456043D01*
X1641565D01*
G01Y453681D02*
X1636471D01*
X1636271Y453881D01*
G01X1635170Y442856D02*
Y443170D01*
X1636400Y444400D01*
X1639100D01*
X1639268Y444232D01*
X1641565D01*
G01Y446595D02*
X1635185D01*
G01X1634241Y705836D02*
X1634205Y705800D01*
X1632300D01*
X1631600Y705100D01*
Y703400D01*
X1632117Y702883D01*
X1634241D01*
G01Y705836D02*
X1638336D01*
X1639300Y706800D01*
Y708900D01*
G01D02*
Y710900D01*
X1638700Y711500D01*
X1634260D01*
X1634177Y711417D01*
G01X1634241Y723736D02*
X1634177Y723800D01*
X1631900D01*
X1631300Y723200D01*
Y721500D01*
X1632017Y720783D01*
X1634241D01*
G01X1640100Y723200D02*
X1640200D01*
X1641577Y724577D01*
Y728117D01*
G01X1634241Y723736D02*
X1636565D01*
X1637101Y723200D01*
X1640100D01*
G01X1634541Y738336D02*
X1634505Y738300D01*
X1632200D01*
X1631700Y737800D01*
Y736000D01*
X1632317Y735383D01*
X1634541D01*
G01X1635300Y743400D02*
Y739095D01*
X1634541Y738336D01*
G01X1630577Y744317D02*
X1631160Y744900D01*
X1633800D01*
X1635300Y743400D01*
G01X1634541Y756536D02*
X1634505Y756500D01*
X1632500D01*
X1631800Y755800D01*
Y754200D01*
X1632417Y753583D01*
X1634541D01*
G01X1629877Y762717D02*
X1629894Y762700D01*
X1633600D01*
X1634541Y761759D01*
G01D02*
Y756536D01*
G01X1634083Y777777D02*
X1634200Y777894D01*
Y781000D01*
X1632900Y782300D01*
X1629500D01*
G01X1629700Y795700D02*
X1631800D01*
X1632600Y794900D01*
Y790494D01*
X1632583Y790477D01*
G01X1628400Y809400D02*
X1630400D01*
X1631400Y808400D01*
Y804594D01*
X1631383Y804577D01*
G01X1635149Y871353D02*
X1644552D01*
G01X1635176Y886761D02*
X1638828D01*
X1640675Y884914D01*
Y881999D01*
G01X1635000Y919263D02*
X1637022Y917241D01*
X1641023D01*
G01X1634580Y942120D02*
X1644325D01*
G01X1637771Y952120D02*
X1637776Y952125D01*
X1640781D01*
G01X1643504Y1116338D02*
X1645374Y1114468D01*
G01X1636023Y1116338D02*
X1637893Y1118208D01*
G01X1636023Y1112598D02*
X1637893Y1114468D01*
G01X1632283Y1112598D02*
X1634153Y1114468D01*
G01X1628543Y1112598D02*
X1630413Y1114468D01*
G01X1639763Y1112598D02*
X1641633Y1114468D01*
G01X1632283Y1116338D02*
X1634153Y1118208D01*
G01X1628543Y1116338D02*
X1630413Y1118208D01*
G01X1632283Y1217322D02*
X1634153Y1215452D01*
G01X1645374Y1211712D02*
X1643504Y1213582D01*
G01X1641634Y1215452D02*
X1639764Y1217322D01*
X1639763D01*
G01X1656644Y98198D02*
X1652644D01*
G01X1662148Y97475D02*
X1659648D01*
G01X1661133Y141247D02*
X1657304D01*
G01X1658902Y146461D02*
X1658645Y146204D01*
Y143740D01*
G01D02*
X1657304Y142399D01*
Y141247D01*
G01X1653334Y151540D02*
Y147540D01*
G01X1658902Y149414D02*
X1657162D01*
X1656025Y148277D01*
G01D02*
X1655753D01*
X1655016Y147540D01*
X1653334D01*
G01X1656750Y259535D02*
Y256303D01*
G01X1656509Y265896D02*
Y264086D01*
X1656750Y263845D01*
Y262685D01*
G01X1651422Y265701D02*
X1652750Y264373D01*
Y262685D01*
G01X1653057Y281716D02*
X1655022Y279751D01*
Y277477D01*
G01X1656990Y269603D02*
Y267599D01*
X1656509Y267118D01*
Y265896D01*
G01X1658958Y269603D02*
Y268681D01*
X1661525Y266114D01*
G01X1655022Y269603D02*
Y267575D01*
X1654326Y266879D01*
X1652600D01*
X1651422Y265701D01*
G01X1658998Y281982D02*
X1656990Y279974D01*
Y277477D01*
G01X1651803Y284908D02*
X1655803D01*
G01D02*
Y283104D01*
X1654415Y281716D01*
X1653057D01*
G01X1659803Y284908D02*
Y282787D01*
X1658998Y281982D01*
G01X1659676Y391496D02*
X1669260D01*
G01X1659676Y386772D02*
X1665488D01*
X1670260Y382000D01*
Y377912D01*
G01X1659676Y384410D02*
X1663780D01*
G01X1659676Y382047D02*
X1666959D01*
G01X1659676Y389134D02*
X1667626D01*
X1670260Y386500D01*
G01X1659676Y398583D02*
X1665260D01*
G01X1659676Y396221D02*
X1668657D01*
X1670348Y397912D01*
G01X1659676Y393858D02*
X1663618D01*
G01X1659676Y400945D02*
X1664705D01*
X1667260Y403500D01*
G01X1659676Y412756D02*
X1665504D01*
X1669260Y409000D01*
G01X1650044Y435158D02*
X1651738Y436852D01*
Y442037D01*
X1654901Y445200D01*
X1656931D01*
X1657899Y444232D01*
X1659676D01*
G01X1649789Y440489D02*
Y441889D01*
X1654495Y446595D01*
X1659676D01*
G01X1650087Y444841D02*
X1653746Y448500D01*
X1657215D01*
X1657672Y448957D01*
X1659676D01*
G01X1649773Y449961D02*
X1649912Y450100D01*
X1656552D01*
X1657771Y451319D01*
X1659676D01*
G01X1653490Y458572D02*
X1655265Y456797D01*
X1657109D01*
X1657863Y456043D01*
X1659676D01*
G01Y540335D02*
X1681925D01*
G01X1659676Y623445D02*
X1673266D01*
X1673799Y622912D01*
X1682016D01*
G01X1647402Y881460D02*
X1651390Y877472D01*
Y871345D01*
G01X1644552Y871353D02*
X1646595D01*
X1646603Y871345D01*
X1648240D01*
G01X1643825Y881999D02*
X1648375Y886549D01*
Y886766D01*
G01X1650205Y925911D02*
X1651927Y924189D01*
Y909279D01*
G01X1644718Y909263D02*
X1644734Y909279D01*
X1648777D01*
G01X1644173Y917241D02*
X1645736D01*
X1647763Y919268D01*
G01X1648387Y945554D02*
X1650943D01*
X1651534Y944963D01*
Y942136D01*
G01X1644325Y942120D02*
X1644341Y942136D01*
X1648384D01*
G01X1643931Y952125D02*
X1647470D01*
G01X1650984Y1112598D02*
X1652854Y1114468D01*
G01X1647244Y1112598D02*
X1649114Y1114468D01*
G01X1654724Y1112598D02*
X1656594Y1114468D01*
G01X1654724Y1135039D02*
X1656594Y1133169D01*
G01X1654724Y1138779D02*
X1656594Y1136909D01*
G01X1654724Y1142519D02*
X1656594Y1140649D01*
G01X1658464Y1149999D02*
X1660334Y1148129D01*
G01X1654724Y1146259D02*
X1652854Y1144389D01*
G01X1654724Y1149999D02*
X1656594Y1148129D01*
G01X1658464Y1146259D02*
X1656594Y1144389D01*
G01X1658464Y1142519D02*
X1660334Y1140649D01*
G01X1656594Y1204232D02*
X1658464Y1206102D01*
G01X1652854Y1200491D02*
X1654724Y1198621D01*
G01X1652854Y1215452D02*
X1650984Y1217322D01*
G01X1656594Y1211712D02*
X1658464Y1213582D01*
G01X1656594Y1215452D02*
X1658464Y1217322D01*
G01X1656594Y1207972D02*
X1654724Y1209842D01*
G01X1649114Y1207972D02*
X1647244Y1206102D01*
G01X1654724D02*
X1652854Y1207972D01*
G01X1654724Y1213582D02*
X1652854Y1211712D01*
G01X1665190Y76587D02*
X1667590D01*
G01X1665190Y72615D02*
X1665218Y72587D01*
X1667590D01*
G01X1667545Y68581D02*
Y69564D01*
X1670568Y72587D01*
X1670740D01*
G01X1679470Y64722D02*
Y72429D01*
X1677132Y74767D01*
X1672920D01*
X1670740Y72587D01*
G01X1667545Y80581D02*
Y79618D01*
X1670576Y76587D01*
X1670740D01*
G01D02*
X1678410D01*
X1682030Y72967D01*
Y64722D01*
G01X1666629Y100625D02*
X1667995Y99259D01*
X1671551D01*
G01X1671002Y112083D02*
Y112402D01*
X1673088Y114488D01*
G01X1675291Y107921D02*
Y103621D01*
G01X1662148Y105087D02*
Y100625D01*
G01D02*
X1666629D01*
G01X1667208Y141247D02*
X1664283D01*
G01X1667208D02*
X1670008D01*
X1670855Y140400D01*
X1680857D01*
X1683105Y142648D01*
X1684627D01*
G01X1673945Y145768D02*
Y143868D01*
X1673595Y143518D01*
X1671695D01*
G01D02*
Y142392D01*
X1671922Y142165D01*
X1680265D01*
X1683100Y145000D01*
X1686061D01*
X1686700Y144361D01*
Y140316D01*
X1686079Y139695D01*
X1684627D01*
G01X1665988Y149414D02*
X1670441D01*
X1670795Y149768D01*
G01X1665988Y152367D02*
X1670789D01*
X1670795Y152373D01*
G01D02*
Y149768D01*
G01X1669352Y168713D02*
Y171523D01*
G01X1677731Y172665D02*
X1674810D01*
G01X1672502Y168713D02*
X1677683D01*
X1677731Y168665D01*
G01X1674810Y172665D02*
X1671441Y176034D01*
Y179897D01*
G01X1674747Y178560D02*
Y179904D01*
G01X1677731Y180665D02*
X1675508D01*
X1674747Y179904D01*
G01D02*
Y180204D01*
X1673085Y181866D01*
X1671441D01*
G01X1677731Y184665D02*
X1676900Y183834D01*
X1674637D01*
G01D02*
X1671441D01*
G01Y185803D02*
Y189278D01*
X1672348Y190185D01*
X1674157D01*
G01D02*
Y191730D01*
X1675092Y192665D01*
X1677731D01*
G01X1668882Y188362D02*
Y192490D01*
G01D02*
X1670716Y194324D01*
X1672715D01*
X1673557Y195166D01*
Y196620D01*
G01X1667318Y198828D02*
Y198628D01*
X1669326Y196620D01*
X1670407D01*
G01X1680881Y196665D02*
Y198033D01*
X1680077Y198837D01*
X1672157D01*
X1669820Y201174D01*
X1665913D01*
X1664779Y200040D01*
Y192361D01*
X1664840Y192300D01*
G01X1674927Y200864D02*
X1677826D01*
G01X1671052Y209229D02*
X1671774D01*
X1672362Y208641D01*
Y203429D01*
X1674927Y200864D01*
G01X1674950Y207037D02*
X1676777Y208864D01*
X1677826D01*
G01X1671052Y211197D02*
X1672505D01*
X1674950Y208752D01*
Y207037D01*
G01X1677826Y212864D02*
X1677417Y212455D01*
X1675016D01*
G01X1671052Y213166D02*
X1672738D01*
X1673449Y212455D01*
X1675016D01*
G01X1671052Y217103D02*
X1673065D01*
X1677826Y221864D01*
G01X1661525Y266114D02*
Y264678D01*
X1660750Y263903D01*
Y262685D01*
G01X1671093Y319290D02*
X1667480D01*
X1666101Y317911D01*
G01D02*
X1661388D01*
X1661350Y317873D01*
G01X1666101Y317911D02*
X1667281Y316731D01*
X1671093D01*
G01X1674545Y344878D02*
X1669449D01*
X1668979Y344408D01*
Y339559D01*
G01D02*
Y337606D01*
X1670261Y336324D01*
X1681888D01*
G01X1665945Y1138779D02*
X1664075Y1140649D01*
G01X1669685Y1153740D02*
X1667815Y1155610D01*
G01X1665945Y1146259D02*
X1664075Y1148129D01*
G01X1665945Y1153740D02*
X1664075Y1155610D01*
G01X1673425Y1142519D02*
X1675295Y1144389D01*
G01X1673425Y1149999D02*
X1675295Y1151869D01*
G01X1679470Y64722D02*
Y60513D01*
G01X1682030Y64722D02*
X1682330Y64422D01*
Y60438D01*
G01X1679598Y85731D02*
X1679470Y85603D01*
Y81848D01*
G01X1683152Y86046D02*
X1682030Y84924D01*
Y81848D01*
G01X1688011Y86012D02*
X1684884Y82885D01*
Y81848D01*
G01X1680155Y88801D02*
X1679598Y88244D01*
Y85731D01*
G01X1684104Y88729D02*
Y86998D01*
X1683152Y86046D01*
G01X1680155Y91951D02*
Y94351D01*
G01X1684104Y91879D02*
Y94279D01*
G01X1688011Y88824D02*
Y86012D01*
G01X1691566Y107899D02*
X1695566D01*
G01X1691269Y113684D02*
Y111534D01*
X1692019Y110784D01*
X1694291D01*
G01X1689301Y113684D02*
Y110794D01*
X1689291Y110784D01*
G01D02*
X1687566Y109059D01*
Y107899D01*
G01X1682780Y147754D02*
X1687018D01*
X1689700Y145068D01*
Y131007D01*
X1689591Y130898D01*
G01X1683591Y127748D02*
X1683814Y127525D01*
Y124315D01*
X1683782Y124283D01*
G01D02*
X1686176D01*
X1687333Y123126D01*
Y121558D01*
G01X1691269D02*
Y124163D01*
X1691769Y124663D01*
X1693870D01*
G01X1689301Y121558D02*
Y123785D01*
X1688848Y124879D01*
G01D02*
Y127005D01*
X1689591Y127748D01*
G01X1679440Y157370D02*
Y148980D01*
X1680669Y147754D01*
X1682780D01*
G01X1691713Y136742D02*
Y138338D01*
X1692213Y138838D01*
X1695214D01*
G01X1682780Y150904D02*
Y154865D01*
G01X1697432Y161958D02*
Y158209D01*
X1696932Y157709D01*
X1690561D01*
X1687717Y154865D01*
G01D02*
X1682780D01*
G01X1677731Y168665D02*
Y172665D01*
G01Y176665D02*
Y180665D01*
G01Y196665D02*
Y192665D01*
G01X1680881D02*
X1683524D01*
G01X1680881Y188665D02*
X1682906D01*
X1683637Y187934D01*
Y186778D01*
G01D02*
Y185398D01*
X1682904Y184665D01*
X1680881D01*
G01X1677826Y204864D02*
Y208864D01*
G01X1680976D02*
X1683556D01*
G01X1677823Y225719D02*
Y221867D01*
X1677826Y221864D01*
G01X1679825Y228631D02*
X1677823Y226629D01*
Y225719D01*
G01X1692061Y242078D02*
X1684789D01*
X1682301Y244566D01*
Y255458D01*
X1685723Y258880D01*
X1736333D01*
G01X1691241Y248371D02*
X1692923D01*
X1693660Y249108D01*
X1693932D01*
G01X1691241Y252371D02*
Y248371D01*
G01X1683523Y318740D02*
Y314890D01*
G01X1690687Y312849D02*
X1688380D01*
X1686339Y314890D01*
G01D02*
X1683523D01*
G01X1678573Y321849D02*
X1683482D01*
X1683523Y321890D01*
G01X1691534Y328844D02*
X1687849D01*
X1683523Y324518D01*
G01D02*
Y321890D01*
G01X1677810Y324466D02*
X1676299Y322955D01*
Y319760D01*
X1676769Y319290D01*
X1678573D01*
G01X1683207Y342319D02*
X1688676D01*
G01D02*
X1692676D01*
G01X1691534Y332584D02*
X1686408D01*
G01X1687424Y347937D02*
X1688676Y346685D01*
Y345469D01*
G01X1689920Y545912D02*
X1691111Y544721D01*
X1704530D01*
X1709238Y549429D01*
Y552165D01*
X1710174Y553101D01*
G01X1686770Y545912D02*
Y541912D01*
G01X1681925Y540335D02*
X1685193D01*
X1686770Y541912D01*
G01X1692028Y550137D02*
X1694545D01*
G01X1693000Y626912D02*
X1689920D01*
G01X1686770D02*
Y622912D01*
G01X1682016D02*
X1686770D01*
G01X1692126Y1138779D02*
X1693996Y1136909D01*
G01X1677165Y1149999D02*
X1679035Y1151869D01*
G01X1677165Y1142519D02*
X1679035Y1144389D01*
G01X1684645Y1149999D02*
X1682775Y1148129D01*
G01X1692126Y1153740D02*
X1693996Y1151870D01*
G01X1688385Y1142519D02*
X1686515Y1140649D01*
G01X1692126Y1146259D02*
X1693996Y1144389D01*
G01X1688385Y1157480D02*
X1686515Y1155610D01*
G01X1684645Y1142519D02*
X1682775Y1140649D01*
G01X1688385Y1149999D02*
X1686515Y1148129D01*
G01X1684645Y1157480D02*
X1682775Y1155610D01*
G01X1692126Y1161220D02*
X1693996Y1159350D01*
G01X1692126Y1183661D02*
X1693996Y1181791D01*
G01X1692126Y1176180D02*
X1693996Y1174310D01*
G01X1692126Y1191141D02*
X1693996Y1189271D01*
G01X1706335Y106495D02*
X1710251D01*
X1710317Y106561D01*
G01X1706335Y102495D02*
Y106495D01*
G01X1694291Y110784D02*
X1695566Y109509D01*
Y107899D01*
G01X1697645Y130903D02*
X1697614Y130934D01*
Y134838D01*
G01X1697645Y127753D02*
Y126313D01*
X1698851Y125107D01*
G01X1693870Y124663D02*
Y126008D01*
X1693591Y126287D01*
Y127748D01*
G01X1704235Y143762D02*
X1707465D01*
G01X1693692Y153296D02*
Y150265D01*
X1695240Y148717D01*
X1701365D01*
G01D02*
X1703518D01*
X1704235Y148000D01*
Y146912D01*
G01X1697614Y134838D02*
Y138838D01*
G01X1695214D02*
X1697614D01*
G01X1706460Y225055D02*
Y229782D01*
X1705686Y230556D01*
G01X1709941Y228747D02*
Y227724D01*
X1708429Y226212D01*
Y225055D01*
G01X1696910Y232859D02*
Y232681D01*
X1700945Y228646D01*
G01X1702523Y225055D02*
Y227068D01*
X1700945Y228646D01*
G01X1706312Y232959D02*
X1705686Y232333D01*
Y230556D01*
G01X1709098Y241681D02*
X1708457Y241040D01*
Y233660D01*
X1709133Y232984D01*
X1710547D01*
G01X1699040Y242078D02*
X1695211D01*
G01X1696809Y247292D02*
X1696552Y247035D01*
Y244571D01*
G01D02*
X1695211Y243230D01*
Y242078D01*
G01X1693932Y249108D02*
X1695069Y250245D01*
X1696809D01*
G01X1708702Y250599D02*
X1708348Y250245D01*
X1703895D01*
G01Y253198D02*
Y256394D01*
G01D02*
X1706427D01*
X1708898Y253923D01*
Y250795D01*
X1708702Y250599D01*
G01X1692676Y345469D02*
Y348015D01*
G01X1694545Y550137D02*
X1696917Y547765D01*
X1701425D01*
X1703945Y550285D01*
Y551381D01*
G01X1698716Y550065D02*
Y552316D01*
X1702724Y556324D01*
X1704944D01*
X1707685Y559065D01*
Y560043D01*
G01X1713545Y558287D02*
X1711985D01*
X1710229Y560043D01*
X1707685D01*
G01X1708015Y1137129D02*
X1706131D01*
X1705160Y1138100D01*
Y1171775D01*
X1706450Y1173065D01*
G01X1695866Y1138779D02*
X1697736Y1136909D01*
G01X1695866Y1153740D02*
X1697736Y1151870D01*
G01X1695866Y1146259D02*
X1697736Y1144389D01*
G01X1712526Y1153242D02*
Y1150166D01*
X1711960Y1149600D01*
X1711060D01*
X1708042Y1146582D01*
X1708015D01*
Y1142700D01*
G01D02*
Y1140279D01*
G01X1695866Y1161220D02*
X1697736Y1159350D01*
G01X1695866Y1176180D02*
X1697736Y1174310D01*
G01X1695866Y1183661D02*
X1697736Y1181791D01*
G01X1695866Y1191141D02*
X1697736Y1189271D01*
G01X1709820Y1199665D02*
X1707463Y1202022D01*
Y1204973D01*
X1708905Y1206415D01*
X1709827D01*
G01X1720334Y99961D02*
X1715559D01*
X1713394Y102126D01*
Y103411D01*
G01X1710519Y97667D02*
X1713788D01*
G01X1720334Y97599D02*
X1713856D01*
X1713788Y97667D01*
G01X1720334Y90512D02*
X1724446D01*
X1724584Y90650D01*
G01X1720334Y88150D02*
X1727431D01*
X1729896Y90615D01*
G01X1724334Y95236D02*
X1720334D01*
G01Y92874D02*
X1711421D01*
X1709184Y95111D01*
G01X1713394Y103411D02*
X1710317D01*
G01Y106561D02*
X1713553D01*
G01X1710547Y232984D02*
Y231180D01*
X1709941Y230574D01*
Y228747D01*
G01X1712248Y241681D02*
Y244297D01*
G01X1713746Y382723D02*
X1717746D01*
G01X1720571Y385644D02*
X1717746Y382819D01*
Y382723D01*
G01X1727803Y389013D02*
Y388103D01*
X1726801Y387101D01*
X1722028D01*
X1720571Y385644D01*
G01X1721746Y382723D02*
X1725746D01*
G01X1718710Y454334D02*
X1716310D01*
G01X1728050Y456044D02*
X1726410D01*
X1724580Y454214D01*
G01D02*
X1723412D01*
X1723292Y454334D01*
X1721860D01*
G01X1728050Y454076D02*
X1726888D01*
X1726300Y453488D01*
Y450422D01*
X1724923Y449045D01*
G01D02*
X1723634Y450334D01*
X1721860D01*
G01X1728050Y458012D02*
X1725945D01*
X1724627Y459330D01*
G01D02*
X1723631Y458334D01*
X1721860D01*
G01X1710174Y553101D02*
X1712210Y555137D01*
X1713545D01*
G01Y558287D02*
Y562137D01*
G01X1710511Y1138130D02*
X1711512Y1137129D01*
X1713008D01*
G01X1721008D02*
Y1134729D01*
G01Y1140279D02*
X1725008D01*
G01X1717008D02*
X1721008D01*
G01X1723805Y1142666D02*
X1723361D01*
X1723333Y1142638D01*
X1714333D01*
X1713008Y1141313D01*
Y1140279D01*
G01X1723974Y1146842D02*
Y1142835D01*
X1723805Y1142666D01*
G01X1715110Y1146071D02*
Y1153218D01*
X1715086Y1153242D01*
G01X1715110Y1146071D02*
X1713629D01*
X1713091Y1146609D01*
X1711333D01*
G01X1709967Y1153242D02*
X1709960Y1153249D01*
Y1160200D01*
X1711160Y1161400D01*
X1713500D01*
G01D02*
X1714360D01*
X1715086Y1160674D01*
Y1153242D01*
G01X1725191Y1171120D02*
Y1168768D01*
X1724191Y1167768D01*
G01X1726828Y1163968D02*
Y1166771D01*
X1725831Y1167768D01*
X1724191D01*
G01X1725680Y1157544D02*
X1723228D01*
X1721461Y1159311D01*
Y1170540D01*
X1722041Y1171120D01*
G01X1715086Y1167808D02*
Y1164126D01*
X1713500Y1162540D01*
Y1161400D01*
G01X1712715Y1181970D02*
X1711100Y1180355D01*
Y1174300D01*
X1712526Y1172874D01*
Y1171950D01*
G01D02*
Y1167808D01*
G01X1716700Y1174526D02*
X1717645Y1173581D01*
Y1167808D01*
G01X1719692Y1187215D02*
X1721702Y1185205D01*
G01X1725702Y1182055D02*
X1721702D01*
G01X1721674Y1178240D02*
X1719886D01*
X1719385Y1178741D01*
Y1180175D01*
G01D02*
Y1181255D01*
X1720185Y1182055D01*
X1721702D01*
G01X1721674Y1175090D02*
X1725674D01*
G01X1713239Y1176038D02*
X1714700Y1177499D01*
Y1183100D01*
X1716650Y1185050D01*
X1716731D01*
G01Y1181900D02*
X1716700Y1181869D01*
Y1174526D01*
G01X1712715Y1185120D02*
Y1188500D01*
G01X1713721Y1203311D02*
X1716320Y1200712D01*
Y1195226D01*
X1720448Y1191098D01*
X1741052D01*
X1744529Y1187621D01*
Y1121271D01*
X1745796Y1120004D01*
Y1117518D01*
X1744529Y1116251D01*
G01X1742029D02*
X1740735Y1117545D01*
Y1120869D01*
X1742029Y1122163D01*
Y1174158D01*
X1741559Y1174628D01*
X1739454D01*
X1738984Y1175098D01*
Y1175828D01*
X1739454Y1176298D01*
X1741559D01*
X1742029Y1176768D01*
Y1177498D01*
X1741559Y1177968D01*
X1739848D01*
X1739378Y1178438D01*
Y1179168D01*
X1739848Y1179638D01*
X1741559D01*
X1742029Y1180108D01*
Y1180838D01*
X1741559Y1181308D01*
X1739848D01*
X1739378Y1181778D01*
Y1182508D01*
X1739848Y1182978D01*
X1741559D01*
X1742029Y1183448D01*
Y1187271D01*
X1740100Y1189200D01*
X1719659D01*
X1714564Y1194295D01*
Y1199089D01*
X1710388Y1203265D01*
X1709827D01*
G01X1721662Y1201043D02*
Y1201151D01*
G01D02*
X1721660Y1201149D01*
Y1198569D01*
G01X1721662Y1201151D02*
Y1203443D01*
G01X1717568Y1203243D02*
X1718625Y1202186D01*
Y1199814D01*
G01X1709820Y1196515D02*
X1712457D01*
X1712542Y1196600D01*
G01X1722425Y1214986D02*
Y1215339D01*
X1720536Y1217228D01*
G01D02*
X1719227Y1218537D01*
X1717954D01*
G01X1725253Y1217814D02*
Y1217842D01*
X1723200Y1219895D01*
G01X1720783Y1221364D02*
X1721731D01*
X1723200Y1219895D01*
G01X1709827Y1206415D02*
Y1211293D01*
X1708745Y1212375D01*
Y1224125D01*
G01X1712966Y1224116D02*
Y1221864D01*
X1712423Y1221321D01*
Y1207759D01*
X1713721Y1206461D01*
G01X1717568Y1206393D02*
X1713789D01*
X1713721Y1206461D01*
G01X1726475Y1223170D02*
X1725452Y1224193D01*
X1723612D01*
G01X1708745Y1227275D02*
Y1229608D01*
X1710825Y1231688D01*
G01X1712966Y1227266D02*
Y1229841D01*
G01X1738444Y92874D02*
X1743175D01*
G01X1734267Y95236D02*
X1738444D01*
G01Y99961D02*
X1734217D01*
G01X1725746Y382723D02*
Y385123D01*
G01D02*
X1727317D01*
X1729772Y387578D01*
Y389013D01*
G01X1729746Y382723D02*
Y384123D01*
X1730746Y385123D01*
G01D02*
X1731740Y386117D01*
Y389013D01*
G01X1737746Y382723D02*
Y385123D01*
G01D02*
Y386599D01*
X1737246Y387099D01*
X1734209D01*
X1733709Y387599D01*
Y389013D01*
G01X1737746Y379573D02*
Y377213D01*
X1737786Y377173D01*
G01X1741420Y391569D02*
X1741417Y391572D01*
X1736268D01*
G01X1729751Y377173D02*
Y379568D01*
X1729746Y379573D01*
G01X1733746D02*
X1731346Y377173D01*
X1729751D01*
G01X1735924Y456044D02*
X1738814D01*
X1738824Y456034D01*
G01D02*
X1740549Y454309D01*
X1741709D01*
G01X1735924Y458012D02*
X1738074D01*
X1738824Y458762D01*
Y461034D01*
G01D02*
X1740099Y462309D01*
X1741709D01*
G01X1741800Y917900D02*
X1738560Y914660D01*
Y901930D01*
X1743211Y897279D01*
X1750087D01*
G01X1729008Y1134729D02*
Y1137129D01*
G01X1733008D02*
Y1134856D01*
X1732881Y1134729D01*
G01X1725008Y1134636D02*
Y1137129D01*
G01X1737008Y1140279D02*
X1733008D01*
G01D02*
X1729008D01*
G01D02*
X1729388Y1140659D01*
Y1146842D01*
G01X1732137Y1157404D02*
X1729388Y1154655D01*
Y1146842D01*
G01X1725008Y1140279D02*
X1726828Y1142099D01*
Y1146842D01*
G01X1725680Y1157544D02*
X1726828Y1156396D01*
Y1146842D01*
G01X1725674Y1175090D02*
Y1173978D01*
X1725191Y1173495D01*
Y1171120D01*
G01X1730999Y1175138D02*
X1729540D01*
X1729040Y1174638D01*
Y1171120D01*
G01D02*
X1729210Y1170950D01*
Y1167768D01*
G01D02*
X1729388Y1167590D01*
Y1163968D01*
G01X1732137Y1157404D02*
X1735805D01*
X1739800Y1161399D01*
Y1172030D01*
X1739130Y1172700D01*
X1733770D01*
X1732190Y1171120D01*
G01X1728343Y1185205D02*
X1725702D01*
G01X1731021Y1185201D02*
X1733052Y1187232D01*
Y1187310D01*
G01X1734989Y1185238D02*
X1737689D01*
G01X1731021Y1182051D02*
X1734952D01*
X1734989Y1182088D01*
G01D02*
X1736729D01*
X1737482Y1181335D01*
Y1180235D01*
G01D02*
Y1179038D01*
X1736732Y1178288D01*
X1734999D01*
G01Y1175138D02*
X1730999D01*
G01X1733660Y1198569D02*
Y1200817D01*
X1733662Y1200819D01*
Y1201039D01*
G01D02*
Y1203443D01*
G01X1729660Y1198569D02*
Y1201011D01*
X1729628Y1201043D01*
G01D02*
X1729662Y1201077D01*
Y1203443D01*
G01X1725660Y1198569D02*
Y1201041D01*
X1725658Y1201043D01*
G01D02*
X1725662Y1201047D01*
Y1203443D01*
G01X1737662D02*
Y1200969D01*
G01D02*
Y1198571D01*
X1737660Y1198569D01*
G01X1726475Y1223170D02*
X1728082Y1221563D01*
Y1220643D01*
G01X1733739Y1226300D02*
X1731813Y1228226D01*
X1731533D01*
G01X1726441Y1227022D02*
Y1227904D01*
X1729325Y1230788D01*
X1729553D01*
G01D02*
X1730493D01*
X1731533Y1229748D01*
Y1228226D01*
G01X1730911Y1223472D02*
Y1224427D01*
X1729322Y1226016D01*
G01X1759006Y98198D02*
X1755006D01*
G01X1743175Y92874D02*
Y95018D01*
X1744569Y96412D01*
X1753345D01*
X1755006Y98073D01*
Y98198D01*
G01X1755112Y262685D02*
Y264373D01*
X1753784Y265701D01*
G01D02*
X1754962Y266879D01*
X1756688D01*
X1757384Y267575D01*
Y269603D01*
G01X1754165Y284908D02*
X1758165D01*
G01X1757384Y277477D02*
Y279751D01*
X1755419Y281716D01*
G01D02*
X1756777D01*
X1758165Y283104D01*
Y284908D01*
G01X1752497Y373479D02*
Y371076D01*
G01X1744524Y379429D02*
Y375754D01*
G01X1752497Y376629D02*
X1748497D01*
Y376830D01*
G01X1755433Y379028D02*
X1756497Y377964D01*
Y376629D01*
G01X1750721Y383732D02*
Y383478D01*
X1750364Y383121D01*
X1748216D01*
X1744524Y379429D01*
G01X1748497Y376830D02*
Y378722D01*
X1748863Y379088D01*
X1750135D01*
G01X1752689Y383732D02*
Y381642D01*
X1750135Y379088D01*
G01X1754658Y383732D02*
Y379803D01*
X1755433Y379028D01*
G01X1741746Y379573D02*
Y377173D01*
G01Y382723D02*
X1742937D01*
X1744180Y383966D01*
G01X1741746Y382723D02*
X1741753Y382730D01*
Y387999D01*
X1741420Y388332D01*
Y391569D01*
G01X1756894Y472020D02*
Y470748D01*
X1757260Y470382D01*
X1759353D01*
G01X1752250Y474574D02*
X1754340D01*
X1756894Y472020D01*
G01X1756553Y466409D02*
X1759353D01*
G01X1752250Y472606D02*
X1752504D01*
X1752861Y472249D01*
Y470101D01*
X1756553Y466409D01*
G01X1741709Y458309D02*
Y462309D01*
G01X1759353Y478382D02*
X1758018D01*
X1756954Y477318D01*
G01X1752250Y476543D02*
X1756179D01*
X1756954Y477318D01*
G01X1759353Y487382D02*
X1756391D01*
G01X1752250Y480480D02*
X1753240D01*
X1754763Y482003D01*
Y485754D01*
X1756391Y487382D01*
G01X1750032Y879199D02*
X1746897D01*
G01X1753182D02*
X1753196Y879213D01*
X1757879D01*
G01X1750033Y884649D02*
X1746884D01*
G01X1753183D02*
X1753201Y884667D01*
X1757914D01*
G01X1753237Y897279D02*
X1757914D01*
X1757933Y897260D01*
G01X1749267Y915451D02*
Y918413D01*
G01X1757805Y913336D02*
X1755690Y915451D01*
X1752417D01*
G01X1757275Y926200D02*
Y919425D01*
X1761400Y915300D01*
X1765100D01*
X1766236Y914164D01*
Y912920D01*
G01X1757275Y931100D02*
Y926200D01*
G01X1754125Y935100D02*
X1746600D01*
G01X1757275D02*
Y931100D01*
G01X1756422Y1634729D02*
X1760422D01*
G01X1767552Y76587D02*
X1769952D01*
G01X1767552Y72615D02*
X1767580Y72587D01*
X1769952D01*
G01X1769907Y80581D02*
Y79618D01*
X1772938Y76587D01*
X1773102D01*
G01D02*
X1780772D01*
X1784392Y72967D01*
Y64722D01*
G01X1769907Y68581D02*
Y69564D01*
X1772930Y72587D01*
X1773102D01*
G01X1781832Y64722D02*
Y72469D01*
X1779534Y74767D01*
X1775282D01*
X1773102Y72587D01*
G01X1764510Y97475D02*
X1762010D01*
G01X1768991Y100625D02*
X1770357Y99259D01*
X1773913D01*
G01X1775450Y114488D02*
X1773364Y112402D01*
Y112083D01*
G01X1764510Y100625D02*
X1768991D01*
G01X1764510Y105087D02*
Y100625D01*
G01X1771714Y168713D02*
Y171523D01*
G01X1771244Y188362D02*
Y192490D01*
G01D02*
X1773068Y194314D01*
X1775212D01*
X1775919Y195021D01*
Y196620D01*
G01X1772769D02*
X1768748D01*
X1767202Y195074D01*
Y192300D01*
G01X1773414Y213166D02*
X1775100D01*
X1775811Y212455D01*
X1777378D01*
G01X1773414Y209229D02*
X1774136D01*
X1774724Y208641D01*
Y203429D01*
X1777289Y200864D01*
G01X1773414Y211197D02*
X1774867D01*
X1777312Y208752D01*
Y207037D01*
G01X1773414Y217103D02*
X1775427D01*
X1780188Y221864D01*
G01X1759112Y259535D02*
Y256303D01*
G01X1758871Y265896D02*
Y264086D01*
X1759112Y263845D01*
Y262685D01*
G01X1763112D02*
Y263903D01*
X1763887Y264678D01*
Y266114D01*
G01X1761360Y281982D02*
X1759352Y279974D01*
Y277477D01*
G01Y269603D02*
Y267599D01*
X1758871Y267118D01*
Y265896D01*
G01X1763887Y266114D02*
X1761320Y268681D01*
Y269603D01*
G01X1762165Y284908D02*
Y282787D01*
X1761360Y281982D01*
G01X1765497Y376631D02*
X1769497D01*
G01X1765497D02*
Y379591D01*
G01X1769497Y373481D02*
X1772954Y370024D01*
X1804600D01*
X1815008Y380432D01*
Y424601D01*
G01X1758595Y383732D02*
Y382742D01*
X1760118Y381219D01*
X1763869D01*
X1765497Y379591D01*
G01X1759353Y474382D02*
Y470382D01*
G01X1764906Y474382D02*
X1767728Y471560D01*
X1770986D01*
G01X1764906Y474382D02*
X1762503D01*
G01X1759353Y487382D02*
Y489224D01*
X1759928Y489799D01*
X1767401D01*
X1768700Y488500D01*
X1771552D01*
X1797837Y477612D01*
X1819900Y455549D01*
Y426695D01*
X1817806Y424601D01*
X1815008D01*
G01X1763480Y880636D02*
X1761336D01*
X1759913Y879213D01*
X1757879D01*
G01X1757914Y884667D02*
X1759976Y882605D01*
X1763480D01*
G01Y910164D02*
X1760977D01*
X1757805Y913336D01*
G01X1757933Y897260D02*
Y900124D01*
X1762067Y904258D01*
X1763480D01*
G01X1772188Y1428369D02*
X1787622D01*
X1790209Y1430956D01*
G01X1763000Y1581925D02*
Y1580288D01*
X1760617Y1577905D01*
X1758390D01*
G01X1761072Y1593192D02*
Y1590719D01*
G01X1765072Y1593192D02*
Y1589073D01*
X1763000Y1587001D01*
Y1585075D01*
G01X1766313Y1580198D02*
Y1583687D01*
X1764925Y1585075D01*
X1763000D01*
G01X1761072Y1596342D02*
Y1597904D01*
X1759947Y1599029D01*
G01X1758820Y1604357D02*
Y1600156D01*
X1759947Y1599029D01*
G01X1765072Y1596342D02*
Y1599479D01*
X1765040Y1599511D01*
G01X1763820Y1604357D02*
Y1600731D01*
X1765040Y1599511D01*
G01X1762041Y1631511D02*
X1763820Y1629732D01*
Y1625223D01*
G01X1768422Y1632245D02*
Y1630193D01*
X1768820Y1629795D01*
Y1625223D01*
G01X1760422Y1634729D02*
Y1633130D01*
X1762041Y1631511D01*
G01X1768422Y1634729D02*
Y1632245D01*
G01X1764422Y1634729D02*
X1768422D01*
G01X1772422D02*
Y1632636D01*
X1773820Y1631238D01*
G01X1776422Y1634729D02*
X1772422D01*
G01X1785246Y60660D02*
X1784392Y61514D01*
Y64722D01*
G01X1781832D02*
Y60513D01*
G01X1784392Y81848D02*
Y85231D01*
X1785084Y85923D01*
X1786466D01*
G01X1781960Y85731D02*
X1781832Y85603D01*
Y81848D01*
G01X1787246D02*
X1790577D01*
X1790712Y81713D01*
G01X1786466Y85923D02*
Y88729D01*
G01X1782517Y88801D02*
X1781960Y88244D01*
Y85731D01*
G01X1786466Y91879D02*
Y94279D01*
G01X1782517Y91951D02*
Y94351D01*
G01X1777653Y107921D02*
Y103621D01*
G01X1774864Y168713D02*
X1780045D01*
X1780093Y168665D01*
G01D02*
Y172665D01*
G01D02*
X1777172D01*
G01D02*
X1773803Y176034D01*
Y179897D01*
G01X1777109Y178560D02*
Y179904D01*
G01X1780093Y176665D02*
Y180665D01*
G01X1777109Y179904D02*
X1777870Y180665D01*
X1780093D01*
G01X1777109Y179904D02*
Y180204D01*
X1775447Y181866D01*
X1773803D01*
G01X1780093Y196665D02*
X1775964D01*
X1775919Y196620D01*
G01X1780093Y192665D02*
X1777454D01*
X1776519Y191730D01*
Y190185D01*
G01D02*
X1774710D01*
X1773803Y189278D01*
Y185803D01*
G01X1780093Y184665D02*
X1779262Y183834D01*
X1776999D01*
G01D02*
X1773803D01*
G01X1783243Y192665D02*
X1785779D01*
G01X1789587Y200716D02*
X1789613Y200690D01*
Y196531D01*
G01X1783243Y196665D02*
X1785886D01*
G01X1789613Y196531D02*
X1786020D01*
X1785886Y196665D01*
G01X1783243Y188665D02*
X1785268D01*
X1785999Y187934D01*
Y186778D01*
G01D02*
Y185398D01*
X1785266Y184665D01*
X1783243D01*
G01X1780188Y212864D02*
X1779779Y212455D01*
X1777378D01*
G01X1777289Y200864D02*
X1780188D01*
G01Y204864D02*
Y208864D01*
G01X1777312Y207037D02*
X1779139Y208864D01*
X1780188D01*
G01X1783338D02*
X1785918D01*
G01X1780185Y225719D02*
Y221867D01*
X1780188Y221864D01*
G01X1782187Y228631D02*
X1780185Y226629D01*
Y225719D01*
G01X1792763Y196531D02*
X1794516D01*
X1795627Y197642D01*
Y290354D01*
X1792428Y293553D01*
Y298376D01*
X1787674Y303130D01*
G01X1780018Y468607D02*
X1777608D01*
X1776561Y467560D01*
G01X1774136Y471560D02*
Y467560D01*
G01D02*
X1776561D01*
G01X1792986Y474560D02*
Y472060D01*
X1792486Y471560D01*
X1787104D01*
G01X1780018D02*
X1778061D01*
X1777061Y472560D01*
Y475560D01*
G01X1790061Y474513D02*
X1787104D01*
G01X1774136Y479560D02*
Y475560D01*
G01X1777061D02*
X1774136D01*
G01X1789537Y927652D02*
Y930498D01*
G01X1780016Y912920D02*
Y916810D01*
X1782357Y919151D01*
G01X1789537Y924502D02*
Y922736D01*
X1785952Y919151D01*
X1782357D01*
G01X1793474Y924411D02*
Y922654D01*
X1789774Y918954D01*
G01D02*
X1787218Y916398D01*
X1783467D01*
X1781984Y914915D01*
Y912920D01*
G01X1792638Y989660D02*
Y992512D01*
X1791183Y993967D01*
X1780379D01*
X1779143Y995203D01*
G01X1787059Y1430956D02*
X1782088D01*
G01D02*
X1780865Y1432179D01*
Y1442536D01*
X1779718Y1443683D01*
X1778227D01*
G01X1783178Y1443715D02*
X1786091D01*
G01X1774339Y1443685D02*
X1778225D01*
X1778227Y1443683D01*
G01X1787745Y1437765D02*
Y1442774D01*
X1788686Y1443715D01*
X1790264D01*
G01X1783178Y1440762D02*
Y1437550D01*
G01X1786936Y1467917D02*
Y1463431D01*
X1786205Y1462700D01*
G01X1783055Y1472952D02*
Y1462700D01*
G01X1795100Y1463678D02*
X1792222Y1460800D01*
X1784955D01*
X1783055Y1462700D01*
G01X1774216Y1475875D02*
X1778102D01*
X1778104Y1475873D01*
G01D02*
X1783023D01*
X1783055Y1475905D01*
G01D02*
X1785349D01*
X1786936Y1474318D01*
Y1467917D01*
G01X1773820Y1625223D02*
Y1631238D01*
G01X1790712Y81713D02*
Y85375D01*
X1790373Y85714D01*
Y88824D01*
G01X1809095Y435101D02*
X1807315D01*
X1804283Y438133D01*
X1800445D01*
G01X1800346Y432227D02*
X1802415D01*
X1803530Y431112D01*
G01X1811858Y431601D02*
X1807660D01*
X1807171Y431112D01*
X1803530D01*
G01X1800933Y456026D02*
X1796933D01*
G01X1796901Y449550D02*
Y451981D01*
X1797907Y452987D01*
G01D02*
X1796933Y453961D01*
Y456026D01*
G01X1800933Y459176D02*
Y461607D01*
G01X1792986Y474560D02*
X1790108D01*
X1790061Y474513D01*
G01X1809700Y910175D02*
X1804600D01*
G01D02*
X1798531D01*
X1798520Y910164D01*
G01X1797365Y930761D02*
Y927533D01*
X1797374Y927524D01*
G01X1793474Y927561D02*
Y930374D01*
G01X1795764Y912920D02*
Y918695D01*
G01D02*
X1797374Y920305D01*
Y924374D01*
G01X1802983Y1223198D02*
Y1223092D01*
X1800489Y1220598D01*
G01X1797402Y1220047D02*
X1799158D01*
X1800489Y1220598D01*
G01X1797402Y1222016D02*
X1798334D01*
X1802063Y1225745D01*
X1805126D01*
G01X1811482Y1226423D02*
X1809358D01*
X1806133Y1223198D01*
G01X1790209Y1430956D02*
X1795415D01*
X1796160Y1431701D01*
Y1439587D01*
X1797294Y1440721D01*
X1800046D01*
G01X1790264Y1446668D02*
Y1443715D01*
G01X1799946Y1444543D02*
X1795374D01*
G01X1800046Y1440721D02*
X1803879D01*
X1803885Y1440715D01*
G01D02*
X1807386D01*
X1807393Y1440722D01*
G01X1812202Y1432624D02*
X1800829D01*
X1800046Y1433407D01*
Y1437571D01*
G01X1799923Y1472911D02*
X1795100Y1468088D01*
Y1463678D01*
G01X1802813Y1464015D02*
X1799923Y1466905D01*
Y1469761D01*
G01X1799823Y1476733D02*
X1798409Y1478147D01*
X1795147D01*
G01D02*
X1792905Y1475905D01*
X1790141D01*
G01Y1478858D02*
Y1475905D01*
G01X1799923Y1472911D02*
X1799929Y1472905D01*
X1803762D01*
G01D02*
X1803769Y1472912D01*
X1807270D01*
G01X1811858Y424601D02*
Y428101D01*
G01X1809095Y435101D02*
X1811858D01*
G01Y428101D02*
Y431601D01*
G01X1809700Y907025D02*
X1814900D01*
G01D02*
X1819775D01*
X1819900Y906900D01*
G01X1819156Y1085145D02*
Y1089145D01*
G01D02*
X1816756D01*
G01X1812866Y1093171D02*
X1814301D01*
X1816756Y1090716D01*
Y1089145D01*
G01X1819156Y1077145D02*
Y1081145D01*
G01D02*
X1819060D01*
X1816235Y1083970D01*
G01D02*
X1814778Y1085427D01*
Y1090332D01*
X1813908Y1091202D01*
X1812866D01*
G01Y1095139D02*
X1815762D01*
X1816756Y1094145D01*
G01D02*
X1817756Y1093145D01*
X1819156D01*
G01Y1101145D02*
X1816756D01*
G01D02*
X1815280D01*
X1814780Y1100645D01*
Y1097608D01*
X1814280Y1097108D01*
X1812866D01*
G01X1822306Y1101145D02*
X1823746D01*
X1824706Y1100185D01*
G01X1822306Y1105145D02*
X1823706D01*
X1824706Y1106145D01*
G01X1810307Y1099667D02*
Y1104816D01*
X1810310Y1104819D01*
G01D02*
X1813547D01*
X1813873Y1105145D01*
X1819156D01*
G01X1824706Y1093150D02*
Y1094745D01*
X1822306Y1097145D01*
G01X1824706Y1093150D02*
X1822311D01*
X1822306Y1093145D01*
G01X1812130Y1205349D02*
X1809349Y1208130D01*
Y1208309D01*
G01X1828272Y1105996D02*
X1824855D01*
X1824706Y1106145D01*
G01X1828272Y1105996D02*
Y1102107D01*
G01Y1098957D02*
Y1095968D01*
G54D264*
G01X409284Y745280D02*
Y741316D01*
G01X407316Y745280D02*
Y742416D01*
X406200Y741300D01*
G01X405347Y780320D02*
Y783047D01*
X407000Y784700D01*
G01X425820Y759847D02*
X429253D01*
G01X526897Y797102D02*
X522697D01*
G01X526897Y824661D02*
X522481D01*
G01X534672Y789327D02*
Y785037D01*
G01X526897Y812850D02*
X531313D01*
G01X526897Y822693D02*
X531313D01*
G01X526897Y826630D02*
X531313D01*
G01X536641Y834405D02*
Y838649D01*
G01X542546Y789327D02*
Y784911D01*
G01X554357Y784889D02*
Y789327D01*
G01X551524Y784889D02*
X552389Y785754D01*
Y789327D01*
G01X550420D02*
Y793743D01*
G01X540578Y789327D02*
Y793889D01*
G01X546483Y834405D02*
Y830321D01*
X546855Y829949D01*
G01X562231Y789327D02*
Y784911D01*
G01X558294Y789327D02*
Y784911D01*
G01X556326Y789327D02*
Y793743D01*
G01X571975Y812850D02*
X567559D01*
G01X571975Y803008D02*
X567559D01*
G01X560263Y834405D02*
Y829989D01*
G01X571975Y824661D02*
X567559D01*
G01X556326Y829989D02*
Y834405D01*
G01X1491656Y924453D02*
X1487240D01*
G01X1491656Y940201D02*
X1496072D01*
G01X1491656Y950044D02*
X1496072D01*
G01X1491656Y952012D02*
X1487240D01*
G01X1491656Y953981D02*
X1496072D01*
G01X1511242Y961756D02*
Y958460D01*
X1512161Y957541D01*
G01X1501400Y961756D02*
Y966000D01*
G01X1516283Y912240D02*
X1517148Y913105D01*
Y916678D01*
G01X1519116Y912240D02*
Y916678D01*
G01X1523053D02*
Y912262D01*
G01X1521085Y921094D02*
Y916678D01*
G01X1515179Y921094D02*
Y916678D01*
G01X1536734Y940201D02*
X1528638D01*
X1527876Y939439D01*
G01X1536734Y930359D02*
X1529555D01*
X1527267Y932647D01*
G01X1525022Y961756D02*
Y957340D01*
G01X1529128Y952978D02*
X1531926D01*
X1532892Y952012D01*
X1536734D01*
G01X1521085Y957340D02*
Y961756D01*
G01X1782600Y874500D02*
Y875500D01*
X1781984Y876116D01*
Y877880D01*
G01X1780016D02*
Y874400D01*
G01X1798520Y892447D02*
X1802000D01*
G54D138*
X417211Y1126178D03*
X449339D03*
X482798D03*
X514926D03*
X1331385D03*
X1363513D03*
X1396972D03*
X1429100D03*
G54D18*
X8786Y85411D03*
X6298Y99649D03*
X18298D03*
X6499Y138847D03*
X8264Y159013D03*
X15184Y150286D03*
X19184D03*
X16709Y173285D03*
X17822Y212889D03*
X6811Y1005604D03*
X10701D03*
X14645D03*
X11768Y1525256D03*
X14375Y1550556D03*
X10367Y1550563D03*
X31971Y106469D03*
X23184Y150286D03*
X32201Y236042D03*
X26192Y616794D03*
X30192D03*
X33992D03*
X27556Y1005604D03*
X33659D03*
X21506D03*
X25674Y1491774D03*
X35850Y1553213D03*
X26231Y1551642D03*
X22381Y1551660D03*
X45643Y470402D03*
X49643D03*
X39549Y1005604D03*
X45858D03*
X51946D03*
X40951Y1553213D03*
X47074Y1553204D03*
X52048Y1553179D03*
X65759Y442977D03*
X54936Y454821D03*
X61759Y442977D03*
X57759D03*
X62224Y470542D03*
X66345Y490147D03*
X56514Y536891D03*
X64408Y578815D03*
X63684Y602708D03*
X61192Y639294D03*
X57692D03*
X64692D03*
X56149Y824291D03*
X65774Y1005604D03*
X61779D03*
X57834D03*
X57702Y1198728D03*
X61380Y1205454D03*
X53737Y1199888D03*
X54351Y1483866D03*
X56114Y1553178D03*
X64747Y1553171D03*
X63090Y1615060D03*
X80660Y101256D03*
X76660D03*
X70577Y101609D03*
X84808Y103511D03*
X76766Y262593D03*
X84766D03*
X78106Y662474D03*
X74910Y687495D03*
X84699Y1004449D03*
X87652Y578620D03*
X93456Y655308D03*
X95836Y986014D03*
X99836D03*
Y995014D03*
X95836D03*
X97609Y1013880D03*
X104662Y116534D03*
X115582Y107807D03*
X111582D03*
X113607Y130806D03*
X106796Y157923D03*
X111836Y986014D03*
X103836D03*
X115836D03*
X107836D03*
X111836Y995014D03*
X103836D03*
X115836D03*
X107836D03*
X109601Y1226509D03*
X105601D03*
X119582Y107807D03*
X128251Y146820D03*
X120184Y212889D03*
X127235Y448564D03*
X119836Y986014D03*
X123836D03*
X127836D03*
X131836D03*
X119836Y995014D03*
X123836D03*
X127836D03*
X131836D03*
X127604Y1105591D03*
Y1118191D03*
Y1130791D03*
Y1143391D03*
Y1155991D03*
Y1168591D03*
Y1181191D03*
X134333Y106469D03*
X134563Y236042D03*
X138971Y541874D03*
X142961Y541833D03*
X143836Y986014D03*
X147836D03*
X139836D03*
X135836D03*
X143836Y995014D03*
X147836D03*
X139836D03*
X135836D03*
X139250Y1012854D03*
Y1025454D03*
X159836Y986014D03*
X151836D03*
X159836Y995014D03*
X155836D03*
X151836D03*
X179022Y101256D03*
X172939Y101609D03*
X179128Y262593D03*
X183022Y101256D03*
X188526Y100533D03*
Y108145D03*
X187128Y262593D03*
X201033Y91859D03*
X207024Y116534D03*
X213944Y107807D03*
X209158Y157923D03*
X221944Y107807D03*
X217944D03*
X215969Y130806D03*
X230613Y146820D03*
X222546Y212889D03*
X221942Y1537368D03*
X225753Y1537198D03*
X229942Y1549368D03*
X236695Y106469D03*
X236925Y236042D03*
X242102Y653729D03*
X246102D03*
X240842Y1530368D03*
X233753Y1537198D03*
X237942Y1549368D03*
X244942D03*
X233942D03*
X250102Y653729D03*
X248042Y1530368D03*
X275301Y101609D03*
X281384Y101256D03*
X290888Y100533D03*
X285384Y101256D03*
X290888Y108145D03*
X289490Y262593D03*
X281490D03*
X303395Y91859D03*
X309386Y116534D03*
X311520Y157923D03*
X312263Y321798D03*
X324306Y107807D03*
X320306D03*
X316306D03*
X318222Y130697D03*
X324908Y212889D03*
X317416Y345377D03*
X321416D03*
X323285Y553195D03*
X339057Y106469D03*
X332975Y146820D03*
X339287Y236042D03*
X342486Y382631D03*
X342285Y558195D03*
X336755Y1140187D03*
X337629Y1178808D03*
X342298Y1193899D03*
X346486Y382631D03*
X358486D03*
X350486D03*
X354486D03*
X353202Y411985D03*
X345748Y1140187D03*
X350414Y1178148D03*
X358443Y1177169D03*
X354414Y1178148D03*
X359761Y1185109D03*
X354442Y1185113D03*
X350442D03*
X346136Y1194034D03*
X370931Y367347D03*
X362486Y382631D03*
X374714Y793252D03*
X365748Y1140187D03*
X362282Y1177832D03*
X363729Y1185146D03*
X393250Y100533D03*
X387746Y101256D03*
X383746D03*
X377663Y101609D03*
X393250Y108145D03*
X383852Y262593D03*
X391852D03*
X389237Y376537D03*
X381237D03*
X385237D03*
X404686Y42956D03*
X400686D03*
X394237Y376539D03*
X403478Y875751D03*
X399369D03*
X399816Y956130D03*
X400043Y967387D03*
X404043D03*
X403263Y1158242D03*
X397461Y1566492D03*
X401461D03*
X420422Y365140D03*
X412318Y365132D03*
X411847Y432320D03*
X425673Y459084D03*
X426000Y789283D03*
X416200Y798583D03*
X417682Y1057696D03*
X410668Y1105613D03*
X414455D03*
X422532Y1101825D03*
X421461Y1566492D03*
X417461D03*
X431424Y365001D03*
X435024D03*
X427566Y883916D03*
X427913Y1101825D03*
X431285Y1113379D03*
X449745Y628543D03*
X445745D03*
X442796Y1105613D03*
X446583D03*
X454660Y1101825D03*
X456025Y1220971D03*
X459387Y116534D03*
X474307Y107807D03*
X470307D03*
X466307D03*
X468332Y130806D03*
X461521Y157923D03*
X474909Y212889D03*
X468836Y543080D03*
X460041Y1101825D03*
X463413Y1113379D03*
X468850Y1158242D03*
X462687D03*
X461319Y1220971D03*
X489058Y106469D03*
X482976Y146820D03*
X489288Y236042D03*
X485485Y437400D03*
X489485D03*
X491078Y616794D03*
X483278D03*
X487278D03*
X476255Y1105613D03*
X480042D03*
X488119Y1101825D03*
X500729Y467402D03*
X504729D03*
X501082Y992664D03*
X505958Y1057989D03*
X493500Y1101825D03*
X496872Y1113379D03*
X520845Y439977D03*
X516845D03*
X512845D03*
X510022Y451821D03*
X517310Y467542D03*
X523431Y490147D03*
X513600Y536891D03*
X521494Y578815D03*
X520770Y602708D03*
X516770D03*
X518278Y639294D03*
X514778D03*
X521778D03*
X519285Y728479D03*
X515285D03*
X511285D03*
X523285D03*
X509096Y758773D03*
X513504Y761890D03*
X508383Y1105613D03*
X512170D03*
X520247Y1101825D03*
X537747Y101256D03*
X533747D03*
X527664Y101609D03*
X533853Y262593D03*
X539285Y728479D03*
X535285D03*
X531285D03*
X527285D03*
X524319Y761864D03*
X536715Y1009304D03*
X529000Y1113379D03*
X528274Y1158242D03*
X555758Y91859D03*
X543251Y100533D03*
Y108145D03*
X541853Y262593D03*
X544738Y578620D03*
X552923Y986014D03*
Y995014D03*
X554696Y1013880D03*
X561749Y116534D03*
X568669Y107807D03*
X570694Y130806D03*
X563883Y157923D03*
X568464Y757957D03*
X560256Y779157D03*
X556923Y986014D03*
X568923D03*
X560923D03*
X564923D03*
X556923Y995014D03*
X568923D03*
X560923D03*
X564923D03*
X562688Y1226509D03*
X566688D03*
X564242Y1528168D03*
X571809Y1538484D03*
X562786Y1537592D03*
X558786D03*
X571942Y1547268D03*
X576669Y107807D03*
X572669D03*
X585338Y146820D03*
X577271Y212889D03*
X584321Y448564D03*
X573203Y938380D03*
X576923Y986014D03*
X580923D03*
X584923D03*
X572923D03*
X576923Y995014D03*
X580923D03*
X584923D03*
X572923D03*
X584691Y1105591D03*
Y1118191D03*
Y1130791D03*
Y1143391D03*
Y1155991D03*
Y1168591D03*
Y1181191D03*
X587809Y1538484D03*
X579809D03*
X583742Y1547768D03*
X591420Y106469D03*
X591650Y236042D03*
X600047Y541833D03*
X596057Y541874D03*
X600923Y986014D03*
X604923D03*
X592923D03*
X596923D03*
X588923D03*
X600923Y995014D03*
X604923D03*
X592923D03*
X596923D03*
X588923D03*
X596337Y1012854D03*
Y1025454D03*
X600242Y1541568D03*
X591809Y1538484D03*
X608923Y986014D03*
X616923D03*
X608923Y995014D03*
X616923D03*
X612923D03*
X636109Y101256D03*
X630026Y101609D03*
X636215Y262593D03*
X645613Y100533D03*
X640109Y101256D03*
X645613Y108145D03*
X644215Y262593D03*
X658120Y91859D03*
X664111Y116534D03*
X666245Y157923D03*
X679031Y107807D03*
X671031D03*
X675031D03*
X673056Y130806D03*
X679633Y212889D03*
X693782Y106469D03*
X687700Y146820D03*
X694012Y236042D03*
X699188Y653729D03*
X688728Y703417D03*
X703188Y653729D03*
X707188D03*
X713382Y705220D03*
X732388Y101609D03*
X723811Y742039D03*
X742471Y101256D03*
X747975Y100533D03*
X738471Y101256D03*
X747975Y108145D03*
X738577Y262593D03*
X746577D03*
X747140Y1586793D03*
X748924Y1614851D03*
X748997Y1624393D03*
X747590Y1633692D03*
X760482Y91859D03*
X766473Y116534D03*
X763145Y1586771D03*
X759169Y1586818D03*
X763452Y1616825D03*
X752150Y1633717D03*
X781393Y107807D03*
X773393D03*
X777393D03*
X775418Y130806D03*
X768607Y157923D03*
X781995Y212889D03*
X769349Y321798D03*
X774502Y345377D03*
X778502D03*
X780371Y553195D03*
X783215Y1452633D03*
X767512Y1449685D03*
X777033Y1592480D03*
X781110D03*
X767452Y1616825D03*
X773822Y1633208D03*
X796144Y106469D03*
X790062Y146820D03*
X796374Y236042D03*
X799371Y558195D03*
X793842Y1140187D03*
X794716Y1178808D03*
X798324Y1198092D03*
X799230Y1206514D03*
X799901Y1472584D03*
X791610Y1599496D03*
X787447Y1599519D03*
X802835Y1140187D03*
X811529Y1185113D03*
X811501Y1178148D03*
X807501D03*
X807529Y1185113D03*
X814148Y1380666D03*
X832284Y716497D03*
X827284Y709547D03*
Y716497D03*
X828880Y870347D03*
X828643Y896072D03*
X826987Y929688D03*
X831409Y922276D03*
X827409D03*
X828423Y962177D03*
X822835Y1140187D03*
X816848Y1185109D03*
X820826Y1178196D03*
X820816Y1185146D03*
X816826Y1178196D03*
X840833Y101256D03*
X844833D03*
X834750Y101609D03*
X840939Y262593D03*
X848284Y716497D03*
X839290Y709527D03*
X843284Y709547D03*
X839290Y716477D03*
X843284Y716497D03*
X833112Y836573D03*
X836405Y863475D03*
X832880Y870347D03*
X832643Y896072D03*
X842000Y901483D03*
X848628Y912572D03*
X846000Y901483D03*
X841064Y922076D03*
X837235D03*
X840423Y962177D03*
X862844Y91859D03*
X850337Y100533D03*
Y108145D03*
X848939Y262593D03*
X858586Y379983D03*
X854086D03*
X858586Y390483D03*
X854086D03*
X863086D03*
X852284Y709547D03*
Y716497D03*
X856628Y912572D03*
X864628D03*
X849205Y929692D03*
X852488Y1017136D03*
X857884D03*
X864007D03*
X874531Y200408D03*
X880736Y388763D03*
X875916Y816523D03*
X872628Y912572D03*
X880628D03*
X879740Y944184D03*
X870401Y1017136D03*
X875954D03*
X893736Y388763D03*
X888736D03*
X884736D03*
X892931Y539551D03*
X885931D03*
X889431D03*
X895933Y615651D03*
X892728Y792759D03*
X895916Y816523D03*
X888628Y912572D03*
X892628D03*
X896628D03*
X881454Y1017136D03*
X885210D03*
X889089D03*
X893613Y1017279D03*
X904614Y343347D03*
X908114D03*
X911072Y384390D03*
X907173Y448661D03*
X899931Y539551D03*
X913208Y615502D03*
X909208D03*
X904376Y615422D03*
X900376D03*
X903916Y806373D03*
X899916D03*
Y816523D03*
X903916D03*
X909416D03*
X900200Y912583D03*
X907300D03*
X903700D03*
X912628Y925609D03*
X904057Y940596D03*
X906255Y1018764D03*
X898046Y1017223D03*
X902225Y1018711D03*
X901392Y1207731D03*
X905070Y1214457D03*
X897427Y1208891D03*
X916473Y116534D03*
X927393Y107807D03*
X923393D03*
X925418Y130806D03*
X918607Y157923D03*
X915072Y384390D03*
X920999Y475425D03*
X925418Y680853D03*
X921418D03*
X921061Y712828D03*
X925061D03*
X927916Y814523D03*
X921790Y816523D03*
X920628Y925609D03*
X924628D03*
X928628D03*
X916628D03*
X927984Y1017136D03*
X916465D03*
X921861D03*
X931393Y107807D03*
X940062Y146820D03*
X932661Y198060D03*
X938125Y236727D03*
X942757Y257672D03*
X941685Y360736D03*
X942437Y367688D03*
X931072Y384390D03*
X940365Y616794D03*
X944365D03*
X932412Y680853D03*
X938526Y730508D03*
X935916Y814523D03*
X939916D03*
X941535Y826540D03*
X937635D03*
X940516Y898088D03*
X944628Y925609D03*
X936628D03*
X940628D03*
X932628D03*
X945671Y988726D03*
X939931Y1017136D03*
X945431D03*
X934378D03*
X946144Y106469D03*
X947040Y221213D03*
X951278Y241031D03*
Y248010D03*
X959816Y470402D03*
X948165Y616794D03*
X961503Y704315D03*
X953551D03*
X957551D03*
X959950Y731521D03*
X951100Y841583D03*
X952783Y833266D03*
X947200Y841583D03*
X957900Y853483D03*
X958567Y933302D03*
X950567D03*
X953671Y988726D03*
X961671D03*
X949671D03*
X950987Y1017136D03*
X954866D03*
X961404Y1208891D03*
X969109Y454821D03*
X975932Y442977D03*
X971932D03*
X963816Y470402D03*
X976397Y470542D03*
X970687Y536891D03*
X978581Y578815D03*
X977857Y602708D03*
X973857D03*
X975365Y639294D03*
X971865D03*
X963950Y731521D03*
X966746Y933275D03*
X962567Y933302D03*
X965671Y988726D03*
X967625Y1017367D03*
X971760Y1017387D03*
X963823Y1017223D03*
X975659Y1017408D03*
X965369Y1207731D03*
X969047Y1214457D03*
X990833Y101256D03*
X994833D03*
X984750Y101609D03*
X990939Y262593D03*
X990405Y314000D03*
X988045Y364067D03*
X992045D03*
X979932Y442977D03*
X980518Y490147D03*
X978865Y639294D03*
X983712Y719572D03*
X994051Y816826D03*
X1000337Y100533D03*
Y108145D03*
X998939Y262593D03*
X1000698Y305734D03*
X996045Y364067D03*
X1001825Y578620D03*
X1007990Y771457D03*
X995990D03*
X1006699Y816883D03*
X1002699D03*
X1010699D03*
X1010009Y986014D03*
Y995014D03*
X998872Y1004449D03*
X1000248Y1024394D03*
X1012844Y91859D03*
X1018835Y116534D03*
X1025755Y107807D03*
X1020969Y157923D03*
X1016635Y305734D03*
X1020635D03*
X1025749D03*
X1012635D03*
X1018922Y805798D03*
X1014819Y935395D03*
X1026009Y986014D03*
X1018009D03*
X1022009D03*
X1014009D03*
X1026009Y995014D03*
X1018009D03*
X1022009D03*
X1014009D03*
X1011782Y1013880D03*
X1019774Y1226509D03*
X1023774D03*
X1017329Y1316495D03*
X1020049Y1333819D03*
X1019671Y1347982D03*
X1019257Y1366456D03*
X1033755Y107807D03*
X1029755D03*
X1027780Y130806D03*
X1042424Y146820D03*
X1034357Y212889D03*
X1029639Y305734D03*
X1041408Y448564D03*
X1030009Y986014D03*
X1038009D03*
X1042009D03*
X1034009D03*
Y995014D03*
X1030009D03*
X1038009D03*
X1042009D03*
X1041777Y1105591D03*
Y1118191D03*
Y1130791D03*
Y1143391D03*
Y1155991D03*
Y1168591D03*
Y1181191D03*
X1038996Y1371550D03*
X1048506Y106469D03*
X1048736Y236042D03*
X1045650Y305734D03*
X1057134Y541833D03*
X1053144Y541874D03*
X1046009Y986014D03*
X1050009D03*
X1054009D03*
X1058009D03*
X1046009Y995014D03*
X1050009D03*
X1054009D03*
X1058009D03*
X1053423Y1012854D03*
Y1025454D03*
X1074009Y986014D03*
X1066009D03*
X1062009D03*
X1074009Y995014D03*
X1066009D03*
X1062009D03*
X1070009D03*
X1087112Y101609D03*
X1086108Y1526491D03*
X1086469Y1585468D03*
X1090904Y1596264D03*
X1089474Y1634908D03*
X1093195Y101256D03*
X1097195D03*
X1102699Y100533D03*
Y108145D03*
X1093301Y262593D03*
X1101301D03*
X1096233Y1585491D03*
X1104233D03*
X1102904Y1596264D03*
X1093474Y1634908D03*
X1101474D03*
X1105474D03*
X1115206Y91859D03*
X1121197Y116534D03*
X1123331Y157923D03*
X1136117Y107807D03*
X1132117D03*
X1128117D03*
X1130142Y130806D03*
X1136719Y212889D03*
X1150868Y106469D03*
X1144786Y146820D03*
X1151098Y236042D03*
X1156275Y653729D03*
X1156485Y770625D03*
X1155485Y842125D03*
X1160275Y653729D03*
X1164275D03*
X1167485Y828625D03*
X1159485D03*
X1171485Y842125D03*
X1163485D03*
X1167485D03*
X1159485D03*
X1189474Y101609D03*
X1183485Y828625D03*
X1175485D03*
X1183485Y842125D03*
X1179485D03*
X1175485D03*
X1195557Y101256D03*
X1199557D03*
X1205061Y100533D03*
Y108145D03*
X1195663Y262593D03*
X1203663D03*
X1217568Y91859D03*
X1238479Y107807D03*
X1223559Y116534D03*
X1234479Y107807D03*
X1230479D03*
X1232504Y130806D03*
X1225693Y157923D03*
X1226436Y321798D03*
X1231589Y345377D03*
X1235589D03*
X1237458Y553195D03*
X1253230Y106469D03*
X1247148Y146820D03*
X1239081Y212889D03*
X1253460Y236042D03*
X1250928Y1140187D03*
X1251802Y1178808D03*
X1249230Y1192404D03*
X1256659Y382631D03*
X1268659D03*
X1260659D03*
X1264659D03*
X1267375Y411985D03*
X1256458Y558195D03*
X1261622Y901500D03*
X1259921Y1140187D03*
X1264587Y1178148D03*
X1268587D03*
X1268615Y1185113D03*
X1264615D03*
X1255485Y1201908D03*
X1275660Y345693D03*
X1279655Y345634D03*
X1276659Y382631D03*
X1272659D03*
X1280042Y905131D03*
X1279921Y1140187D03*
X1277912Y1178196D03*
X1273912D03*
X1273934Y1185109D03*
X1277902Y1185146D03*
X1297919Y101256D03*
X1301919D03*
X1291836Y101609D03*
X1298025Y262593D03*
X1303410Y376537D03*
X1287437Y375662D03*
X1295410Y376537D03*
X1299410D03*
X1292566Y807304D03*
X1298909Y818575D03*
X1288155Y897983D03*
X1302000Y922983D03*
X1298000D03*
X1300882Y934047D03*
X1300500Y966983D03*
X1314859Y42956D03*
X1318859D03*
X1307423Y100533D03*
Y108145D03*
X1306025Y262593D03*
X1308410Y376539D03*
X1316903Y368224D03*
X1317000Y793483D03*
X1313000D03*
Y809483D03*
X1317000D03*
X1313152Y934047D03*
X1309103D03*
X1317000Y940983D03*
X1304949Y934047D03*
X1307000Y966983D03*
X1317437Y1158242D03*
X1325007Y368232D03*
X1334009Y368093D03*
X1326020Y432320D03*
X1333000Y793483D03*
X1329000D03*
X1325000D03*
X1321000D03*
X1333000Y809483D03*
X1325000D03*
X1329000D03*
X1321000D03*
X1322500Y922983D03*
X1326500D03*
Y940983D03*
X1327000Y966983D03*
X1332000D03*
X1331856Y1057696D03*
X1324842Y1105613D03*
X1328629D03*
X1337609Y368093D03*
X1339846Y459084D03*
X1341000Y793483D03*
X1337000D03*
X1341000Y809483D03*
X1345000D03*
X1349000D03*
X1337000D03*
X1350500Y922983D03*
X1336000Y940983D03*
X1337691Y951626D03*
X1342087Y1101825D03*
X1336706D03*
X1345459Y1113379D03*
X1353000Y809483D03*
X1354500Y922983D03*
X1358500D03*
X1362500D03*
X1366500D03*
X1361948Y949086D03*
X1356970Y1105613D03*
X1360757D03*
X1373560Y116534D03*
X1384480Y107807D03*
X1380480D03*
X1382505Y130806D03*
X1375694Y157923D03*
X1370500Y922983D03*
X1378500D03*
X1374500D03*
X1382500D03*
X1373948Y949086D03*
X1374215Y1101825D03*
X1368834D03*
X1377587Y1113379D03*
X1376861Y1158242D03*
X1383024D03*
X1388480Y107807D03*
X1397149Y146820D03*
X1389082Y212889D03*
X1397452Y616794D03*
X1390537Y809162D03*
X1386335Y809187D03*
X1388346Y927128D03*
X1390429Y1105613D03*
X1394216D03*
X1403231Y106469D03*
X1403461Y236042D03*
X1414903Y467402D03*
X1405252Y616794D03*
X1401452D03*
X1401000Y922983D03*
X1407674Y1101825D03*
X1402293D03*
X1411046Y1113379D03*
X1416684Y1514632D03*
X1411586Y1546437D03*
X1411094Y1569115D03*
X1431019Y439977D03*
X1427019D03*
X1424196Y451821D03*
X1431484Y467542D03*
X1418903Y467402D03*
X1427774Y536891D03*
X1430944Y602708D03*
X1432452Y639294D03*
X1428952D03*
X1420132Y1057989D03*
X1422557Y1105613D03*
X1426344D03*
X1426253Y1410760D03*
X1430374Y1498553D03*
X1433405Y1543475D03*
X1432913Y1566153D03*
X1447920Y101256D03*
X1441837Y101609D03*
X1448026Y262593D03*
X1435019Y439977D03*
X1437605Y490147D03*
X1435668Y578815D03*
X1434944Y602708D03*
X1435952Y639294D03*
X1443459Y1037394D03*
X1434421Y1101825D03*
X1443174Y1113379D03*
X1442448Y1158242D03*
X1436792Y1558424D03*
X1457424Y100533D03*
X1451920Y101256D03*
X1457424Y108145D03*
X1456026Y262593D03*
X1458912Y578620D03*
X1455959Y1004449D03*
X1469931Y91859D03*
X1475922Y116534D03*
X1478056Y157923D03*
X1475096Y986014D03*
X1479096D03*
X1471096D03*
X1467096D03*
X1475096Y995014D03*
X1479096D03*
X1471096D03*
X1467096D03*
X1468869Y1013880D03*
X1480861Y1226509D03*
X1476861D03*
X1490842Y107807D03*
X1482842D03*
X1486842D03*
X1484867Y130806D03*
X1491444Y212889D03*
X1491096Y986014D03*
X1487096D03*
X1495096D03*
X1483096D03*
X1491096Y995014D03*
X1487096D03*
X1495096D03*
X1483096D03*
X1505593Y106469D03*
X1499511Y146820D03*
X1505823Y236042D03*
X1498495Y448564D03*
X1514221Y541833D03*
X1510231Y541874D03*
X1503096Y986014D03*
X1507096D03*
X1511096D03*
X1499096D03*
X1503096Y995014D03*
X1507096D03*
X1511096D03*
X1499096D03*
X1510510Y1025454D03*
Y1012854D03*
X1498864Y1105591D03*
Y1118191D03*
Y1130791D03*
Y1143391D03*
Y1155991D03*
Y1168591D03*
Y1181191D03*
X1525015Y906508D03*
X1523096Y986014D03*
X1519096D03*
X1515096D03*
X1523096Y995014D03*
X1519096D03*
X1527096D03*
X1515096D03*
X1544199Y101609D03*
X1531096Y986014D03*
Y995014D03*
X1554282Y101256D03*
X1559786Y100533D03*
X1550282Y101256D03*
X1559786Y108145D03*
X1550388Y262593D03*
X1558388D03*
X1572293Y91859D03*
X1578284Y116534D03*
X1593204Y107807D03*
X1589204D03*
X1585204D03*
X1587229Y130806D03*
X1580418Y157923D03*
X1593806Y212889D03*
X1594307Y1505038D03*
X1594500Y1511983D03*
X1607955Y106469D03*
X1601873Y146820D03*
X1608185Y236042D03*
X1608483Y783385D03*
X1608383Y798185D03*
X1608283Y812185D03*
X1600333Y1446468D03*
X1605000Y1511983D03*
X1598142Y1530368D03*
X1613362Y653729D03*
X1617362D03*
X1621362D03*
X1616683Y750485D03*
X1616583Y764485D03*
X1634083Y777685D03*
X1632583Y790385D03*
X1631383Y804485D03*
X1652644Y101256D03*
X1656644D03*
X1646561Y101609D03*
X1652750Y262593D03*
X1660750D03*
X1674655Y91859D03*
X1662148Y100533D03*
Y108145D03*
X1680646Y116534D03*
X1691566Y107807D03*
X1687566D03*
X1689591Y130806D03*
X1682780Y157923D03*
X1683523Y321798D03*
X1688676Y345377D03*
X1692676D03*
X1695566Y107807D03*
X1704235Y146820D03*
X1696168Y212889D03*
X1694545Y553195D03*
X1708015Y1140187D03*
X1708889Y1178808D03*
X1708745Y1227183D03*
X1710317Y106469D03*
X1710547Y236042D03*
X1713746Y382631D03*
X1717746D03*
X1725746D03*
X1721746D03*
X1724462Y411985D03*
X1713545Y558195D03*
X1717008Y1140187D03*
X1725674Y1178148D03*
X1721674D03*
X1725702Y1185113D03*
X1721702D03*
X1713721Y1206369D03*
X1709827Y1206323D03*
X1712966Y1227174D03*
X1733746Y382631D03*
X1729746D03*
X1737008Y1140187D03*
X1734999Y1178196D03*
X1730999D03*
X1731021Y1185109D03*
X1734989Y1185146D03*
X1755006Y101256D03*
X1748923Y101609D03*
X1755112Y262593D03*
X1752497Y376537D03*
X1756497D03*
X1756297Y1018535D03*
X1753221Y1621562D03*
X1764510Y100533D03*
X1759006Y101256D03*
X1764510Y108145D03*
X1763112Y262593D03*
X1765497Y376539D03*
X1760497Y376537D03*
X1765131Y1018535D03*
X1760487D03*
X1771992D03*
X1774339Y1443593D03*
X1774216Y1475783D03*
X1763000Y1584983D03*
X1777017Y91859D03*
X1783107Y432320D03*
X1789463Y966233D03*
X1784145Y1018535D03*
X1790035D03*
X1778042D03*
X1796933Y459084D03*
X1793474Y927469D03*
X1796344Y1018535D03*
X1802432D03*
X1805384Y1209377D03*
X1803885Y1440623D03*
X1803762Y1472813D03*
X1808320Y1018535D03*
X1812265D03*
X1816260D03*
X1809349Y1208217D03*
X1813027Y1214943D03*
X1828272Y1102015D03*
Y1109054D03*
G54D147*
X428500Y338500D03*
X1331085Y341592D03*
G54D183*
X721756Y-31826D03*
X841756Y-71006D03*
X1005256Y-31826D03*
X1075256Y-71006D03*
X1291756Y-31956D03*
X1331756Y-71006D03*
X1576256Y-32086D03*
X1586256Y-71006D03*
G54D72*
X39062Y1200716D03*
X41424D03*
Y1210952D03*
X417631Y881916D03*
X415269Y871680D03*
Y881916D03*
X431394Y627843D03*
X433756Y638079D03*
Y627843D03*
X882752Y1209719D03*
X885114Y1219955D03*
Y1209719D03*
X946729D03*
X949091Y1219955D03*
Y1209719D03*
X1790709Y1210205D03*
X1793071Y1220441D03*
Y1210205D03*
G54D237*
X958968Y1367717D03*
Y1383465D03*
Y1379528D03*
Y1375591D03*
Y1371654D03*
Y1399213D03*
Y1395276D03*
Y1391339D03*
Y1387402D03*
Y1407087D03*
Y1403150D03*
X972512Y1381496D03*
Y1377559D03*
Y1373622D03*
Y1369685D03*
Y1397245D03*
Y1393308D03*
Y1389370D03*
Y1385434D03*
Y1405119D03*
Y1401182D03*
G54D192*
X801057Y1448158D03*
Y1457016D03*
G54D228*
X944439Y944423D03*
X941880D03*
X939321D03*
X936762D03*
Y967455D03*
X939321D03*
X941880D03*
X944439D03*
X959794Y944423D03*
X957235D03*
X952117D03*
X949558D03*
X946998D03*
X954676D03*
X957235Y967455D03*
X946998D03*
X949558D03*
X952117D03*
X954676D03*
X959794D03*
G54D165*
X454290Y627944D03*
G54D246*
X1015674Y1396137D03*
X1023862D03*
G54D129*
X390780Y748036D03*
Y750005D03*
Y751973D03*
Y753942D03*
Y755910D03*
Y757879D03*
Y759847D03*
Y761816D03*
Y763784D03*
Y765753D03*
Y767721D03*
Y769690D03*
Y771658D03*
Y773627D03*
Y775595D03*
Y777564D03*
X1763480Y880636D03*
Y882605D03*
Y884573D03*
Y886542D03*
Y888510D03*
Y890479D03*
Y892447D03*
Y894416D03*
Y896384D03*
Y898353D03*
Y900321D03*
Y902290D03*
Y904258D03*
Y906227D03*
Y908195D03*
Y910164D03*
G54D81*
X56446Y829677D03*
X68652D03*
X56446Y831645D03*
X68652D03*
X56446Y837551D03*
X68652D03*
X56446Y833614D03*
Y835583D03*
X68652D03*
Y833614D03*
X573500Y943766D03*
X585706D03*
X573500Y951640D03*
X585706D03*
X573500Y945734D03*
Y947703D03*
Y949672D03*
X585706D03*
Y947703D03*
Y945734D03*
X995234Y838324D03*
Y846198D03*
Y840292D03*
Y842261D03*
Y844230D03*
X1007440Y846198D03*
Y838324D03*
Y844230D03*
Y842261D03*
Y840292D03*
X1015116Y940781D03*
X1027322D03*
X1015116Y942749D03*
Y944718D03*
X1027322D03*
Y942749D03*
X1015116Y948655D03*
X1027322D03*
X1015116Y946687D03*
X1027322D03*
X1789760Y971619D03*
Y973587D03*
Y975556D03*
Y977525D03*
Y979493D03*
X1801966Y971619D03*
Y977525D03*
Y975556D03*
Y973587D03*
Y979493D03*
G54D27*
X18745Y200645D03*
X25745D03*
X29424Y667294D03*
X36424D03*
X29424Y675765D03*
X36424D03*
X34410Y1220505D03*
Y1234305D03*
Y1227405D03*
Y1241205D03*
X49393Y523969D03*
X37959Y559194D03*
X44959D03*
X37959Y567194D03*
X44959D03*
X37959Y575194D03*
X44959D03*
X41410Y1220505D03*
X47750Y1221988D03*
X41410Y1234305D03*
Y1227405D03*
X47750Y1228888D03*
Y1235788D03*
X41410Y1241205D03*
X59203Y477988D03*
X66203D03*
X56393Y523969D03*
X63149Y822618D03*
X54750Y1221988D03*
Y1228888D03*
Y1235788D03*
X83998Y229621D03*
X76998D03*
X83525Y664104D03*
X70149Y822618D03*
X90525Y664104D03*
X121107Y200645D03*
X128107D03*
X179360Y229621D03*
X186360D03*
X223469Y200645D03*
X230469D03*
X242583Y669913D03*
X246583Y661113D03*
X250583Y669913D03*
X288722Y229621D03*
X281722D03*
X325831Y200645D03*
X327427Y312849D03*
X319427D03*
X323427Y321649D03*
X332831Y200645D03*
X358676Y466326D03*
X365676D03*
X372500Y494216D03*
X365500D03*
X391084Y229621D03*
X384084D03*
X392767Y408142D03*
X385767D03*
X400968Y846677D03*
X407968D03*
X398190Y1093068D03*
X405190D03*
X398184Y1085881D03*
X405184D03*
X421726Y654538D03*
Y647730D03*
X423241Y846644D03*
X416241D03*
X423241Y862644D03*
X416241D03*
X423241Y854644D03*
X416241D03*
X440090Y515536D03*
X438226Y654538D03*
Y647730D03*
X428726Y654538D03*
Y647730D03*
X439744Y1093088D03*
X447090Y515536D03*
X445226Y654538D03*
Y647730D03*
X452591Y996766D03*
X459591D03*
X446744Y1093088D03*
X475832Y200645D03*
X471770Y480801D03*
X464770D03*
X463777Y1093068D03*
X470777D03*
X482832Y200645D03*
X506479Y523969D03*
X495045Y559194D03*
X502045D03*
X495045Y567194D03*
X502045D03*
X495045Y575194D03*
X502045D03*
X505331Y1093088D03*
X505189Y1085890D03*
X516289Y477988D03*
X523289D03*
X513479Y523969D03*
X512331Y1093088D03*
X512189Y1085890D03*
X534085Y229621D03*
X541085D03*
X578194Y200645D03*
X585194D03*
X580203Y936707D03*
X587203D03*
X636447Y229621D03*
X643447D03*
X680556Y200645D03*
X687556D03*
X699669Y669913D03*
X707669D03*
X703669Y661113D03*
X745809Y229621D03*
X738809D03*
X782918Y200645D03*
X784513Y312849D03*
X776513D03*
X780513Y321649D03*
X789918Y200645D03*
X815762Y460326D03*
X822762D03*
X829586Y489216D03*
X822586D03*
X848171Y229621D03*
X841171D03*
X881093Y421483D03*
X876440Y1236491D03*
Y1229591D03*
Y1243391D03*
Y1250291D03*
X888093Y421483D03*
X891440Y1230991D03*
Y1237891D03*
X883440Y1236491D03*
Y1229591D03*
X891440Y1244791D03*
X883440Y1243391D03*
Y1250291D03*
X898440Y1230991D03*
Y1237891D03*
Y1244791D03*
X933584Y185816D03*
X940584D03*
X940417Y1229591D03*
Y1236491D03*
Y1243391D03*
Y1250291D03*
X952132Y559194D03*
X959132D03*
X952132Y567194D03*
X959132D03*
X952132Y575194D03*
X959132D03*
X962417Y1230991D03*
X955417D03*
X962417Y1237891D03*
X955417D03*
X947417Y1229591D03*
Y1236491D03*
X962417Y1244791D03*
X955417D03*
X947417Y1243391D03*
Y1250291D03*
X973376Y477988D03*
X963566Y523969D03*
X970566D03*
X976703Y842659D03*
X991171Y229621D03*
X980376Y477988D03*
X983703Y842659D03*
X998171Y229621D03*
X1021703Y843159D03*
X1014703D03*
X1021819Y933722D03*
X1035280Y200645D03*
X1042280D03*
X1028819Y933722D03*
X1100533Y229621D03*
X1093533D03*
X1137642Y200645D03*
X1144642D03*
X1156756Y669913D03*
X1164756D03*
X1160756Y661113D03*
X1202895Y229621D03*
X1195895D03*
X1233600Y312849D03*
X1237600Y321649D03*
X1240004Y200645D03*
X1247004D03*
X1241600Y312849D03*
X1279849Y466326D03*
X1272849D03*
X1286673Y494216D03*
X1279673D03*
X1298257Y229621D03*
X1299940Y408142D03*
X1305257Y229621D03*
X1306940Y408142D03*
X1312364Y1093068D03*
X1319364D03*
X1312358Y1085881D03*
X1319358D03*
X1366765Y996766D03*
X1360918Y1093088D03*
X1353918D03*
X1373765Y996766D03*
X1377951Y1093068D03*
X1384951D03*
X1390005Y200645D03*
X1397005D03*
X1409219Y559194D03*
X1416219D03*
X1409219Y567194D03*
X1416219D03*
X1409219Y575194D03*
X1416219D03*
X1430463Y477988D03*
X1420653Y523969D03*
X1427653D03*
X1426505Y1093088D03*
X1419505D03*
X1426363Y1085890D03*
X1419363D03*
X1448258Y229621D03*
X1437463Y477988D03*
X1455258Y229621D03*
X1492367Y200645D03*
X1499367D03*
X1557620Y229621D03*
X1550620D03*
X1594729Y200645D03*
X1601729D03*
X1613843Y669913D03*
X1621843D03*
X1617843Y661113D03*
X1659982Y229621D03*
X1652982D03*
X1690687Y312849D03*
X1697091Y200645D03*
X1704091D03*
X1698687Y312849D03*
X1694687Y321649D03*
X1736936Y466326D03*
X1729936D03*
X1736760Y494216D03*
X1755344Y229621D03*
X1757027Y408142D03*
X1743760Y494216D03*
X1762344Y229621D03*
X1764027Y408142D03*
X1784397Y1236977D03*
X1791397D03*
X1784397Y1230077D03*
X1791397D03*
X1784397Y1243877D03*
X1791397D03*
X1784397Y1250777D03*
X1791397D03*
X1796463Y964560D03*
X1803463D03*
X1806397Y1231477D03*
X1799397D03*
X1806397Y1238377D03*
X1799397D03*
X1806397Y1245277D03*
X1799397D03*
G54D63*
X42893Y619311D03*
X46436D03*
X49979D03*
X53523D03*
X499979D03*
X503522D03*
X507065D03*
X510609D03*
X957066D03*
X960609D03*
X964152D03*
X967696D03*
X1414153D03*
X1417696D03*
X1421239D03*
X1424783D03*
G54D36*
X17874Y1041679D03*
X26360D03*
X48093D03*
X39607D03*
X440077Y1234726D03*
X448563D03*
X478786D03*
X487272D03*
X864564Y1050682D03*
X873050D03*
X894783D03*
X886297D03*
X928541D03*
X937027D03*
X958760D03*
X950274D03*
X1362737Y1234726D03*
X1354251D03*
X1392960D03*
X1401446D03*
X1772521Y1051168D03*
X1781007D03*
X1802740D03*
X1794254D03*
G54D90*
X56348Y1727941D03*
Y1737941D03*
X56248Y1750941D03*
X56348Y1773941D03*
X56248Y1760941D03*
X56348Y1783941D03*
X56248Y1806941D03*
Y1796941D03*
X308448Y1737941D03*
Y1727941D03*
Y1750941D03*
Y1760941D03*
Y1773941D03*
Y1783941D03*
X308348Y1796941D03*
Y1806941D03*
X343286Y1738583D03*
Y1728583D03*
X343112Y1751624D03*
X343212Y1774624D03*
X343112Y1761624D03*
X343212Y1784624D03*
Y1797624D03*
Y1807624D03*
X595386Y1728583D03*
Y1738583D03*
X595312Y1751624D03*
Y1774624D03*
Y1761624D03*
Y1784624D03*
Y1807624D03*
Y1797624D03*
X630083Y1738286D03*
Y1728286D03*
X629861Y1751765D03*
X629711Y1775438D03*
X629861Y1761765D03*
X629711Y1785438D03*
X629475Y1798845D03*
Y1808845D03*
X882183Y1728286D03*
Y1738286D03*
X881911Y1751765D03*
X881761Y1775438D03*
X881911Y1761765D03*
X881761Y1785438D03*
X881525Y1798845D03*
Y1808845D03*
X917279Y1738990D03*
Y1728990D03*
X917163Y1752566D03*
Y1762566D03*
X917073Y1786014D03*
Y1776014D03*
X917166Y1800435D03*
Y1810435D03*
X1169329Y1728990D03*
Y1738990D03*
X1169263Y1752566D03*
Y1762566D03*
X1169123Y1776014D03*
Y1786014D03*
X1169216Y1800435D03*
Y1810435D03*
G54D156*
X420661Y1119422D03*
X423141Y1113822D03*
Y1119422D03*
X418181Y1113822D03*
Y1119422D03*
X420661Y1113822D03*
X455269Y1119422D03*
X450309Y1113822D03*
Y1119422D03*
X452789Y1113822D03*
Y1119422D03*
X455269Y1113822D03*
X488728Y1119422D03*
X483768Y1113822D03*
X486248D03*
Y1119422D03*
X483768D03*
X488728Y1113822D03*
X515484Y695757D03*
X515504Y701351D03*
X521159Y706388D03*
X515649D03*
X523929D03*
X518389D03*
X518376Y1113822D03*
Y1119422D03*
X520856Y1113822D03*
Y1119422D03*
X515896Y1113822D03*
Y1119422D03*
X529469Y706230D03*
X526699Y706388D03*
X1332355Y1113822D03*
Y1119422D03*
X1334835Y1113822D03*
Y1119422D03*
X1337315Y1113822D03*
Y1119422D03*
X1366963D03*
Y1113822D03*
X1364483Y1119422D03*
Y1113822D03*
X1369443Y1119422D03*
Y1113822D03*
X1397942Y1119422D03*
X1400422D03*
Y1113822D03*
X1397942D03*
X1402902Y1119422D03*
Y1113822D03*
X1432550Y1119422D03*
Y1113822D03*
X1430070Y1119422D03*
Y1113822D03*
X1435030Y1119422D03*
Y1113822D03*
G54D255*
X1236871Y1715189D03*
Y1744208D03*
X1236864Y1773377D03*
X1235371Y1802909D03*
X1250055Y1710189D03*
Y1720189D03*
Y1739208D03*
Y1749208D03*
X1250048Y1768377D03*
Y1778377D03*
X1248555Y1797909D03*
Y1807909D03*
X1734069Y1710189D03*
Y1720189D03*
Y1739208D03*
Y1749208D03*
X1734062Y1768377D03*
Y1778377D03*
X1734069Y1797909D03*
Y1807909D03*
X1747253Y1715189D03*
Y1744208D03*
X1747246Y1773377D03*
X1747253Y1802909D03*
G54D45*
X27130Y219149D03*
X129492D03*
X231854D03*
X334216D03*
X384382Y389638D03*
X484217Y219149D03*
X586579D03*
X688941D03*
X791303D03*
X879708Y402979D03*
X941969Y204320D03*
X1043665Y219149D03*
X1146027D03*
X1248389D03*
X1298555Y389638D03*
X1398390Y219149D03*
X1500752D03*
X1603114D03*
X1705476D03*
X1755642Y389638D03*
G54D54*
X51043Y60709D03*
Y150197D03*
X153405Y60709D03*
Y150197D03*
X190325Y455492D03*
Y503760D03*
Y583957D03*
Y636752D03*
X255767Y60709D03*
Y150197D03*
X279360Y368760D03*
Y421555D03*
Y501752D03*
Y550020D03*
X358129Y60709D03*
Y150197D03*
X508130Y60709D03*
Y150197D03*
X610492Y60709D03*
Y150197D03*
X647411Y455492D03*
Y503760D03*
Y583957D03*
Y636752D03*
X712854Y60709D03*
Y150197D03*
X736446Y368760D03*
Y421555D03*
Y501752D03*
Y550020D03*
X815216Y60709D03*
Y150197D03*
X965216Y60709D03*
Y150197D03*
X1067578Y60709D03*
Y150197D03*
X1104498Y455492D03*
Y503760D03*
Y583957D03*
Y636752D03*
X1169940Y60709D03*
Y150197D03*
X1193533Y368760D03*
Y421555D03*
Y501752D03*
Y550020D03*
X1272302Y60709D03*
Y150197D03*
X1422303Y60709D03*
Y150197D03*
X1524665Y60709D03*
Y150197D03*
X1561585Y455492D03*
Y503760D03*
Y583957D03*
Y636752D03*
X1627027Y60709D03*
Y150197D03*
X1650620Y368760D03*
Y421555D03*
Y501752D03*
Y550020D03*
X1729389Y60709D03*
Y150197D03*
G54D219*
X910492Y311046D03*
Y309471D03*
X904704Y311046D03*
Y309471D03*
X910492Y312621D03*
X904704D03*
G54D174*
X522524Y699411D03*
G54D274*
G01X529414Y690553D02*
X528958Y690742D01*
X527257Y692443D01*
X526993D01*
G01X529493Y694943D02*
X529495Y694941D01*
X531382Y692521D01*
G01X529414Y708269D02*
X526699Y706388D01*
G01X531382Y706301D02*
X531074Y705559D01*
X529501Y703986D01*
Y702622D01*
G01X895586Y562097D02*
X896051Y562562D01*
Y566990D01*
G01X881814Y571419D02*
X887685D01*
G01X882904Y581261D02*
X887685D01*
G01X882466Y574066D02*
X883145Y573387D01*
X887685D01*
G01X881510Y572917D02*
X882268D01*
X882782Y572403D01*
X884732D01*
G01X886093Y840568D02*
X884518Y838993D01*
Y835804D01*
G01X903925Y566990D02*
Y562548D01*
G01X896204Y561097D02*
X897035Y561928D01*
Y564037D01*
G01X896128Y559700D02*
X896236Y559808D01*
Y559814D01*
X899004Y562582D01*
Y564037D01*
G01X901600Y596700D02*
X901956Y596344D01*
Y591596D01*
G01X893100Y833864D02*
X892392Y835574D01*
Y837418D01*
G01Y840568D02*
X890817Y838993D01*
Y835193D01*
G01X889243Y840568D02*
X887668Y838993D01*
Y834281D01*
G01X905894Y566990D02*
Y561842D01*
G01X910511Y560905D02*
X909831Y562548D01*
Y566990D01*
G01X912291Y575356D02*
X916733D01*
G01X912291Y573387D02*
X916725D01*
G01X916733Y583230D02*
X912291D01*
G01X909840Y591673D02*
Y596589D01*
X909850Y596599D01*
G01Y591663D02*
X909840Y591673D01*
G01X915525Y587163D02*
X917928D01*
G01X1010047Y322072D02*
X1005605D01*
G01X1005100Y327978D02*
X1010047D01*
G01Y326009D02*
X1004899D01*
G01X1010047Y335852D02*
X1005547D01*
G01X1026287Y315170D02*
Y319612D01*
G01X1016444D02*
Y314139D01*
G01X1018413Y319612D02*
Y313879D01*
G01X1024318Y348999D02*
Y344218D01*
G01X1014476D02*
Y349254D01*
G01X1016444Y344218D02*
Y349172D01*
G01X1034730Y322063D02*
X1039455D01*
G01X1034720Y322053D02*
X1034730Y322063D01*
G01X1030220Y313554D02*
Y316378D01*
G01X1040755Y331301D02*
X1039401Y329947D01*
X1034653D01*
G01X1315330Y856642D02*
X1312000D01*
G01X1321629Y831445D02*
Y827000D01*
G01X1315330Y840894D02*
X1312396D01*
G01X1315330Y847193D02*
X1312037D01*
G01X1334228Y831445D02*
Y827772D01*
G01X1381472Y837744D02*
X1384600D01*
G01X1381472Y850343D02*
X1384600D01*
G54D265*
G01X60747Y1555890D02*
Y1555815D01*
X60013Y1555081D01*
Y1553270D01*
G01X169389Y1121948D02*
X171259Y1120078D01*
G01X176870Y1118208D02*
X175000Y1120078D01*
X174999D01*
G01X221942Y1537460D02*
X221745Y1537263D01*
X217610D01*
X217519Y1537172D01*
G01X437666Y620456D02*
Y621586D01*
X436369Y622883D01*
G01X513666Y696458D02*
X515484Y695757D01*
G01X513666Y702364D02*
X515504Y701351D01*
G01X521159Y706388D02*
Y707888D01*
X521540Y708269D01*
G01X523869Y384805D02*
X526242D01*
X527200Y385763D01*
Y387763D01*
G01X553958Y747158D02*
X548421D01*
X547777Y746514D01*
G01X555701Y841388D02*
X556326Y840763D01*
Y834405D01*
G01X560088Y1035088D02*
X557681D01*
G01X563200Y1035102D02*
X565451D01*
G01X699789Y699653D02*
X693733D01*
X693163Y700223D01*
G01X688728Y700359D02*
X693027D01*
X693163Y700223D01*
G01X821764Y845424D02*
X819975Y847213D01*
Y848569D01*
G01X826165Y863000D02*
Y859281D01*
G01X842670Y875507D02*
X842367Y875810D01*
X840585D01*
X840234Y875459D01*
G01X839883Y879459D02*
X837454D01*
X837383Y879530D01*
G01X840193Y871459D02*
X839934Y871200D01*
X837655D01*
X837396Y871459D01*
G01X836423Y962269D02*
Y964669D01*
G01X832423Y962269D02*
X836423D01*
G01X853653Y831469D02*
X850496D01*
G01X878610Y747171D02*
X879177Y746604D01*
X883169D01*
X883725Y747160D01*
X884045D01*
G01X871294Y771809D02*
X872350Y772865D01*
Y775898D01*
G01X903297Y271654D02*
X897311D01*
X896953Y272012D01*
G01X889303Y694119D02*
X884903D01*
G01X944695Y874268D02*
Y878216D01*
G01X950691Y857440D02*
X953091D01*
G01X953217Y861440D02*
X950691D01*
G01X947845Y874268D02*
X950251D01*
G01X1007440Y846198D02*
X1008896D01*
X1011378Y848680D01*
X1015628D01*
G01X1018278Y833659D02*
X1020703D01*
G01X1271121Y892513D02*
X1267122D01*
X1264769Y894866D01*
G01X1321278Y776946D02*
X1324346D01*
X1326430Y779030D01*
X1327584D01*
G01X1404239Y1545478D02*
Y1547755D01*
G01X1403747Y1568156D02*
Y1570433D01*
G01X1426410Y354587D02*
X1429522D01*
X1430986Y356051D01*
G01X1424453Y1491198D02*
X1422176D01*
G01X1474261Y1035088D02*
X1471854D01*
G01X1477373Y1035102D02*
X1479624D01*
G01X1506457Y323766D02*
X1501807D01*
G01X1538133Y352053D02*
X1537996Y351916D01*
X1528505D01*
G01X1520460Y968739D02*
X1521085Y968114D01*
Y961756D01*
G01X1593942Y1437014D02*
X1597225D01*
G01X1807393Y1438622D02*
Y1436345D01*
G01X1807270Y1470812D02*
Y1468535D01*
G54D238*
X965740Y1413859D03*
G54D37*
X15424Y1041679D03*
X28810D03*
X37157D03*
X50543D03*
X437627Y1234726D03*
X451013D03*
X476336D03*
X489722D03*
X862114Y1050682D03*
X875500D03*
X897233D03*
X883847D03*
X926091D03*
X947824D03*
X939477D03*
X961210D03*
X1351801Y1234726D03*
X1365187D03*
X1390510D03*
X1403896D03*
X1770071Y1051168D03*
X1783457D03*
X1791804D03*
X1805190D03*
G54D247*
X1019768Y1411117D03*
G54D175*
X537944Y760782D03*
Y767474D03*
X546606D03*
Y760782D03*
X1511365Y894825D03*
X1502703Y888133D03*
Y894825D03*
X1511365Y888133D03*
G54D166*
X456091Y1033616D03*
X1370265D03*
G54D19*
X8460Y111710D03*
X16728D03*
X8460Y128836D03*
X16728D03*
X202994Y64722D03*
X211262D03*
X202994Y81848D03*
X211262D03*
X305356Y64722D03*
Y81848D03*
X313624Y64722D03*
Y81848D03*
X360982Y1146842D03*
X352714D03*
X360982Y1163968D03*
X352714D03*
X557719Y64722D03*
X565987D03*
X557719Y81848D03*
X565987D03*
X660081Y64722D03*
X668349D03*
X660081Y81848D03*
X668349D03*
X762443Y64722D03*
Y81848D03*
X770711Y64722D03*
Y81848D03*
X809801Y1146842D03*
Y1163968D03*
X830829Y935779D03*
Y952905D03*
X818069Y1146842D03*
Y1163968D03*
X839097Y935779D03*
Y952905D03*
X864805Y64722D03*
Y81848D03*
X873073Y64722D03*
Y81848D03*
X1014805Y64722D03*
X1023073D03*
X1014805Y81848D03*
X1023073D03*
X1117167Y64722D03*
Y81848D03*
X1125435Y64722D03*
Y81848D03*
X1219529Y64722D03*
Y81848D03*
X1227797Y64722D03*
Y81848D03*
X1266887Y1146842D03*
Y1163968D03*
X1275155Y1146842D03*
Y1163968D03*
X1471892Y64722D03*
X1480160D03*
X1471892Y81848D03*
X1480160D03*
X1574254Y64722D03*
Y81848D03*
X1582522Y64722D03*
Y81848D03*
X1594312Y1479190D03*
Y1496316D03*
X1602580Y1479190D03*
Y1496316D03*
X1676616Y64722D03*
Y81848D03*
X1684884Y64722D03*
Y81848D03*
X1723974Y1146842D03*
Y1163968D03*
X1732242Y1146842D03*
Y1163968D03*
X1778978Y64722D03*
X1787246D03*
X1778978Y81848D03*
X1787246D03*
G54D229*
X933810Y944423D03*
Y967455D03*
X962746Y944423D03*
Y967455D03*
G54D256*
X1298720Y807880D03*
Y802762D03*
X1305412Y807880D03*
Y802762D03*
G54D46*
X34292Y601811D03*
Y607311D03*
X40092Y601811D03*
Y607311D03*
X82715Y656990D03*
X88515D03*
X96871Y1027663D03*
X109164Y1005353D03*
X103364D03*
X102671Y1027663D03*
X115533Y1103108D03*
Y1115708D03*
Y1128308D03*
Y1140908D03*
Y1153508D03*
Y1166108D03*
Y1178708D03*
X127179Y1010371D03*
X132979D03*
X127179Y1022971D03*
X132979D03*
X121333Y1103108D03*
X133954Y1110308D03*
X128154D03*
X133954Y1122908D03*
X128154D03*
X121333Y1115708D03*
X133954Y1135508D03*
X128154D03*
X121333Y1128308D03*
Y1140908D03*
X133954Y1148108D03*
X128154D03*
X121333Y1153508D03*
X133954Y1160708D03*
X128154D03*
X133954Y1173308D03*
X128154D03*
X121333Y1166108D03*
X133954Y1185908D03*
X128154D03*
X121333Y1178708D03*
X145600Y1017571D03*
X139800D03*
X145600Y1030171D03*
X139800D03*
X400728Y344439D03*
X406528D03*
Y349939D03*
X400728D03*
X399300Y793800D03*
X405100D03*
X456439Y1247517D03*
X462239D03*
X491378Y601811D03*
Y607311D03*
X497178Y601811D03*
Y607311D03*
X495735Y1037680D03*
X534624Y774889D03*
X540424D03*
X549304Y846389D03*
X555104D03*
X553958Y1027663D03*
X566251Y1005353D03*
X560451D03*
X559758Y1027663D03*
X572620Y1103108D03*
Y1115708D03*
Y1128308D03*
Y1140908D03*
Y1153508D03*
Y1166108D03*
Y1178708D03*
X584266Y1010371D03*
Y1022971D03*
X578420Y1103108D03*
Y1115708D03*
X585241Y1110308D03*
Y1122908D03*
Y1135508D03*
X578420Y1128308D03*
Y1140908D03*
X585241Y1148108D03*
X578420Y1153508D03*
X585241Y1160708D03*
Y1173308D03*
X578420Y1166108D03*
X585241Y1185908D03*
X578420Y1178708D03*
X590066Y1010371D03*
X602687Y1017571D03*
X596887D03*
X590066Y1022971D03*
X602687Y1030171D03*
X596887D03*
X591041Y1110308D03*
Y1122908D03*
Y1135508D03*
Y1148108D03*
Y1160708D03*
Y1173308D03*
Y1185908D03*
X948465Y601811D03*
X954265D03*
Y607311D03*
X948465D03*
X1011044Y1027663D03*
X1023337Y1005353D03*
X1017537D03*
X1016844Y1027663D03*
X1041352Y1010371D03*
Y1022971D03*
X1029706Y1103108D03*
X1035506D03*
X1029706Y1115708D03*
X1035506D03*
X1042327Y1110308D03*
Y1122908D03*
X1029706Y1140908D03*
X1035506D03*
X1029706Y1128308D03*
X1035506D03*
X1042327Y1135508D03*
X1029706Y1153508D03*
X1035506D03*
X1042327Y1148108D03*
X1029706Y1166108D03*
X1035506D03*
X1042327Y1160708D03*
Y1173308D03*
X1029706Y1178708D03*
X1035506D03*
X1042327Y1185908D03*
X1047152Y1010371D03*
Y1022971D03*
X1059773Y1017571D03*
X1053973D03*
X1059773Y1030171D03*
X1053973D03*
X1048127Y1110308D03*
Y1122908D03*
Y1135508D03*
Y1148108D03*
Y1160708D03*
Y1173308D03*
Y1185908D03*
X1303313Y351454D03*
Y356954D03*
X1309113Y351454D03*
Y356954D03*
X1405552Y601811D03*
X1411352D03*
Y607311D03*
X1405552D03*
X1409909Y1037680D03*
X1480424Y1005353D03*
X1474624D03*
X1468131Y1027663D03*
X1473931D03*
X1498439Y1010371D03*
Y1022971D03*
X1486793Y1103108D03*
X1492593D03*
X1486793Y1115708D03*
X1492593D03*
X1486793Y1128308D03*
X1492593D03*
X1486793Y1140908D03*
X1492593D03*
X1486793Y1153508D03*
X1492593D03*
X1486793Y1166108D03*
X1492593D03*
X1486793Y1178708D03*
X1492593D03*
X1499383Y902240D03*
X1505183D03*
X1514063Y973740D03*
X1504239Y1010371D03*
Y1022971D03*
X1511060Y1017571D03*
Y1030171D03*
X1505214Y1122908D03*
X1499414D03*
X1505214Y1110308D03*
X1499414D03*
X1505214Y1135508D03*
X1499414D03*
X1505214Y1148108D03*
X1499414D03*
X1505214Y1173308D03*
X1499414D03*
X1505214Y1160708D03*
X1499414D03*
X1505214Y1185908D03*
X1499414D03*
X1519863Y973740D03*
X1516860Y1017571D03*
Y1030171D03*
X1777250Y929249D03*
X1783050D03*
X1802965Y1075688D03*
X1808765D03*
G54D184*
X714937Y734432D03*
X707063Y738172D03*
X714937Y741912D03*
X893324Y715230D03*
Y722710D03*
X907324Y706030D03*
Y713510D03*
X901198Y718970D03*
X915198Y709770D03*
X1025466Y1373216D03*
Y1380696D03*
X1033340Y1376956D03*
G54D73*
X45558Y1199141D03*
X411135Y883491D03*
X437890Y626268D03*
X889248Y1208144D03*
X953225D03*
X1797205Y1208630D03*
G54D55*
X41988Y83425D03*
Y81063D03*
Y78701D03*
Y76339D03*
Y73977D03*
Y99961D03*
Y97599D03*
Y95236D03*
Y92874D03*
Y90512D03*
Y88150D03*
Y85788D03*
Y116496D03*
Y114134D03*
Y111772D03*
Y109410D03*
Y107047D03*
Y104685D03*
Y102323D03*
Y133032D03*
Y130670D03*
Y128307D03*
Y125945D03*
Y123583D03*
Y121221D03*
Y118859D03*
Y137756D03*
Y135394D03*
X60098Y83425D03*
Y81063D03*
Y78701D03*
Y76339D03*
Y73977D03*
Y99961D03*
Y97599D03*
Y95236D03*
Y92874D03*
Y90512D03*
Y88150D03*
Y85788D03*
Y116496D03*
Y114134D03*
Y111772D03*
Y109410D03*
Y107047D03*
Y104685D03*
Y102323D03*
Y133032D03*
Y130670D03*
Y128307D03*
Y125945D03*
Y123583D03*
Y121221D03*
Y118859D03*
Y137756D03*
Y135394D03*
X144350Y83425D03*
Y81063D03*
Y78701D03*
Y76339D03*
Y73977D03*
Y99961D03*
Y97599D03*
Y95236D03*
Y92874D03*
Y90512D03*
Y88150D03*
Y85788D03*
Y116496D03*
Y114134D03*
Y111772D03*
Y109410D03*
Y107047D03*
Y104685D03*
Y102323D03*
Y133032D03*
Y130670D03*
Y128307D03*
Y125945D03*
Y123583D03*
Y121221D03*
Y118859D03*
Y137756D03*
Y135394D03*
X162460Y83425D03*
Y81063D03*
Y78701D03*
Y76339D03*
Y73977D03*
Y99961D03*
Y97599D03*
Y95236D03*
Y92874D03*
Y90512D03*
Y88150D03*
Y85788D03*
Y116496D03*
Y114134D03*
Y111772D03*
Y109410D03*
Y107047D03*
Y104685D03*
Y102323D03*
Y133032D03*
Y130670D03*
Y128307D03*
Y125945D03*
Y123583D03*
Y121221D03*
Y118859D03*
Y137756D03*
Y135394D03*
X246712Y83425D03*
Y81063D03*
Y78701D03*
Y76339D03*
Y73977D03*
Y99961D03*
Y97599D03*
Y95236D03*
Y92874D03*
Y90512D03*
Y88150D03*
Y85788D03*
Y116496D03*
Y114134D03*
Y111772D03*
Y109410D03*
Y107047D03*
Y104685D03*
Y102323D03*
Y133032D03*
Y130670D03*
Y128307D03*
Y125945D03*
Y123583D03*
Y121221D03*
Y118859D03*
Y137756D03*
Y135394D03*
X264822Y83425D03*
Y81063D03*
Y78701D03*
Y76339D03*
Y73977D03*
Y99961D03*
Y97599D03*
Y95236D03*
Y92874D03*
Y90512D03*
Y88150D03*
Y85788D03*
Y116496D03*
Y114134D03*
Y111772D03*
Y109410D03*
Y107047D03*
Y104685D03*
Y102323D03*
Y133032D03*
Y130670D03*
Y128307D03*
Y125945D03*
Y123583D03*
Y121221D03*
Y118859D03*
Y137756D03*
Y135394D03*
X349074Y83425D03*
Y81063D03*
Y78701D03*
Y76339D03*
Y73977D03*
Y99961D03*
Y97599D03*
Y95236D03*
Y92874D03*
Y90512D03*
Y88150D03*
Y85788D03*
Y116496D03*
Y114134D03*
Y111772D03*
Y109410D03*
Y107047D03*
Y104685D03*
Y102323D03*
Y133032D03*
Y130670D03*
Y128307D03*
Y125945D03*
Y123583D03*
Y121221D03*
Y118859D03*
Y137756D03*
Y135394D03*
X367184Y83425D03*
Y81063D03*
Y78701D03*
Y76339D03*
Y73977D03*
Y99961D03*
Y97599D03*
Y95236D03*
Y92874D03*
Y90512D03*
Y88150D03*
Y85788D03*
Y116496D03*
Y114134D03*
Y111772D03*
Y109410D03*
Y107047D03*
Y104685D03*
Y102323D03*
Y133032D03*
Y130670D03*
Y128307D03*
Y125945D03*
Y123583D03*
Y121221D03*
Y118859D03*
Y137756D03*
Y135394D03*
X499075Y83425D03*
Y81063D03*
Y78701D03*
Y76339D03*
Y73977D03*
Y99961D03*
Y97599D03*
Y95236D03*
Y92874D03*
Y90512D03*
Y88150D03*
Y85788D03*
Y116496D03*
Y114134D03*
Y111772D03*
Y109410D03*
Y107047D03*
Y104685D03*
Y102323D03*
Y133032D03*
Y130670D03*
Y128307D03*
Y125945D03*
Y123583D03*
Y121221D03*
Y118859D03*
Y137756D03*
Y135394D03*
X517185Y83425D03*
Y81063D03*
Y78701D03*
Y76339D03*
Y73977D03*
Y99961D03*
Y97599D03*
Y95236D03*
Y92874D03*
Y90512D03*
Y88150D03*
Y85788D03*
Y116496D03*
Y114134D03*
Y111772D03*
Y109410D03*
Y107047D03*
Y104685D03*
Y102323D03*
Y133032D03*
Y130670D03*
Y128307D03*
Y125945D03*
Y123583D03*
Y121221D03*
Y118859D03*
Y137756D03*
Y135394D03*
X601437Y83425D03*
Y81063D03*
Y78701D03*
Y76339D03*
Y73977D03*
Y99961D03*
Y97599D03*
Y95236D03*
Y92874D03*
Y90512D03*
Y88150D03*
Y85788D03*
Y116496D03*
Y114134D03*
Y111772D03*
Y109410D03*
Y107047D03*
Y104685D03*
Y102323D03*
Y133032D03*
Y130670D03*
Y128307D03*
Y125945D03*
Y123583D03*
Y121221D03*
Y118859D03*
Y137756D03*
Y135394D03*
X619547Y83425D03*
Y81063D03*
Y78701D03*
Y76339D03*
Y73977D03*
Y99961D03*
Y97599D03*
Y95236D03*
Y92874D03*
Y90512D03*
Y88150D03*
Y85788D03*
Y116496D03*
Y114134D03*
Y111772D03*
Y109410D03*
Y107047D03*
Y104685D03*
Y102323D03*
Y133032D03*
Y130670D03*
Y128307D03*
Y125945D03*
Y123583D03*
Y121221D03*
Y118859D03*
Y137756D03*
Y135394D03*
X703799Y83425D03*
Y81063D03*
Y78701D03*
Y76339D03*
Y73977D03*
Y99961D03*
Y97599D03*
Y95236D03*
Y92874D03*
Y90512D03*
Y88150D03*
Y85788D03*
Y116496D03*
Y114134D03*
Y111772D03*
Y109410D03*
Y107047D03*
Y104685D03*
Y102323D03*
Y133032D03*
Y130670D03*
Y128307D03*
Y125945D03*
Y123583D03*
Y121221D03*
Y118859D03*
Y137756D03*
Y135394D03*
X721909Y83425D03*
Y81063D03*
Y78701D03*
Y76339D03*
Y73977D03*
Y99961D03*
Y97599D03*
Y95236D03*
Y92874D03*
Y90512D03*
Y88150D03*
Y85788D03*
Y116496D03*
Y114134D03*
Y111772D03*
Y109410D03*
Y107047D03*
Y104685D03*
Y102323D03*
Y133032D03*
Y130670D03*
Y128307D03*
Y125945D03*
Y123583D03*
Y121221D03*
Y118859D03*
Y137756D03*
Y135394D03*
X806161Y83425D03*
Y81063D03*
Y78701D03*
Y76339D03*
Y73977D03*
Y99961D03*
Y97599D03*
Y95236D03*
Y92874D03*
Y90512D03*
Y88150D03*
Y85788D03*
Y116496D03*
Y114134D03*
Y111772D03*
Y109410D03*
Y107047D03*
Y104685D03*
Y102323D03*
Y133032D03*
Y130670D03*
Y128307D03*
Y125945D03*
Y123583D03*
Y121221D03*
Y118859D03*
Y137756D03*
Y135394D03*
X824271Y83425D03*
Y81063D03*
Y78701D03*
Y76339D03*
Y73977D03*
Y99961D03*
Y97599D03*
Y95236D03*
Y92874D03*
Y90512D03*
Y88150D03*
Y85788D03*
Y116496D03*
Y114134D03*
Y111772D03*
Y109410D03*
Y107047D03*
Y104685D03*
Y102323D03*
Y133032D03*
Y130670D03*
Y128307D03*
Y125945D03*
Y123583D03*
Y121221D03*
Y118859D03*
Y137756D03*
Y135394D03*
X956161Y83425D03*
Y81063D03*
Y78701D03*
Y76339D03*
Y73977D03*
Y99961D03*
Y97599D03*
Y95236D03*
Y92874D03*
Y90512D03*
Y88150D03*
Y85788D03*
Y116496D03*
Y114134D03*
Y111772D03*
Y109410D03*
Y107047D03*
Y104685D03*
Y102323D03*
Y133032D03*
Y130670D03*
Y128307D03*
Y125945D03*
Y123583D03*
Y121221D03*
Y118859D03*
Y137756D03*
Y135394D03*
X974271Y83425D03*
Y81063D03*
Y78701D03*
Y76339D03*
Y73977D03*
Y99961D03*
Y97599D03*
Y95236D03*
Y92874D03*
Y90512D03*
Y88150D03*
Y85788D03*
Y116496D03*
Y114134D03*
Y111772D03*
Y109410D03*
Y107047D03*
Y104685D03*
Y102323D03*
Y133032D03*
Y130670D03*
Y128307D03*
Y125945D03*
Y123583D03*
Y121221D03*
Y118859D03*
Y137756D03*
Y135394D03*
X1058523Y83425D03*
Y81063D03*
Y78701D03*
Y76339D03*
Y73977D03*
Y99961D03*
Y97599D03*
Y95236D03*
Y92874D03*
Y90512D03*
Y88150D03*
Y85788D03*
Y116496D03*
Y114134D03*
Y111772D03*
Y109410D03*
Y107047D03*
Y104685D03*
Y102323D03*
Y133032D03*
Y130670D03*
Y128307D03*
Y125945D03*
Y123583D03*
Y121221D03*
Y118859D03*
Y137756D03*
Y135394D03*
X1076633Y83425D03*
Y81063D03*
Y78701D03*
Y76339D03*
Y73977D03*
Y99961D03*
Y97599D03*
Y95236D03*
Y92874D03*
Y90512D03*
Y88150D03*
Y85788D03*
Y116496D03*
Y114134D03*
Y111772D03*
Y109410D03*
Y107047D03*
Y104685D03*
Y102323D03*
Y133032D03*
Y130670D03*
Y128307D03*
Y125945D03*
Y123583D03*
Y121221D03*
Y118859D03*
Y137756D03*
Y135394D03*
X1160885Y83425D03*
Y81063D03*
Y78701D03*
Y76339D03*
Y73977D03*
Y99961D03*
Y97599D03*
Y95236D03*
Y92874D03*
Y90512D03*
Y88150D03*
Y85788D03*
Y116496D03*
Y114134D03*
Y111772D03*
Y109410D03*
Y107047D03*
Y104685D03*
Y102323D03*
Y133032D03*
Y130670D03*
Y128307D03*
Y125945D03*
Y123583D03*
Y121221D03*
Y118859D03*
Y137756D03*
Y135394D03*
X1178995Y83425D03*
Y81063D03*
Y78701D03*
Y76339D03*
Y73977D03*
Y99961D03*
Y97599D03*
Y95236D03*
Y92874D03*
Y90512D03*
Y88150D03*
Y85788D03*
Y116496D03*
Y114134D03*
Y111772D03*
Y109410D03*
Y107047D03*
Y104685D03*
Y102323D03*
Y133032D03*
Y130670D03*
Y128307D03*
Y125945D03*
Y123583D03*
Y121221D03*
Y118859D03*
Y137756D03*
Y135394D03*
X1263247Y83425D03*
Y81063D03*
Y78701D03*
Y76339D03*
Y73977D03*
Y99961D03*
Y97599D03*
Y95236D03*
Y92874D03*
Y90512D03*
Y88150D03*
Y85788D03*
Y116496D03*
Y114134D03*
Y111772D03*
Y109410D03*
Y107047D03*
Y104685D03*
Y102323D03*
Y133032D03*
Y130670D03*
Y128307D03*
Y125945D03*
Y123583D03*
Y121221D03*
Y118859D03*
Y137756D03*
Y135394D03*
X1281357Y83425D03*
Y81063D03*
Y78701D03*
Y76339D03*
Y73977D03*
Y99961D03*
Y97599D03*
Y95236D03*
Y92874D03*
Y90512D03*
Y88150D03*
Y85788D03*
Y116496D03*
Y114134D03*
Y111772D03*
Y109410D03*
Y107047D03*
Y104685D03*
Y102323D03*
Y133032D03*
Y130670D03*
Y128307D03*
Y125945D03*
Y123583D03*
Y121221D03*
Y118859D03*
Y137756D03*
Y135394D03*
X1413248Y83425D03*
Y81063D03*
Y78701D03*
Y76339D03*
Y73977D03*
Y99961D03*
Y97599D03*
Y95236D03*
Y92874D03*
Y90512D03*
Y88150D03*
Y85788D03*
Y116496D03*
Y114134D03*
Y111772D03*
Y109410D03*
Y107047D03*
Y104685D03*
Y102323D03*
Y133032D03*
Y130670D03*
Y128307D03*
Y125945D03*
Y123583D03*
Y121221D03*
Y118859D03*
Y137756D03*
Y135394D03*
X1431358Y83425D03*
Y81063D03*
Y78701D03*
Y76339D03*
Y73977D03*
Y99961D03*
Y97599D03*
Y95236D03*
Y92874D03*
Y90512D03*
Y88150D03*
Y85788D03*
Y116496D03*
Y114134D03*
Y111772D03*
Y109410D03*
Y107047D03*
Y104685D03*
Y102323D03*
Y133032D03*
Y130670D03*
Y128307D03*
Y125945D03*
Y123583D03*
Y121221D03*
Y118859D03*
Y137756D03*
Y135394D03*
X1515610Y83425D03*
Y81063D03*
Y78701D03*
Y76339D03*
Y73977D03*
Y99961D03*
Y97599D03*
Y95236D03*
Y92874D03*
Y90512D03*
Y88150D03*
Y85788D03*
Y116496D03*
Y114134D03*
Y111772D03*
Y109410D03*
Y107047D03*
Y104685D03*
Y102323D03*
Y133032D03*
Y130670D03*
Y128307D03*
Y125945D03*
Y123583D03*
Y121221D03*
Y118859D03*
Y137756D03*
Y135394D03*
X1533720Y83425D03*
Y81063D03*
Y78701D03*
Y76339D03*
Y73977D03*
Y99961D03*
Y97599D03*
Y95236D03*
Y92874D03*
Y90512D03*
Y88150D03*
Y85788D03*
Y116496D03*
Y114134D03*
Y111772D03*
Y109410D03*
Y107047D03*
Y104685D03*
Y102323D03*
Y133032D03*
Y130670D03*
Y128307D03*
Y125945D03*
Y123583D03*
Y121221D03*
Y118859D03*
Y137756D03*
Y135394D03*
X1617972Y83425D03*
Y81063D03*
Y78701D03*
Y76339D03*
Y73977D03*
Y99961D03*
Y97599D03*
Y95236D03*
Y92874D03*
Y90512D03*
Y88150D03*
Y85788D03*
Y116496D03*
Y114134D03*
Y111772D03*
Y109410D03*
Y107047D03*
Y104685D03*
Y102323D03*
Y133032D03*
Y130670D03*
Y128307D03*
Y125945D03*
Y123583D03*
Y121221D03*
Y118859D03*
Y137756D03*
Y135394D03*
X1636082Y83425D03*
Y81063D03*
Y78701D03*
Y76339D03*
Y73977D03*
Y99961D03*
Y97599D03*
Y95236D03*
Y92874D03*
Y90512D03*
Y88150D03*
Y85788D03*
Y116496D03*
Y114134D03*
Y111772D03*
Y109410D03*
Y107047D03*
Y104685D03*
Y102323D03*
Y133032D03*
Y130670D03*
Y128307D03*
Y125945D03*
Y123583D03*
Y121221D03*
Y118859D03*
Y137756D03*
Y135394D03*
X1720334Y83425D03*
Y81063D03*
Y78701D03*
Y76339D03*
Y73977D03*
Y99961D03*
Y97599D03*
Y95236D03*
Y92874D03*
Y90512D03*
Y88150D03*
Y85788D03*
Y116496D03*
Y114134D03*
Y111772D03*
Y109410D03*
Y107047D03*
Y104685D03*
Y102323D03*
Y133032D03*
Y130670D03*
Y128307D03*
Y125945D03*
Y123583D03*
Y121221D03*
Y118859D03*
Y137756D03*
Y135394D03*
X1738444Y83425D03*
Y81063D03*
Y78701D03*
Y76339D03*
Y73977D03*
Y99961D03*
Y97599D03*
Y95236D03*
Y92874D03*
Y90512D03*
Y88150D03*
Y85788D03*
Y116496D03*
Y114134D03*
Y111772D03*
Y109410D03*
Y107047D03*
Y104685D03*
Y102323D03*
Y133032D03*
Y130670D03*
Y128307D03*
Y125945D03*
Y123583D03*
Y121221D03*
Y118859D03*
Y137756D03*
Y135394D03*
G54D28*
X12422Y214006D03*
Y207006D03*
X27201Y155151D03*
Y162151D03*
X48949Y826718D03*
Y833718D03*
X50602Y971296D03*
Y978296D03*
X70236Y281155D03*
Y274155D03*
X62733Y531055D03*
Y538055D03*
X61555Y971296D03*
Y978296D03*
X57909Y985176D03*
Y992176D03*
X68342Y985014D03*
Y992014D03*
X70658Y215535D03*
Y222535D03*
X72643Y448919D03*
Y455919D03*
X72564Y484311D03*
Y491311D03*
X114784Y214006D03*
Y207006D03*
X123599Y112672D03*
Y119672D03*
X145882Y586056D03*
Y579056D03*
X152882Y586056D03*
Y579056D03*
X173020Y215535D03*
Y222535D03*
X172598Y281155D03*
Y274155D03*
X225961Y112672D03*
Y119672D03*
X217146Y214006D03*
Y207006D03*
X275382Y215535D03*
Y222535D03*
X274960Y281155D03*
Y274155D03*
X328323Y112672D03*
Y119672D03*
X319508Y214006D03*
Y207006D03*
X317549Y419937D03*
Y426937D03*
Y439431D03*
Y446431D03*
X362042Y441402D03*
Y434402D03*
X358933Y488017D03*
Y481017D03*
X377744Y215535D03*
Y222535D03*
X377322Y281155D03*
Y274155D03*
X371919Y441002D03*
Y448002D03*
X379919Y441002D03*
Y448002D03*
X399853Y391802D03*
Y398802D03*
X405121Y930778D03*
X397121D03*
X405121Y937778D03*
X397121D03*
X400004Y1198971D03*
Y1191971D03*
X413121Y930778D03*
X421121D03*
X413121Y937778D03*
X421121D03*
X426934Y1198971D03*
Y1191971D03*
X431764Y507650D03*
Y500650D03*
X453864Y1198971D03*
Y1191971D03*
X469509Y214006D03*
Y207006D03*
X473206Y1198971D03*
Y1191971D03*
X478324Y112672D03*
Y119672D03*
X500136Y1198971D03*
Y1191971D03*
X519819Y531055D03*
Y538055D03*
X527745Y215535D03*
Y222535D03*
X527323Y281155D03*
Y274155D03*
X527729Y445919D03*
Y452919D03*
X529650Y484311D03*
Y491311D03*
X527066Y1198971D03*
Y1191971D03*
X571871Y214006D03*
Y207006D03*
X566003Y940807D03*
Y947807D03*
X580686Y112672D03*
Y119672D03*
X602968Y586056D03*
Y579056D03*
X609968Y586056D03*
Y579056D03*
X630107Y215535D03*
Y222535D03*
X629685Y281155D03*
Y274155D03*
X683048Y112672D03*
Y119672D03*
X674233Y214006D03*
Y207006D03*
X732469Y215535D03*
Y222535D03*
X732047Y281155D03*
Y274155D03*
X776595Y214006D03*
Y207006D03*
X780434Y419937D03*
Y426937D03*
X773434Y419937D03*
Y426937D03*
X785410Y112672D03*
Y119672D03*
X816019Y476017D03*
Y483017D03*
X834831Y215535D03*
Y222535D03*
X834409Y281155D03*
Y274155D03*
X858882Y467675D03*
Y460675D03*
X866135Y985334D03*
Y992334D03*
X859242Y985334D03*
Y992334D03*
X852117Y985334D03*
Y992334D03*
X874882Y467675D03*
Y460675D03*
X866882Y467675D03*
Y460675D03*
X895179Y408143D03*
Y415143D03*
X907953Y998291D03*
Y1005291D03*
X927261Y199177D03*
Y192177D03*
X935410Y112672D03*
Y119672D03*
X955165Y996486D03*
Y1003486D03*
X948285Y996437D03*
Y1003437D03*
X976906Y531055D03*
Y538055D03*
X979129Y997259D03*
Y1004259D03*
X967028Y996535D03*
Y1003535D03*
X984831Y215535D03*
Y222535D03*
X984409Y281155D03*
Y274155D03*
X986816Y448919D03*
Y455919D03*
X986737Y484311D03*
Y491311D03*
X1007619Y937822D03*
Y944822D03*
X1037772Y112672D03*
Y119672D03*
X1028957Y214006D03*
Y207006D03*
X1060055Y586056D03*
Y579056D03*
X1067055Y586056D03*
Y579056D03*
X1087193Y215535D03*
Y222535D03*
X1086771Y281155D03*
Y274155D03*
X1140134Y112672D03*
Y119672D03*
X1131319Y214006D03*
Y207006D03*
X1189555Y215535D03*
Y222535D03*
X1189133Y281155D03*
Y274155D03*
X1233681Y214006D03*
Y207006D03*
X1231722Y419937D03*
Y426937D03*
Y439431D03*
Y446431D03*
X1242496Y112672D03*
Y119672D03*
X1276215Y441402D03*
Y434402D03*
X1286092Y441002D03*
Y448002D03*
X1273106Y488017D03*
Y481017D03*
X1291917Y215535D03*
Y222535D03*
X1291495Y281155D03*
Y274155D03*
X1294092Y441002D03*
Y448002D03*
X1314026Y391802D03*
Y398802D03*
X1314178Y1198971D03*
Y1191971D03*
X1341108Y1198971D03*
Y1191971D03*
X1368038Y1198971D03*
Y1191971D03*
X1383682Y214006D03*
Y207006D03*
X1392497Y112672D03*
Y119672D03*
X1387380Y1198971D03*
Y1191971D03*
X1414310Y1198971D03*
Y1191971D03*
X1433993Y531055D03*
Y538055D03*
X1441918Y215535D03*
Y222535D03*
X1441496Y281155D03*
Y274155D03*
X1441903Y445919D03*
Y452919D03*
X1443824Y484311D03*
Y491311D03*
X1441240Y1198971D03*
Y1191971D03*
X1494859Y112672D03*
Y119672D03*
X1486044Y214006D03*
Y207006D03*
X1517142Y586056D03*
Y579056D03*
X1524142Y586056D03*
Y579056D03*
X1544280Y215535D03*
Y222535D03*
X1543858Y281155D03*
Y274155D03*
X1597221Y112672D03*
Y119672D03*
X1588406Y214006D03*
Y207006D03*
X1646642Y215535D03*
Y222535D03*
X1646220Y281155D03*
Y274155D03*
X1690768Y214006D03*
Y207006D03*
X1688809Y419937D03*
Y426937D03*
Y439431D03*
Y446431D03*
X1699583Y112672D03*
Y119672D03*
X1743179Y441002D03*
X1733302Y441402D03*
Y434402D03*
X1743179Y448002D03*
X1730193Y488017D03*
Y481017D03*
X1749004Y215535D03*
Y222535D03*
X1748582Y281155D03*
Y274155D03*
X1751179Y441002D03*
Y448002D03*
X1771113Y391802D03*
Y398802D03*
X1782263Y968660D03*
Y975660D03*
X1804012Y997858D03*
Y1004858D03*
X1817965Y997858D03*
Y1004858D03*
X1811133Y997858D03*
Y1004858D03*
X1824814Y997895D03*
Y1004895D03*
G54D157*
X419061Y1143544D03*
Y1167756D03*
X446889Y1143544D03*
Y1167756D03*
X484648Y1143544D03*
Y1167756D03*
X512476Y1143544D03*
Y1167756D03*
X1333235Y1143544D03*
Y1167756D03*
X1361063Y1143544D03*
Y1167756D03*
X1398822Y1143544D03*
Y1167756D03*
X1426650Y1143544D03*
Y1167756D03*
G54D64*
X39743Y617343D03*
Y621279D03*
X418161Y432227D03*
Y434195D03*
Y436164D03*
Y438133D03*
Y440101D03*
Y442069D03*
Y444038D03*
Y446007D03*
Y447975D03*
X429185Y438133D03*
Y442069D03*
Y434195D03*
Y440101D03*
Y436164D03*
Y446007D03*
Y444038D03*
Y447975D03*
X496829Y617343D03*
Y621279D03*
X913487Y448568D03*
Y450536D03*
Y452505D03*
Y454474D03*
Y456442D03*
Y458410D03*
Y460379D03*
Y462348D03*
Y464316D03*
X924511Y454474D03*
Y450536D03*
Y456442D03*
Y452505D03*
Y458410D03*
Y462348D03*
Y460379D03*
Y464316D03*
X953916Y617343D03*
Y621279D03*
X1332334Y432227D03*
Y434195D03*
Y436164D03*
Y438133D03*
Y440101D03*
Y442069D03*
Y444038D03*
Y446007D03*
Y447975D03*
X1343358Y438133D03*
Y442069D03*
Y434195D03*
Y440101D03*
Y436164D03*
Y446007D03*
Y444038D03*
Y447975D03*
X1411003Y617343D03*
Y621279D03*
X1789421Y432227D03*
Y434195D03*
Y436164D03*
Y438133D03*
Y440101D03*
Y442069D03*
Y444038D03*
Y446007D03*
Y447975D03*
X1800445Y438133D03*
Y442069D03*
Y434195D03*
Y440101D03*
Y436164D03*
Y446007D03*
Y444038D03*
Y447975D03*
G54D91*
X83565Y273540D03*
X185927D03*
X288289D03*
X390651D03*
X540652D03*
X643014D03*
X745376D03*
X847738D03*
X997738D03*
X1100100D03*
X1202462D03*
X1304824D03*
X1454825D03*
X1557187D03*
X1659549D03*
X1761911D03*
G54D82*
X62549Y833614D03*
X579603Y947703D03*
X1001337Y842261D03*
X1021219Y944718D03*
X1795863Y975556D03*
G54D148*
X419839Y350114D03*
X421413D03*
X422988D03*
X424563D03*
X430862D03*
X437161D03*
X426138D03*
X429287D03*
X435587D03*
X427713D03*
X432437D03*
X434012D03*
X1322424Y353206D03*
X1323998D03*
X1333447D03*
X1328723D03*
X1331872D03*
X1325573D03*
X1327148D03*
X1330298D03*
X1335022D03*
X1339746D03*
X1338172D03*
X1336597D03*
G54D193*
X797907Y1443778D03*
Y1461396D03*
X815624Y1443778D03*
X813852D03*
X812080D03*
X810309D03*
X808537D03*
X806765D03*
X801450D03*
X803222D03*
X804994D03*
X799679D03*
X804994Y1461396D03*
X806765D03*
X808537D03*
X810309D03*
X812080D03*
X813852D03*
X815624D03*
X799679D03*
X801450D03*
X803222D03*
X819167Y1443778D03*
X817395D03*
Y1461396D03*
X819167D03*
G54D139*
X417211Y1133067D03*
X449339D03*
X482798D03*
X514926D03*
X1331385D03*
X1363513D03*
X1396972D03*
X1429100D03*
G54D275*
G01X32051Y225055D02*
Y225329D01*
X35722Y229000D01*
X36185Y230117D01*
G01D02*
X36201Y230133D01*
Y232984D01*
G01X59966Y497617D02*
Y498153D01*
X59740Y498379D01*
Y500016D01*
X59670Y500086D01*
G01X54339Y1491047D02*
X57144D01*
G01X138547Y230117D02*
X138563Y230133D01*
Y232984D01*
G01X134413Y225055D02*
Y225329D01*
X138084Y229000D01*
X138547Y230117D01*
G01X240909D02*
X240925Y230133D01*
Y232984D01*
G01X236775Y225055D02*
Y225329D01*
X240446Y229000D01*
X240909Y230117D01*
G01X343271D02*
X343287Y230133D01*
Y232984D01*
G01X339137Y225055D02*
Y225329D01*
X342808Y229000D01*
X343271Y230117D01*
G01X416187Y1110233D02*
Y1108027D01*
X416495Y1107283D01*
Y1105897D01*
X416988Y1104792D01*
G01X440114Y344012D02*
X443478D01*
X443480Y344014D01*
G01X448315Y1110233D02*
Y1108027D01*
X448623Y1107283D01*
Y1105897D01*
X449116Y1104792D01*
G01X459360Y1012325D02*
X460401Y1013366D01*
X466046D01*
G01X459860Y1015825D02*
X460860Y1014825D01*
X463786D01*
X463902Y1014941D01*
X466046D01*
G01X471755Y1038665D02*
X467652Y1034562D01*
Y1028367D01*
X468408Y1027611D01*
Y1026752D01*
G01X470610Y1033783D02*
X469269Y1032442D01*
Y1028764D01*
X469983Y1028050D01*
Y1026752D01*
G01X489138Y225055D02*
Y225329D01*
X492809Y229000D01*
X493272Y230117D01*
G01X485360Y1031680D02*
Y1030255D01*
X482582Y1027477D01*
Y1026752D01*
G01X482210Y1031680D02*
Y1030105D01*
X481007Y1028902D01*
Y1026752D01*
G01X481774Y1110233D02*
Y1108027D01*
X482082Y1107283D01*
Y1105897D01*
X482575Y1104792D01*
G01X493272Y230117D02*
X493288Y230133D01*
Y232984D01*
G01X517052Y497617D02*
Y499790D01*
X516756Y500086D01*
G01X513666Y690553D02*
X515573Y692515D01*
G01X515649Y706388D02*
X515578Y706459D01*
X515404Y706531D01*
X513666Y708269D01*
G01X513902Y1110233D02*
Y1108027D01*
X514210Y1107283D01*
Y1105897D01*
X514703Y1104792D01*
G01X531382Y690553D02*
X529493Y692443D01*
G01X529469Y706230D02*
Y706356D01*
X531382Y708269D01*
G01X595634Y230117D02*
X595650Y230133D01*
Y232984D01*
G01X591500Y225055D02*
Y225329D01*
X595171Y229000D01*
X595634Y230117D01*
G01X697996D02*
X698012Y230133D01*
Y232984D01*
G01X693862Y225055D02*
Y225329D01*
X697533Y229000D01*
X697996Y230117D01*
G01X796224Y225055D02*
Y225329D01*
X799895Y229000D01*
X800358Y230117D01*
G01X795791Y1451701D02*
X794071D01*
G01X795791Y1453473D02*
X793882D01*
G01X800358Y230117D02*
X800374Y230133D01*
Y232984D01*
G01X957229Y911082D02*
X957039Y910892D01*
Y895061D01*
X958074Y894026D01*
Y859426D01*
X962100Y855400D01*
Y839450D01*
X961175Y838525D01*
G01X890145Y566990D02*
X887694D01*
X887417Y566713D01*
G01X904704Y312621D02*
X901965D01*
X901848Y312738D01*
G01X912783Y564037D02*
Y562557D01*
X913853Y561487D01*
G01X909850Y596599D02*
Y597787D01*
X910789Y598726D01*
G01X923888Y840568D02*
X925463Y838993D01*
G01Y836336D02*
X928777Y833022D01*
Y829859D01*
X929790Y828846D01*
Y828603D01*
G01X920739Y846867D02*
X922313Y845293D01*
G01X927038Y843717D02*
X930018D01*
X932401Y846100D01*
X934500D01*
X936018Y844582D01*
X938858D01*
G01X940100Y830700D02*
X937100Y833700D01*
X933906D01*
X927038Y840568D01*
G01X923888Y843717D02*
X925467Y842138D01*
G01X927995D02*
X931297Y838836D01*
X936847D01*
X938820Y836863D01*
G01X945100Y852400D02*
X939829Y847129D01*
X936427D01*
X936056Y847500D01*
X931400D01*
X930767Y846867D01*
X927038D01*
G01X923888D02*
X925462Y845293D01*
G01X923888Y859465D02*
X925462Y857891D01*
G01X927038Y859465D02*
X931348Y863775D01*
X932080Y865542D01*
X938729Y872191D01*
Y874396D01*
G01X930841Y369160D02*
X934047D01*
G01X939916Y814615D02*
X935916D01*
G01X943916D02*
X939916D01*
G01X929790Y828603D02*
X930163Y828230D01*
Y822788D01*
X935916Y817035D01*
Y814615D01*
G01X937635Y826632D02*
X941535D01*
G01X950335Y826432D02*
X949367Y827400D01*
X946900D01*
X946132Y826632D01*
X941535D01*
G01X940100Y830700D02*
X937635Y828235D01*
Y826632D01*
G01X945035Y830182D02*
X943218D01*
X942000Y831400D01*
Y833683D01*
X938820Y836863D01*
G01X945035Y830182D02*
X948935D01*
G01X943735Y844582D02*
X948665D01*
X950718Y846635D01*
G01X938858Y844582D02*
X943735D01*
G01X937200Y841000D02*
X938784D01*
X940084Y842300D01*
X946575D01*
X947200Y841675D01*
G01X950100Y850425D02*
X948675D01*
X946700Y852400D01*
X945100D01*
G01X940516Y895030D02*
X936617D01*
X936616Y895029D01*
G01D02*
X932716D01*
G01D02*
X929181D01*
G01X942194Y891216D02*
X939403D01*
G01X939447Y887508D02*
X939445Y887506D01*
Y883790D01*
G01X939403Y891216D02*
X939447Y891172D01*
Y887508D01*
G01X946890Y210226D02*
X948152D01*
X950177Y212251D01*
Y215730D01*
G01X951040Y218155D02*
Y216582D01*
X950188Y215730D01*
X950177D01*
G01X948935Y830182D02*
X949027Y830274D01*
X950819D01*
X950844Y830299D01*
X952692D01*
X952783Y830208D01*
G01X950718Y846635D02*
X954452D01*
X954482Y846665D01*
G01X958200Y841675D02*
Y843699D01*
X957199Y844700D01*
X952001D01*
X951100Y843799D01*
Y841675D01*
G01X947200D02*
X951100D01*
G01X950100Y850425D02*
X954000D01*
G01D02*
X957900D01*
G01X1007094Y319120D02*
X1005614D01*
X1004544Y318050D01*
G01X1010047Y341758D02*
Y344209D01*
X1009770Y344486D01*
G01X1039455Y322063D02*
X1041746Y321114D01*
X1041783D01*
G01X1052736Y232984D02*
Y230133D01*
X1052720Y230117D01*
G01X1048586Y225055D02*
Y225329D01*
X1052257Y229000D01*
X1052720Y230117D01*
G01X1150948Y225055D02*
Y225329D01*
X1154619Y229000D01*
X1155082Y230117D01*
G01X1253310Y225055D02*
Y225329D01*
X1256981Y229000D01*
X1257444Y230117D01*
G01D02*
X1257460Y230133D01*
Y232984D01*
G01X1330361Y1110233D02*
Y1108027D01*
X1330669Y1107283D01*
Y1105897D01*
X1331162Y1104792D01*
G01X1342699Y347104D02*
X1346063D01*
X1346065Y347106D01*
G01X1362489Y1110233D02*
Y1108027D01*
X1362797Y1107283D01*
Y1105897D01*
X1363290Y1104792D01*
G01X1373534Y1012325D02*
X1374575Y1013366D01*
X1380220D01*
G01X1374034Y1015825D02*
X1375034Y1014825D01*
X1377960D01*
X1378076Y1014941D01*
X1380220D01*
G01X1384784Y1033783D02*
X1383443Y1032442D01*
Y1028764D01*
X1384157Y1028050D01*
Y1026752D01*
G01X1385929Y1038665D02*
X1381826Y1034562D01*
Y1028367D01*
X1382582Y1027611D01*
Y1026752D01*
G01X1396756D02*
Y1027477D01*
X1399534Y1030255D01*
Y1031680D01*
G01X1395181Y1026752D02*
Y1028902D01*
X1396384Y1030105D01*
Y1031680D01*
G01X1395948Y1110233D02*
Y1108027D01*
X1396256Y1107283D01*
Y1105897D01*
X1396749Y1104792D01*
G01X1407445Y230117D02*
X1407461Y230133D01*
Y232984D01*
G01X1403311Y225055D02*
Y225329D01*
X1406982Y229000D01*
X1407445Y230117D01*
G01X1431226Y497617D02*
Y499790D01*
X1430930Y500086D01*
G01X1428076Y1110233D02*
Y1108027D01*
X1428384Y1107283D01*
Y1105897D01*
X1428877Y1104792D01*
G01X1509807Y230117D02*
X1509823Y230133D01*
Y232984D01*
G01X1505673Y225055D02*
Y225329D01*
X1509344Y229000D01*
X1509807Y230117D01*
G01X1608035Y225055D02*
Y225329D01*
X1611706Y229000D01*
X1612169Y230117D01*
G01D02*
X1612185Y230133D01*
Y232984D01*
G01X1714547D02*
Y230133D01*
X1714531Y230117D01*
G01X1710397Y225055D02*
Y225329D01*
X1714068Y229000D01*
X1714531Y230117D01*
G01X1778047Y912920D02*
Y916120D01*
G54D266*
G01X46240Y109410D02*
X41988D01*
G01X45988Y102323D02*
X41988D01*
G01X46240Y116496D02*
X41988D01*
G01D02*
X37988D01*
G01X41988Y109410D02*
X37988D01*
G01X41988Y102323D02*
X37988D01*
G01X46931Y130670D02*
X41988D01*
G01X37988Y123583D02*
X41988D01*
G01Y130670D02*
X37988D01*
G01X41988Y123583D02*
X47311D01*
X49236Y121658D01*
G01X46932Y137756D02*
X41988D01*
G01D02*
X37988D01*
G01X64098Y109410D02*
X60098D01*
G01X64098Y116496D02*
X60098D01*
G01X64098Y102323D02*
X60098D01*
G01Y116496D02*
X56098D01*
G01X60098Y109410D02*
X56098D01*
G01X60098Y102323D02*
X56678D01*
X55964Y103037D01*
G01X56098Y123583D02*
X60098D01*
G01X56098Y130670D02*
X60098D01*
G01D02*
X64098D01*
G01X60098Y123583D02*
X64098D01*
G01X52437Y137756D02*
X60098D01*
G01D02*
X64098D01*
G01X148602Y109410D02*
X144350D01*
G01X148602Y116496D02*
X144350D01*
G01X148350Y102323D02*
X144350D01*
G01Y116496D02*
X140350D01*
G01X144350Y109410D02*
X140350D01*
G01X144350Y102323D02*
X140350D01*
G01X149827Y130670D02*
X144350D01*
G01X140350Y123583D02*
X144350D01*
G01Y130670D02*
X140350D01*
G01X144350Y123583D02*
X147781D01*
X148774Y124576D01*
G01X149822Y137756D02*
X144350D01*
G01D02*
X140350D01*
G01X158460Y116496D02*
X162460D01*
G01X158326Y103037D02*
X159040Y102323D01*
X162460D01*
G01X158460Y109410D02*
X162460D01*
G01Y116496D02*
X166460D01*
G01X162460Y109410D02*
X166460D01*
G01X162460Y102323D02*
X166460D01*
G01X158460Y130670D02*
X162460D01*
G01X158460Y123583D02*
X162460D01*
G01Y130670D02*
X166460D01*
G01X162460Y123583D02*
X166460D01*
G01X155051Y137756D02*
X162460D01*
G01D02*
X166460D01*
G01X185169Y389154D02*
X181269D01*
G01X177369D02*
X181269D01*
G01X185169Y396240D02*
X181269D01*
G01X186448Y404911D02*
X184864Y403327D01*
X181269D01*
G01X177369Y396240D02*
X181269D01*
G01X177369Y403327D02*
X181269D01*
G01X185402Y412571D02*
Y411043D01*
X184772Y410413D01*
X181269D01*
G01X186589Y426299D02*
X184877Y424587D01*
X181269D01*
G01X177369Y410413D02*
X181269D01*
G01X177369Y424587D02*
X181269D01*
G01X177369Y417500D02*
X181269D01*
G01X177369Y431673D02*
X181269D01*
G01X177369Y438760D02*
X181269D01*
G01X186900Y445847D02*
X181269D01*
G01X177369D02*
X181269D01*
G01X185169Y467539D02*
X181269D01*
G01X177369D02*
X181269D01*
G01X177369Y488799D02*
X181269D01*
G01X185430Y480828D02*
X184545Y481713D01*
X181269D01*
G01X185169Y474626D02*
X181269D01*
G01X177369D02*
X181269D01*
G01X177369Y481713D02*
X181269D01*
G01X177369Y495886D02*
X181269D01*
G01X187380Y498834D02*
X184432Y495886D01*
X181269D01*
G01X177369Y518760D02*
X181269D01*
G01X185169D02*
X181269D01*
G01X177369Y511673D02*
X181269D01*
G01X185169D02*
X181269D01*
G01X177369Y525847D02*
X181269D01*
G01X185169D02*
X181269D01*
G01X177369Y532933D02*
X181269D01*
G01Y540020D02*
X177369D01*
G01Y547106D02*
X181269D01*
G01Y602205D02*
X176758D01*
Y602197D01*
X176650D01*
G01X181269Y595118D02*
X177247D01*
Y595108D01*
X177114D01*
G01X191988Y389154D02*
X199380D01*
G01X190518Y396240D02*
X199380D01*
G01X195295Y414823D02*
Y416038D01*
X196757Y417500D01*
X199380D01*
G01X194603Y422864D02*
X196326Y424587D01*
X199380D01*
G01X194673Y429832D02*
X196514Y431673D01*
X199380D01*
G01X194278Y436447D02*
X196591Y438760D01*
X199380D01*
G01X196313Y447953D02*
Y446794D01*
X197260Y445847D01*
X199380D01*
G01X195480Y467539D02*
X199380D01*
G01X194222Y472772D02*
X196076Y474626D01*
X199380D01*
G01X194956Y487711D02*
X196044Y488799D01*
X199380D01*
G01X195069Y479104D02*
Y480489D01*
X196293Y481713D01*
X199380D01*
G01X195480Y495886D02*
X199380D01*
G01X194080Y510565D02*
X195188Y511673D01*
X199380D01*
G01X190829Y516841D02*
X192748Y518760D01*
X199380D01*
G01X203280Y389154D02*
X199380D01*
G01X203280Y396240D02*
X199380D01*
G01X203280Y403327D02*
X199380D01*
G01X203280Y417500D02*
X199380D01*
G01X203280Y410413D02*
X199380D01*
G01X203280Y431673D02*
X199380D01*
G01X203280Y438760D02*
X199380D01*
G01X203280Y445847D02*
X199380D01*
G01X203280Y467539D02*
X199380D01*
G01X203280Y488799D02*
X199380D01*
G01X203280Y474626D02*
X199380D01*
G01X203280Y481713D02*
X199380D01*
G01X203280Y495886D02*
X199380D01*
G01X203280Y511673D02*
X199380D01*
G01X203280Y518760D02*
X199380D01*
G01X203280Y525847D02*
X199380D01*
G01X203280Y532933D02*
X199380D01*
G01X203280Y540020D02*
X199380D01*
G01X203280Y547106D02*
X199380D01*
G01X203280Y554193D02*
X199380D01*
G01X203280Y602205D02*
X199380D01*
G01X203280Y595118D02*
X199380D01*
G01X250964Y109410D02*
X246712D01*
G01X250712Y102323D02*
X246712D01*
G01X250964Y116496D02*
X246712D01*
G01D02*
X242712D01*
G01X246712Y109410D02*
X242712D01*
G01X246712Y102323D02*
X242712D01*
G01X252189Y130670D02*
X246712D01*
G01X242712Y123583D02*
X246712D01*
G01Y130670D02*
X242712D01*
G01X246712Y123583D02*
X250143D01*
X251136Y124576D01*
G01X252184Y137756D02*
X246712D01*
G01D02*
X242712D01*
G01X264822Y116496D02*
X260822D01*
G01X264822Y109410D02*
X260822D01*
G01X264822Y102323D02*
X261402D01*
X260688Y103037D01*
G01X264822Y130670D02*
X260822D01*
G01X264822Y123583D02*
X260822D01*
G01X264822Y137756D02*
X257413D01*
G01X268822Y116496D02*
X264822D01*
G01X268822Y109410D02*
X264822D01*
G01X268822Y102323D02*
X264822D01*
G01X268822Y130670D02*
X264822D01*
G01X268822Y123583D02*
X264822D01*
G01X268822Y137756D02*
X264822D01*
G01X265011Y403307D02*
X270305D01*
G01X265011Y410394D02*
X270305D01*
G01X266405Y451319D02*
X270305D01*
G01X266405Y465492D02*
X270305D01*
G01X266405Y458406D02*
X270305D01*
G01X274205Y466027D02*
X274136D01*
X273601Y465492D01*
X270305D01*
G01X266405Y472579D02*
X270305D01*
G01X274347Y475262D02*
Y474018D01*
X272908Y472579D01*
X270305D01*
G01X274347Y489435D02*
Y488191D01*
X272908Y486752D01*
X270305D01*
G01X274347Y482666D02*
Y481104D01*
X272908Y479665D01*
X270305D01*
G01X266405D02*
X270305D01*
G01X266405Y486752D02*
X270305D01*
G01X266405Y493839D02*
X270305D01*
G01X274163Y495088D02*
X272914Y493839D01*
X270305D01*
G01X274820Y522134D02*
X273155Y523799D01*
X270305D01*
G01X266405Y516713D02*
X270305D01*
G01X274898Y514608D02*
X272793Y516713D01*
X270305D01*
G01X266405Y509626D02*
X270305D01*
G01X274205D02*
X270305D01*
G01X266405Y523799D02*
X270305D01*
G01X266405Y530886D02*
X270305D01*
G01X275463Y529136D02*
X273713Y530886D01*
X270305D01*
G01X266405Y537973D02*
X270305D01*
G01X275302Y535677D02*
X273006Y537973D01*
X270305D01*
G01X266405Y566752D02*
X270305D01*
G01X274586Y565574D02*
X273408Y566752D01*
X270305D01*
G01X266405Y559665D02*
X270305D01*
G01X274205D02*
X270305D01*
G01X266405Y588012D02*
X270305D01*
G01X266405Y573839D02*
X270305D01*
G01X274233Y574338D02*
X273734Y573839D01*
X270305D01*
G01X266405Y602185D02*
X270305D01*
G01X266405Y595099D02*
X270305D01*
G01X266405Y609272D02*
X270305D01*
G01X266405Y616358D02*
X270305D01*
G01X274332D02*
X270305D01*
G01X292500Y403307D02*
X288416D01*
G01X292500Y410394D02*
X288416D01*
G01X284482Y460250D02*
Y459430D01*
X285506Y458406D01*
X288416D01*
G01X284516Y472579D02*
X288416D01*
G01X292316D02*
X288416D01*
G01X284516Y465492D02*
X288416D01*
G01X292316D02*
X288416D01*
G01X284516Y479665D02*
X288416D01*
G01X292316D02*
X288416D01*
G01X284516Y486752D02*
X288416D01*
G01X292316D02*
X288416D01*
G01X292316Y493839D02*
X288416D01*
G01X284516D02*
X288416D01*
G01X292316Y516713D02*
X288416D01*
G01X284516D02*
X288416D01*
G01X292316Y509626D02*
X288416D01*
G01X284516D02*
X288416D01*
G01X292316Y523799D02*
X288416D01*
G01X283456Y525483D02*
X285140Y523799D01*
X288416D01*
G01X292316Y537973D02*
X288416D01*
G01X280976D02*
X288416D01*
G01X292316Y530886D02*
X288416D01*
G01X283377Y532756D02*
X285247Y530886D01*
X288416D01*
G01X292316Y559665D02*
X288416D01*
G01D02*
X284516D01*
G01Y566752D02*
X288416D01*
G01X292316D02*
X288416D01*
G01X284366Y579978D02*
X285313Y580925D01*
X288416D01*
G01X292316D02*
X288416D01*
G01X284516Y573839D02*
X288416D01*
G01X292316D02*
X288416D01*
G01X292316Y588012D02*
X288416D01*
G01X292316Y595099D02*
X288416D01*
G01X292316Y602185D02*
X288416D01*
G01X284580Y608117D02*
X285735Y609272D01*
X288416D01*
G01X292316D02*
X288416D01*
G01X292316Y616358D02*
X288416D01*
G01X338707Y1167808D02*
Y1173292D01*
X337629Y1174370D01*
Y1175750D01*
G01X353074Y102323D02*
X349074D01*
G01X353326Y109410D02*
X349074D01*
G01X353326Y116496D02*
X349074D01*
G01D02*
X345074D01*
G01X349074Y109410D02*
X345074D01*
G01X349074Y102323D02*
X345074D01*
G01X354551Y130670D02*
X349074D01*
G01X345074Y123583D02*
X349074D01*
G01Y130670D02*
X345074D01*
G01X349074Y123583D02*
X352505D01*
X353498Y124576D01*
G01X354546Y137756D02*
X349074D01*
G01X367184D02*
X359525D01*
G01X349074D02*
X345074D01*
G01X363050Y103037D02*
X363764Y102323D01*
X367184D01*
G01X363184Y116496D02*
X367184D01*
G01X363184Y109410D02*
X367184D01*
G01Y116496D02*
X371184D01*
G01X367184Y109410D02*
X371184D01*
G01X367184Y102323D02*
X371184D01*
G01X363184Y130670D02*
X367184D01*
G01X363184Y123583D02*
X367184D01*
G01Y130670D02*
X371184D01*
G01X367184Y123583D02*
X371184D01*
G01Y137756D02*
X367184D01*
G01X503075Y102323D02*
X499075D01*
G01X503327Y109410D02*
X499075D01*
G01X503327Y116496D02*
X499075D01*
G01D02*
X495075D01*
G01X499075Y109410D02*
X495075D01*
G01X499075Y102323D02*
X495075D01*
G01X504552Y130670D02*
X499075D01*
G01X495075Y123583D02*
X499075D01*
G01Y130670D02*
X495075D01*
G01X499075Y123583D02*
X504722D01*
X506653Y121652D01*
G01X504547Y137756D02*
X499075D01*
G01D02*
X495075D01*
G01X491324Y671200D02*
Y667293D01*
G01Y663326D02*
Y657821D01*
X491373Y657772D01*
G01X513051Y103037D02*
X513765Y102323D01*
X517185D01*
G01X513185Y116496D02*
X517185D01*
G01X513185Y109410D02*
X517185D01*
G01Y116496D02*
X521185D01*
G01X517185Y109410D02*
X521185D01*
G01X517185Y102323D02*
X521185D01*
G01X513185Y130670D02*
X517185D01*
G01X513185Y123583D02*
X517185D01*
G01Y130670D02*
X521185D01*
G01X517185Y123583D02*
X521185D01*
G01Y137756D02*
X517185D01*
G01D02*
X509251D01*
G01X517194Y769259D02*
Y762200D01*
X517412Y761982D01*
G01X517194Y777133D02*
Y773232D01*
G01X553958Y747158D02*
X557157D01*
X557813Y747814D01*
G01X561832Y747158D02*
X567349D01*
X567428Y747079D01*
G01X605437Y102323D02*
X601437D01*
G01X605689Y109410D02*
X601437D01*
G01X605689Y116496D02*
X601437D01*
G01D02*
X597437D01*
G01X601437Y109410D02*
X597437D01*
G01X601437Y102323D02*
X597437D01*
G01X606914Y130670D02*
X601437D01*
G01X597437Y123583D02*
X601437D01*
G01Y130670D02*
X597437D01*
G01X601437Y123583D02*
X604868D01*
X605861Y124576D01*
G01X606909Y137756D02*
X601437D01*
G01D02*
X597437D01*
G01X615547Y109410D02*
X619547D01*
G01X615547Y116496D02*
X619547D01*
G01X615413Y103037D02*
X616127Y102323D01*
X619547D01*
G01Y116496D02*
X623547D01*
G01X619547Y109410D02*
X623547D01*
G01X619547Y102323D02*
X623547D01*
G01X615547Y123583D02*
X619547D01*
G01X615547Y130670D02*
X619547D01*
G01D02*
X623547D01*
G01X619547Y123583D02*
X623547D01*
G01X612138Y137756D02*
X619547D01*
G01D02*
X623547D01*
G01X634455Y389154D02*
X638355D01*
G01X634455Y396240D02*
X638355D01*
G01X634455Y403327D02*
X638355D01*
G01X634455Y410413D02*
X638355D01*
G01X634455Y424587D02*
X638355D01*
G01X634455Y417500D02*
X638355D01*
G01X634455Y431673D02*
X638355D01*
G01X634455Y438760D02*
X638355D01*
G01X634455Y445847D02*
X638355D01*
G01X634455Y467539D02*
X638355D01*
G01X634455Y488799D02*
X638355D01*
G01X634455Y474626D02*
X638355D01*
G01X634455Y481713D02*
X638355D01*
G01X634455Y495886D02*
X638355D01*
G01X634455Y518760D02*
X638355D01*
G01X634455Y511673D02*
X638355D01*
G01X634455Y525847D02*
X638355D01*
G01X634455Y532933D02*
X638355D01*
G01Y540020D02*
X634455D01*
G01Y547106D02*
X638355D01*
G01X633736Y602197D02*
X633836D01*
X633844Y602205D01*
X638355D01*
G01X634200Y595108D02*
X634323D01*
X634333Y595118D01*
X638355D01*
G01X642255Y389154D02*
X638355D01*
G01X649074D02*
X656466D01*
G01X642255Y396240D02*
X638355D01*
G01X643534Y404911D02*
X641950Y403327D01*
X638355D01*
G01X647604Y396240D02*
X656466D01*
G01X642488Y412571D02*
Y411043D01*
X641858Y410413D01*
X638355D01*
G01X652381Y414823D02*
Y416038D01*
X653843Y417500D01*
X656466D01*
G01X651689Y422864D02*
X653412Y424587D01*
X656466D01*
G01X643675Y426299D02*
X641963Y424587D01*
X638355D01*
G01X651759Y429832D02*
X653600Y431673D01*
X656466D01*
G01X651364Y436447D02*
X653677Y438760D01*
X656466D01*
G01X653399Y447953D02*
Y446794D01*
X654346Y445847D01*
X656466D01*
G01X643986D02*
X638355D01*
G01X642255Y467539D02*
X638355D01*
G01X652566D02*
X656466D01*
G01X651308Y472772D02*
X653162Y474626D01*
X656466D01*
G01X652042Y487711D02*
X653130Y488799D01*
X656466D01*
G01X642255Y474626D02*
X638355D01*
G01X652155Y479104D02*
Y480489D01*
X653379Y481713D01*
X656466D01*
G01X642516Y480828D02*
X641631Y481713D01*
X638355D01*
G01X652566Y495886D02*
X656466D01*
G01X644466Y498834D02*
X641518Y495886D01*
X638355D01*
G01X651166Y510565D02*
X652274Y511673D01*
X656466D01*
G01X647915Y516841D02*
X649834Y518760D01*
X656466D01*
G01X642255D02*
X638355D01*
G01X642255Y511673D02*
X638355D01*
G01X642255Y525847D02*
X638355D01*
G01X660366Y389154D02*
X656466D01*
G01X660366Y396240D02*
X656466D01*
G01X660366Y403327D02*
X656466D01*
G01X660366Y417500D02*
X656466D01*
G01X660366Y410413D02*
X656466D01*
G01X660366Y431673D02*
X656466D01*
G01X660366Y438760D02*
X656466D01*
G01X660366Y445847D02*
X656466D01*
G01X660366Y467539D02*
X656466D01*
G01X660366Y488799D02*
X656466D01*
G01X660366Y474626D02*
X656466D01*
G01X660366Y481713D02*
X656466D01*
G01X660366Y495886D02*
X656466D01*
G01X660366Y511673D02*
X656466D01*
G01X660366Y518760D02*
X656466D01*
G01X660366Y525847D02*
X656466D01*
G01X660366Y532933D02*
X656466D01*
G01X660366Y540020D02*
X656466D01*
G01X660366Y554193D02*
X656466D01*
G01X660366Y547106D02*
X656466D01*
G01X660366Y602205D02*
X656466D01*
G01X660366Y595118D02*
X656466D01*
G01X703799Y116496D02*
X699799D01*
G01X703799Y109410D02*
X699799D01*
G01X703799Y102323D02*
X699799D01*
G01Y123583D02*
X703799D01*
G01Y130670D02*
X699799D01*
G01X703799Y137756D02*
X699799D01*
G01X699789Y699653D02*
X703604D01*
G01X707799Y102323D02*
X703799D01*
G01X708051Y109410D02*
X703799D01*
G01X708051Y116496D02*
X703799D01*
G01X721909D02*
X717909D01*
G01X721909Y109410D02*
X717909D01*
G01X721909Y102323D02*
X718489D01*
X717775Y103037D01*
G01X709276Y130670D02*
X703799D01*
G01X721909D02*
X717909D01*
G01X721909Y123583D02*
X717909D01*
G01X703799D02*
X707230D01*
X708223Y124576D01*
G01X709271Y137756D02*
X703799D01*
G01X721909D02*
X714500D01*
G01X707663Y699653D02*
X709769D01*
X712704Y696718D01*
X713200D01*
G01X709194Y774936D02*
X714267D01*
X715994Y776663D01*
G01X709194Y777495D02*
X712232D01*
X713034Y778297D01*
Y779799D01*
X712692Y780141D01*
G01X725909Y102323D02*
X721909D01*
G01X725909Y116496D02*
X721909D01*
G01X725909Y109410D02*
X721909D01*
G01X725909Y130670D02*
X721909D01*
G01X725909Y123583D02*
X721909D01*
G01X725909Y137756D02*
X721909D01*
G01X722097Y403307D02*
X727391D01*
G01X722097Y410394D02*
X727391D01*
G01X723491Y451319D02*
X727391D01*
G01X731291Y466027D02*
X731222D01*
X730687Y465492D01*
X727391D01*
G01X723491D02*
X727391D01*
G01X723491Y472579D02*
X727391D01*
G01X723491Y458406D02*
X727391D01*
G01X731433Y475262D02*
Y474018D01*
X729994Y472579D01*
X727391D01*
G01X731433Y489435D02*
Y488191D01*
X729994Y486752D01*
X727391D01*
G01X731433Y482666D02*
Y481104D01*
X729994Y479665D01*
X727391D01*
G01X723491D02*
X727391D01*
G01X723491Y486752D02*
X727391D01*
G01X723491Y493839D02*
X727391D01*
G01X731249Y495088D02*
X730000Y493839D01*
X727391D01*
G01X731906Y522134D02*
X730241Y523799D01*
X727391D01*
G01X723491Y516713D02*
X727391D01*
G01X731984Y514608D02*
X729879Y516713D01*
X727391D01*
G01X723491Y509626D02*
X727391D01*
G01X731291D02*
X727391D01*
G01X723491Y523799D02*
X727391D01*
G01X723491Y530886D02*
X727391D01*
G01X732549Y529136D02*
X730799Y530886D01*
X727391D01*
G01X723491Y537973D02*
X727391D01*
G01X732388Y535677D02*
X730092Y537973D01*
X727391D01*
G01X723491Y566752D02*
X727391D01*
G01X731672Y565574D02*
X730494Y566752D01*
X727391D01*
G01X723491Y559665D02*
X727391D01*
G01X731291D02*
X727391D01*
G01X723491Y573839D02*
X727391D01*
G01X731319Y574338D02*
X730820Y573839D01*
X727391D01*
G01X723491Y588012D02*
X727391D01*
G01X723491Y595099D02*
X727391D01*
G01X723491Y602185D02*
X727391D01*
G01X723491Y609272D02*
X727391D01*
G01X723491Y616358D02*
X727391D01*
G01X731418D02*
X727391D01*
G01X749586Y403307D02*
X745502D01*
G01X749586Y410394D02*
X745502D01*
G01X741568Y460250D02*
Y459430D01*
X742592Y458406D01*
X745502D01*
G01X741602Y465492D02*
X745502D01*
G01X741602Y472579D02*
X745502D01*
G01X749402Y458406D02*
X745502D01*
G01X749402Y472579D02*
X745502D01*
G01X749402Y465492D02*
X745502D01*
G01X741072Y478958D02*
X742779Y479665D01*
X745502D01*
G01X741602Y486752D02*
X745502D01*
G01X749402Y479665D02*
X745502D01*
G01X749402Y486752D02*
X745502D01*
G01X749402Y493839D02*
X745502D01*
G01X741602D02*
X745502D01*
G01X749402Y516713D02*
X745502D01*
G01X741602D02*
X745502D01*
G01X749402Y509626D02*
X745502D01*
G01X741602D02*
X745502D01*
G01X749402Y523799D02*
X745502D01*
G01X740542Y525483D02*
X742226Y523799D01*
X745502D01*
G01X749402Y537973D02*
X745502D01*
G01X738062D02*
X745502D01*
G01X749402Y530886D02*
X745502D01*
G01X740463Y532756D02*
X742333Y530886D01*
X745502D01*
G01X749402Y559665D02*
X745502D01*
G01X741602D02*
X745502D01*
G01X749402Y566752D02*
X745502D01*
G01X741602D02*
X745502D01*
G01X749402Y573839D02*
X745502D01*
G01X741602D02*
X745502D01*
G01X749402Y588012D02*
X745502D01*
G01X749402Y580925D02*
X745502D01*
G01X741452Y579978D02*
X742399Y580925D01*
X745502D01*
G01X749402Y602185D02*
X745502D01*
G01X749402Y595099D02*
X745502D01*
G01X749402Y609272D02*
X745502D01*
G01X741666Y608117D02*
X742821Y609272D01*
X745502D01*
G01X749402Y616358D02*
X745502D01*
G01X777749Y1431432D02*
X780174D01*
G01D02*
Y1427432D01*
G01Y1435432D02*
X777749D01*
G01X780174Y1439432D02*
X777749D01*
G01X783336Y1443445D02*
X783215Y1443566D01*
Y1449575D01*
G01X795794Y1167808D02*
Y1172906D01*
X794716Y1173984D01*
Y1175750D01*
G01X793744Y1437159D02*
X794344Y1436559D01*
X796269D01*
G01X783215Y1449575D02*
X786850D01*
X788193Y1450918D01*
X793288D01*
G01X810161Y102323D02*
X806161D01*
G01X810413Y109410D02*
X806161D01*
G01X810413Y116496D02*
X806161D01*
G01D02*
X802161D01*
G01X806161Y109410D02*
X802161D01*
G01X806161Y102323D02*
X802161D01*
G01X811638Y130670D02*
X806161D01*
G01X802161Y123583D02*
X806161D01*
G01Y130670D02*
X802161D01*
G01X806161Y123583D02*
X809592D01*
X810585Y124576D01*
G01X811633Y137756D02*
X806161D01*
G01D02*
X802161D01*
G01X801354Y1478681D02*
X801947Y1478088D01*
Y1474064D01*
X803351Y1472660D01*
X805009D01*
G01X820137Y103037D02*
X820851Y102323D01*
X824271D01*
G01X820271Y116496D02*
X824271D01*
G01X820271Y109410D02*
X824271D01*
G01Y116496D02*
X828271D01*
G01X824271Y109410D02*
X828271D01*
G01X824271Y102323D02*
X828271D01*
G01X820271Y130670D02*
X824271D01*
G01X820271Y123583D02*
X824271D01*
G01Y130670D02*
X828271D01*
G01X824271Y123583D02*
X828271D01*
G01Y137756D02*
X824271D01*
G01D02*
X816637D01*
G01X836701Y765839D02*
X832660D01*
X831999Y766500D01*
X830075D01*
G01X836701Y783839D02*
X832660D01*
X831999Y784500D01*
X830075D01*
G01X836701Y801839D02*
X832660D01*
X831999Y802500D01*
X830075D01*
G01X836701Y819839D02*
X832660D01*
X831999Y820500D01*
X830075D01*
G01X832284Y727177D02*
Y716589D01*
G01X836701Y758161D02*
X841500D01*
G01X836701Y776161D02*
X841500D01*
G01X836701Y794161D02*
X841500D01*
G01X836701Y812161D02*
X841500D01*
G01X840136Y830903D02*
X840275D01*
X840930Y831558D01*
X842710D01*
G01X836405Y863567D02*
X836562Y863724D01*
X839851D01*
X840162Y863413D01*
G01X846844Y1454334D02*
X849544D01*
G01X834297Y1454525D02*
X836356D01*
X837685Y1453196D01*
G01X848284Y727177D02*
Y716589D01*
G01X861425Y768000D02*
X859500D01*
X857339Y765839D01*
X854299D01*
G01X861425Y786000D02*
X859500D01*
X857339Y783839D01*
X854299D01*
G01X861425Y804000D02*
X859500D01*
X857339Y801839D01*
X854299D01*
G01X861425Y822000D02*
X859500D01*
X857339Y819839D01*
X854299D01*
G01X880501Y710611D02*
X877801D01*
G01X870321Y715729D02*
X873021D01*
G01X870727Y722060D02*
X867227D01*
G01X883686Y727178D02*
X877727D01*
G01X884045Y754297D02*
X880028Y758314D01*
Y761332D01*
G01X899573Y697881D02*
X898370Y696678D01*
X895751D01*
G01X883669Y1448859D02*
X881244D01*
G01X889944Y1457959D02*
Y1457134D01*
X891844Y1455234D01*
G01X903297Y245669D02*
X898851D01*
G01X903297Y238583D02*
X898851D01*
G01X903297Y231496D02*
X898851D01*
G01X915423Y238583D02*
X910977D01*
G01X915423Y243307D02*
X910977D01*
G01X903297Y259843D02*
X898851D01*
G01X903297Y252756D02*
X898876D01*
X898576Y253056D01*
G01X915423Y252756D02*
X910977D01*
G01X915423Y257480D02*
X910977D01*
G01X915423Y248032D02*
X910977D01*
G01X915423Y262205D02*
X910977D01*
G01X903297Y274016D02*
X898851D01*
G01X903297Y266929D02*
X898851D01*
G01X915423D02*
X910977D01*
G01X903297Y269291D02*
X898144D01*
X898048Y269387D01*
G01X915423Y231496D02*
X918860D01*
X919356Y231000D01*
X919606D01*
G01X915423Y233858D02*
X919577D01*
G01X915423Y236221D02*
X918732D01*
X919432Y236921D01*
X919682D01*
G01X915423Y245669D02*
X919577D01*
G01X915423Y240945D02*
X919577D01*
G01X915423Y255118D02*
X919577D01*
G01X915423Y259843D02*
X919577D01*
G01X915423Y250394D02*
X919577D01*
G01X915423Y274016D02*
X918915D01*
X919479Y274580D01*
X919729D01*
G01X915423Y264567D02*
X919577D01*
G01X915423Y269291D02*
X918537D01*
X919366Y268462D01*
X919616D01*
G01X915423Y271654D02*
X919577D01*
G01X960161Y102323D02*
X956161D01*
G01X960413Y109410D02*
X956161D01*
G01X960413Y116496D02*
X956161D01*
G01D02*
X952161D01*
G01X956161Y109410D02*
X952161D01*
G01X956161Y102323D02*
X952161D01*
G01X961638Y130670D02*
X956161D01*
G01X952161Y123583D02*
X956161D01*
G01Y130670D02*
X952161D01*
G01X963360Y121459D02*
X961236Y123583D01*
X956161D01*
G01X961633Y137756D02*
X956161D01*
G01D02*
X952161D01*
G01X970271Y109410D02*
X974271D01*
G01X978271Y102323D02*
X974271D01*
G01X978271Y116496D02*
X974271D01*
G01D02*
X970271D01*
G01X974271Y109410D02*
X978271D01*
G01X974271Y102323D02*
X970851D01*
X970137Y103037D01*
G01X970271Y130670D02*
X974271D01*
G01X970271Y123583D02*
X974271D01*
G01Y130670D02*
X978271D01*
G01X974271Y123583D02*
X978271D01*
G01X966347Y137756D02*
X974271D01*
G01D02*
X978271D01*
G01X1006053Y783295D02*
Y787745D01*
G01X1062523Y102323D02*
X1058523D01*
G01X1062775Y109410D02*
X1058523D01*
G01X1062775Y116496D02*
X1058523D01*
G01D02*
X1054523D01*
G01X1058523Y109410D02*
X1054523D01*
G01X1058523Y102323D02*
X1054523D01*
G01X1064000Y130670D02*
X1058523D01*
G01X1054523Y123583D02*
X1058523D01*
G01Y130670D02*
X1054523D01*
G01X1058523Y123583D02*
X1061954D01*
X1062947Y124576D01*
G01X1063995Y137756D02*
X1058523D01*
G01D02*
X1054523D01*
G01X1076633Y116496D02*
X1072633D01*
G01X1076633Y109410D02*
X1072633D01*
G01X1076633Y102323D02*
X1073213D01*
X1072499Y103037D01*
G01X1076633Y130670D02*
X1072633D01*
G01X1076633Y123583D02*
X1072633D01*
G01X1076633Y137756D02*
X1069224D01*
G01X1080633Y102323D02*
X1076633D01*
G01X1080633Y116496D02*
X1076633D01*
G01X1080633Y109410D02*
X1076633D01*
G01X1080633Y130670D02*
X1076633D01*
G01X1080633Y123583D02*
X1076633D01*
G01X1080633Y137756D02*
X1076633D01*
G01X1091542Y389154D02*
X1095442D01*
G01X1091542Y396240D02*
X1095442D01*
G01X1091542Y403327D02*
X1095442D01*
G01X1091542Y410413D02*
X1095442D01*
G01X1091542Y424587D02*
X1095442D01*
G01X1091542Y417500D02*
X1095442D01*
G01X1091542Y431673D02*
X1095442D01*
G01X1091542Y438760D02*
X1095442D01*
G01X1091542Y445847D02*
X1095442D01*
G01X1091542Y467539D02*
X1095442D01*
G01X1091542Y488799D02*
X1095442D01*
G01X1091542Y474626D02*
X1095442D01*
G01X1091542Y481713D02*
X1095442D01*
G01X1091542Y495886D02*
X1095442D01*
G01X1091542Y518760D02*
X1095442D01*
G01X1091542Y511673D02*
X1095442D01*
G01X1091542Y525847D02*
X1095442D01*
G01X1091542Y532933D02*
X1095442D01*
G01Y540020D02*
X1091542D01*
G01Y547106D02*
X1095442D01*
G01X1090823Y602197D02*
X1090923D01*
X1090931Y602205D01*
X1095442D01*
G01X1091287Y595108D02*
X1091410D01*
X1091420Y595118D01*
X1095442D01*
G01X1099342Y389154D02*
X1095442D01*
G01X1106161D02*
X1113553D01*
G01X1099342Y396240D02*
X1095442D01*
G01X1100621Y404911D02*
X1099037Y403327D01*
X1095442D01*
G01X1104691Y396240D02*
X1113553D01*
G01X1099575Y412571D02*
Y411043D01*
X1098945Y410413D01*
X1095442D01*
G01X1100762Y426299D02*
X1099050Y424587D01*
X1095442D01*
G01X1101073Y445847D02*
X1095442D01*
G01X1099342Y467539D02*
X1095442D01*
G01X1099342Y474626D02*
X1095442D01*
G01X1099603Y480828D02*
X1098718Y481713D01*
X1095442D01*
G01X1101553Y498834D02*
X1098605Y495886D01*
X1095442D01*
G01X1108253Y510565D02*
X1109361Y511673D01*
X1113553D01*
G01X1105002Y516841D02*
X1106921Y518760D01*
X1113553D01*
G01X1099342D02*
X1095442D01*
G01X1099342Y511673D02*
X1095442D01*
G01X1099342Y525847D02*
X1095442D01*
G01X1117453Y389154D02*
X1113553D01*
G01X1117453Y396240D02*
X1113553D01*
G01X1117453Y403327D02*
X1113553D01*
G01X1108776Y422864D02*
X1110499Y424587D01*
X1113553D01*
G01X1109468Y414823D02*
Y416038D01*
X1110930Y417500D01*
X1113553D01*
G01X1117453D02*
X1113553D01*
G01X1117453Y410413D02*
X1113553D01*
G01X1108846Y429832D02*
X1110687Y431673D01*
X1113553D01*
G01X1108451Y436447D02*
X1110764Y438760D01*
X1113553D01*
G01X1117453Y431673D02*
X1113553D01*
G01X1117453Y438760D02*
X1113553D01*
G01X1110486Y447953D02*
Y446794D01*
X1111433Y445847D01*
X1113553D01*
G01X1117453D02*
X1113553D01*
G01X1109653Y467539D02*
X1113553D01*
G01X1117453D02*
X1113553D01*
G01X1108395Y472772D02*
X1110249Y474626D01*
X1113553D01*
G01X1117453Y488799D02*
X1113553D01*
G01X1109129Y487711D02*
X1110217Y488799D01*
X1113553D01*
G01X1109242Y479104D02*
Y480489D01*
X1110466Y481713D01*
X1113553D01*
G01X1117453Y474626D02*
X1113553D01*
G01X1117453Y481713D02*
X1113553D01*
G01X1117453Y495886D02*
X1113553D01*
G01X1109653D02*
X1113553D01*
G01X1117453Y511673D02*
X1113553D01*
G01X1117453Y518760D02*
X1113553D01*
G01X1117453Y525847D02*
X1113553D01*
G01X1117453Y532933D02*
X1113553D01*
G01X1117453Y540020D02*
X1113553D01*
G01X1117453Y547106D02*
X1113553D01*
G01X1117453Y554193D02*
X1113553D01*
G01X1117453Y602205D02*
X1113553D01*
G01X1117453Y595118D02*
X1113553D01*
G01X1164885Y102323D02*
X1160885D01*
G01X1165137Y109410D02*
X1160885D01*
G01X1165137Y116496D02*
X1160885D01*
G01D02*
X1156885D01*
G01X1160885Y109410D02*
X1156885D01*
G01X1160885Y102323D02*
X1156885D01*
G01X1166362Y130670D02*
X1160885D01*
G01X1156885Y123583D02*
X1160885D01*
G01Y130670D02*
X1156885D01*
G01X1160885Y123583D02*
X1164316D01*
X1165309Y124576D01*
G01X1166357Y137756D02*
X1160885D01*
G01X1178995D02*
X1171586D01*
G01X1160885D02*
X1156885D01*
G01X1173011Y779494D02*
Y779532D01*
X1171284Y781259D01*
Y786294D01*
G01X1174861Y103037D02*
X1175575Y102323D01*
X1178995D01*
G01X1174995Y116496D02*
X1178995D01*
G01X1174995Y109410D02*
X1178995D01*
G01Y116496D02*
X1182995D01*
G01X1178995Y109410D02*
X1182995D01*
G01X1178995Y102323D02*
X1182995D01*
G01X1174995Y130670D02*
X1178995D01*
G01X1174995Y123583D02*
X1178995D01*
G01Y130670D02*
X1182995D01*
G01X1178995Y123583D02*
X1182995D01*
G01Y137756D02*
X1178995D01*
G01X1179184Y403307D02*
X1184478D01*
G01X1179184Y410394D02*
X1184478D01*
G01X1180578Y451319D02*
X1184478D01*
G01X1188378Y466027D02*
X1188309D01*
X1187774Y465492D01*
X1184478D01*
G01X1180578Y472579D02*
X1184478D01*
G01X1180578Y465492D02*
X1184478D01*
G01X1180578Y458406D02*
X1184478D01*
G01X1188520Y475262D02*
Y474018D01*
X1187081Y472579D01*
X1184478D01*
G01X1188520Y489435D02*
Y488191D01*
X1187081Y486752D01*
X1184478D01*
G01X1188520Y482666D02*
Y481104D01*
X1187081Y479665D01*
X1184478D01*
G01X1180578D02*
X1184478D01*
G01X1180578Y486752D02*
X1184478D01*
G01X1180578Y493839D02*
X1184478D01*
G01X1188336Y495088D02*
X1187087Y493839D01*
X1184478D01*
G01X1188993Y522134D02*
X1187328Y523799D01*
X1184478D01*
G01X1180578Y516713D02*
X1184478D01*
G01X1189071Y514608D02*
X1186966Y516713D01*
X1184478D01*
G01X1180578Y509626D02*
X1184478D01*
G01X1188378D02*
X1184478D01*
G01X1180578Y523799D02*
X1184478D01*
G01X1180578Y537973D02*
X1184478D01*
G01X1189475Y535677D02*
X1187179Y537973D01*
X1184478D01*
G01X1180578Y530886D02*
X1184478D01*
G01X1189636Y529136D02*
X1187886Y530886D01*
X1184478D01*
G01X1180578Y559665D02*
X1184478D01*
G01X1188378D02*
X1184478D01*
G01X1180578Y566752D02*
X1184478D01*
G01X1188759Y565574D02*
X1187581Y566752D01*
X1184478D01*
G01X1180578Y588012D02*
X1184478D01*
G01X1180578Y573839D02*
X1184478D01*
G01X1188406Y574338D02*
X1187907Y573839D01*
X1184478D01*
G01X1180578Y602185D02*
X1184478D01*
G01X1180578Y595099D02*
X1184478D01*
G01X1180578Y616358D02*
X1184478D01*
G01X1188505D02*
X1184478D01*
G01X1180578Y609272D02*
X1184478D01*
G01X1173843Y786294D02*
Y783256D01*
X1175056Y782043D01*
X1180715D01*
G01X1206673Y403307D02*
X1202589D01*
G01X1206673Y410394D02*
X1202589D01*
G01X1198655Y460250D02*
Y459430D01*
X1199679Y458406D01*
X1202589D01*
G01X1198689Y465492D02*
X1202589D01*
G01X1198689Y472579D02*
X1202589D01*
G01X1206489Y458406D02*
X1202589D01*
G01X1206489Y472579D02*
X1202589D01*
G01X1206489Y465492D02*
X1202589D01*
G01X1198689Y486752D02*
X1202589D01*
G01X1198689Y479665D02*
X1202589D01*
G01X1206489D02*
X1202589D01*
G01X1206489Y486752D02*
X1202589D01*
G01X1206489Y493839D02*
X1202589D01*
G01X1198689D02*
X1202589D01*
G01X1206489Y516713D02*
X1202589D01*
G01X1198689D02*
X1202589D01*
G01X1206489Y509626D02*
X1202589D01*
G01X1198689D02*
X1202589D01*
G01X1206489Y523799D02*
X1202589D01*
G01X1197629Y525483D02*
X1199313Y523799D01*
X1202589D01*
G01X1206489Y537973D02*
X1202589D01*
G01X1195149D02*
X1202589D01*
G01X1206489Y530886D02*
X1202589D01*
G01X1197550Y532756D02*
X1199420Y530886D01*
X1202589D01*
G01X1206489Y566752D02*
X1202589D01*
G01X1198689D02*
X1202589D01*
G01X1206489Y559665D02*
X1202589D01*
G01X1198689D02*
X1202589D01*
G01X1206489Y580925D02*
X1202589D01*
G01X1198539Y579978D02*
X1199486Y580925D01*
X1202589D01*
G01X1206489Y588012D02*
X1202589D01*
G01X1206489Y573839D02*
X1202589D01*
G01X1198689D02*
X1202589D01*
G01X1206489Y602185D02*
X1202589D01*
G01X1206489Y595099D02*
X1202589D01*
G01X1206489Y616358D02*
X1202589D01*
G01X1206489Y609272D02*
X1202589D01*
G01X1198753Y608117D02*
X1199908Y609272D01*
X1202589D01*
G01X1252880Y1167808D02*
Y1172520D01*
X1251802Y1173598D01*
Y1175750D01*
G01X1267499Y116496D02*
X1263247D01*
G01X1267247Y102323D02*
X1263247D01*
G01X1267499Y109410D02*
X1263247D01*
G01Y116496D02*
X1259247D01*
G01X1263247Y109410D02*
X1259247D01*
G01X1263247Y102323D02*
X1259247D01*
G01X1268724Y130670D02*
X1263247D01*
G01X1259247Y123583D02*
X1263247D01*
G01Y130670D02*
X1259247D01*
G01X1263247Y123583D02*
X1266678D01*
X1267671Y124576D01*
G01X1268719Y137756D02*
X1263247D01*
G01D02*
X1259247D01*
G01X1277223Y103037D02*
X1277937Y102323D01*
X1281357D01*
G01X1277357Y116496D02*
X1281357D01*
G01X1277357Y109410D02*
X1281357D01*
G01Y116496D02*
X1285357D01*
G01X1281357Y109410D02*
X1285357D01*
G01X1281357Y102323D02*
X1285357D01*
G01X1277357Y123583D02*
X1281357D01*
G01X1277357Y130670D02*
X1281357D01*
G01D02*
X1285357D01*
G01X1281357Y123583D02*
X1285357D01*
G01X1273555Y137756D02*
X1281357D01*
G01D02*
X1285357D01*
G01X1291059Y904669D02*
Y902191D01*
X1291955Y901295D01*
G01X1318000Y948063D02*
Y944910D01*
X1318375Y944535D01*
Y943951D01*
G01X1304075Y942500D02*
X1303907Y942668D01*
Y948224D01*
G01Y956098D02*
Y960093D01*
G01X1329500Y955937D02*
Y958943D01*
X1328457Y959986D01*
G01X1337691Y951718D02*
X1337596Y951623D01*
X1330705D01*
X1329500Y950418D01*
Y948063D01*
G01X1337691Y951718D02*
Y959379D01*
X1335343Y961727D01*
G01X1337691Y948568D02*
X1340659D01*
X1341820Y947407D01*
G01X1378322Y859792D02*
X1379896Y858218D01*
G01X1417500Y109410D02*
X1413248D01*
G01X1417500Y116496D02*
X1413248D01*
G01X1417248Y102323D02*
X1413248D01*
G01Y116496D02*
X1409248D01*
G01X1413248Y109410D02*
X1409248D01*
G01X1413248Y102323D02*
X1409248D01*
G01X1418725Y130670D02*
X1413248D01*
G01D02*
X1409248D01*
G01X1413248Y123583D02*
X1409248D01*
G01X1421700Y122900D02*
X1421017Y123583D01*
X1413248D01*
G01X1418720Y137756D02*
X1413248D01*
G01D02*
X1409248D01*
G01X1427358Y116496D02*
X1431358D01*
G01X1427358Y109410D02*
X1431358D01*
G01X1427224Y103037D02*
X1427938Y102323D01*
X1431358D01*
G01Y116496D02*
X1435358D01*
G01X1431358Y109410D02*
X1435358D01*
G01X1431358Y102323D02*
X1435358D01*
G01X1427358Y130670D02*
X1431358D01*
G01X1427358Y123583D02*
X1431358D01*
G01Y130670D02*
X1435358D01*
G01X1431358Y123583D02*
X1435358D01*
G01X1423515Y137756D02*
X1431358D01*
G01D02*
X1435358D01*
G01X1439234Y938291D02*
X1443938D01*
X1444453Y938806D01*
G01X1443428Y1014402D02*
Y1018749D01*
X1440610Y1021567D01*
G01X1437980Y1028372D02*
X1438310Y1028042D01*
Y1023064D01*
G01X1456543Y950980D02*
Y947165D01*
X1455347Y945969D01*
X1453800D01*
G01X1515610Y116496D02*
X1511610D01*
G01X1515610Y109410D02*
X1511610D01*
G01X1515610Y102323D02*
X1511610D01*
G01Y123583D02*
X1515610D01*
G01Y130670D02*
X1511610D01*
G01X1515610Y137756D02*
X1511610D01*
G01X1519610Y102323D02*
X1515610D01*
G01X1519862Y109410D02*
X1515610D01*
G01X1519862Y116496D02*
X1515610D01*
G01X1533720D02*
X1529720D01*
G01X1533720Y109410D02*
X1529720D01*
G01X1533720Y102323D02*
X1530300D01*
X1529586Y103037D01*
G01X1521087Y130670D02*
X1515610D01*
G01X1533720D02*
X1529720D01*
G01X1533720Y123583D02*
X1529720D01*
G01X1515610D02*
X1519041D01*
X1520034Y124576D01*
G01X1521082Y137756D02*
X1515610D01*
G01X1533720D02*
X1526311D01*
G01X1537720Y116496D02*
X1533720D01*
G01X1537720Y109410D02*
X1533720D01*
G01X1537720Y102323D02*
X1533720D01*
G01X1537720Y130670D02*
X1533720D01*
G01X1537720Y123583D02*
X1533720D01*
G01X1537720Y137756D02*
X1533720D01*
G01X1556429Y389154D02*
X1552529D01*
G01X1548629D02*
X1552529D01*
G01X1556429Y396240D02*
X1552529D01*
G01X1557708Y404911D02*
X1556124Y403327D01*
X1552529D01*
G01X1561778Y396240D02*
X1570640D01*
G01X1548629D02*
X1552529D01*
G01X1548629Y403327D02*
X1552529D01*
G01X1556662Y412571D02*
Y411043D01*
X1556032Y410413D01*
X1552529D01*
G01X1557849Y426299D02*
X1556137Y424587D01*
X1552529D01*
G01X1548629Y410413D02*
X1552529D01*
G01X1548629Y424587D02*
X1552529D01*
G01X1548629Y417500D02*
X1552529D01*
G01X1548629Y431673D02*
X1552529D01*
G01X1548629Y438760D02*
X1552529D01*
G01X1558160Y445847D02*
X1552529D01*
G01X1548629D02*
X1552529D01*
G01X1556429Y467539D02*
X1552529D01*
G01X1548629D02*
X1552529D01*
G01X1548629Y488799D02*
X1552529D01*
G01X1556429Y474626D02*
X1552529D01*
G01X1556690Y480828D02*
X1555805Y481713D01*
X1552529D01*
G01X1548629Y474626D02*
X1552529D01*
G01X1548629Y481713D02*
X1552529D01*
G01X1548629Y495886D02*
X1552529D01*
G01X1558640Y498834D02*
X1555692Y495886D01*
X1552529D01*
G01X1562089Y516841D02*
X1564008Y518760D01*
X1570640D01*
G01X1548629Y511673D02*
X1552529D01*
G01X1556429D02*
X1552529D01*
G01X1548629Y518760D02*
X1552529D01*
G01X1556429D02*
X1552529D01*
G01X1548629Y525847D02*
X1552529D01*
G01X1556429D02*
X1552529D01*
G01X1548629Y532933D02*
X1552529D01*
G01Y540020D02*
X1548629D01*
G01Y547106D02*
X1552529D01*
G01X1547910Y602197D02*
X1548010D01*
X1548018Y602205D01*
X1552529D01*
G01X1548374Y595108D02*
X1548497D01*
X1548507Y595118D01*
X1552529D01*
G01X1563248Y389154D02*
X1570640D01*
G01X1574540D02*
X1570640D01*
G01X1574540Y396240D02*
X1570640D01*
G01X1574540Y403327D02*
X1570640D01*
G01X1566555Y414823D02*
Y416038D01*
X1568017Y417500D01*
X1570640D01*
G01X1565863Y422864D02*
X1567586Y424587D01*
X1570640D01*
G01X1574540Y417500D02*
X1570640D01*
G01X1574540Y410413D02*
X1570640D01*
G01X1565933Y429832D02*
X1567774Y431673D01*
X1570640D01*
G01X1565538Y436447D02*
X1567851Y438760D01*
X1570640D01*
G01X1574540D02*
X1570640D01*
G01X1574540Y431673D02*
X1570640D01*
G01X1567573Y447953D02*
Y446794D01*
X1568520Y445847D01*
X1570640D01*
G01X1574540D02*
X1570640D01*
G01X1566740Y467539D02*
X1570640D01*
G01X1574540D02*
X1570640D01*
G01X1565482Y472772D02*
X1567336Y474626D01*
X1570640D01*
G01X1574540Y488799D02*
X1570640D01*
G01X1566216Y487711D02*
X1567304Y488799D01*
X1570640D01*
G01X1566329Y479104D02*
Y480489D01*
X1567553Y481713D01*
X1570640D01*
G01X1574540Y474626D02*
X1570640D01*
G01X1574540Y481713D02*
X1570640D01*
G01X1574540Y495886D02*
X1570640D01*
G01X1566740D02*
X1570640D01*
G01X1574540Y511673D02*
X1570640D01*
G01X1565050D02*
X1570640D01*
G01X1574540Y518760D02*
X1570640D01*
G01X1574540Y525847D02*
X1570640D01*
G01X1574540Y532933D02*
X1570640D01*
G01X1574540Y540020D02*
X1570640D01*
G01X1574540Y547106D02*
X1570640D01*
G01X1574540Y554193D02*
X1570640D01*
G01X1574540Y602205D02*
X1570640D01*
G01X1574540Y595118D02*
X1570640D01*
G01X1621972Y102323D02*
X1617972D01*
G01X1622224Y109410D02*
X1617972D01*
G01X1622224Y116496D02*
X1617972D01*
G01D02*
X1613972D01*
G01X1617972Y109410D02*
X1613972D01*
G01X1617972Y102323D02*
X1613972D01*
G01X1623449Y130670D02*
X1617972D01*
G01X1613972Y123583D02*
X1617972D01*
G01Y130670D02*
X1613972D01*
G01X1617972Y123583D02*
X1621403D01*
X1622396Y124576D01*
G01X1623444Y137756D02*
X1617972D01*
G01D02*
X1613972D01*
G01X1631948Y103037D02*
X1632662Y102323D01*
X1636082D01*
G01X1632082Y116496D02*
X1636082D01*
G01X1632082Y109410D02*
X1636082D01*
G01Y116496D02*
X1640082D01*
G01X1636082Y109410D02*
X1640082D01*
G01X1636082Y102323D02*
X1640082D01*
G01X1632082Y130670D02*
X1636082D01*
G01X1632082Y123583D02*
X1636082D01*
G01Y130670D02*
X1640082D01*
G01X1636082Y123583D02*
X1640082D01*
G01Y137756D02*
X1636082D01*
G01D02*
X1628673D01*
G01X1636271Y403307D02*
X1641565D01*
G01X1636271Y410394D02*
X1641565D01*
G01X1637665Y451319D02*
X1641565D01*
G01X1645465Y466027D02*
X1645396D01*
X1644861Y465492D01*
X1641565D01*
G01X1637665Y472579D02*
X1641565D01*
G01X1637665Y465492D02*
X1641565D01*
G01X1637665Y458406D02*
X1641565D01*
G01X1645607Y475262D02*
Y474018D01*
X1644168Y472579D01*
X1641565D01*
G01X1645607Y489435D02*
Y488191D01*
X1644168Y486752D01*
X1641565D01*
G01X1645607Y482666D02*
Y481104D01*
X1644168Y479665D01*
X1641565D01*
G01X1637665D02*
X1641565D01*
G01X1637665Y486752D02*
X1641565D01*
G01X1637665Y493839D02*
X1641565D01*
G01X1645423Y495088D02*
X1644174Y493839D01*
X1641565D01*
G01X1637665Y516713D02*
X1641565D01*
G01X1646158Y514608D02*
X1644053Y516713D01*
X1641565D01*
G01X1637665Y509626D02*
X1641565D01*
G01X1645465D02*
X1641565D01*
G01X1637665Y523799D02*
X1641565D01*
G01X1646080Y522134D02*
X1644415Y523799D01*
X1641565D01*
G01X1637665Y537973D02*
X1641565D01*
G01X1646562Y535677D02*
X1644266Y537973D01*
X1641565D01*
G01X1637665Y530886D02*
X1641565D01*
G01X1646723Y529136D02*
X1644973Y530886D01*
X1641565D01*
G01X1637665Y559665D02*
X1641565D01*
G01X1645465D02*
X1641565D01*
G01X1637665Y566752D02*
X1641565D01*
G01X1645846Y565574D02*
X1644668Y566752D01*
X1641565D01*
G01X1637665Y573839D02*
X1641565D01*
G01X1645493Y574338D02*
X1644994Y573839D01*
X1641565D01*
G01X1637665Y588012D02*
X1641565D01*
G01X1637665Y602185D02*
X1641565D01*
G01X1637665Y595099D02*
X1641565D01*
G01X1637665Y616358D02*
X1641565D01*
G01X1645592D02*
X1641565D01*
G01X1637665Y609272D02*
X1641565D01*
G01X1663760Y403307D02*
X1659676D01*
G01X1663760Y410394D02*
X1659676D01*
G01X1655742Y460250D02*
Y459430D01*
X1656766Y458406D01*
X1659676D01*
G01X1655776Y465492D02*
X1659676D01*
G01X1655776Y472579D02*
X1659676D01*
G01X1663576Y458406D02*
X1659676D01*
G01X1663576Y472579D02*
X1659676D01*
G01X1663576Y465492D02*
X1659676D01*
G01X1663576Y486752D02*
X1659676D01*
G01X1655776D02*
X1659676D01*
G01X1655776Y479665D02*
X1659676D01*
G01X1663576D02*
X1659676D01*
G01X1663576Y493839D02*
X1659676D01*
G01X1655776D02*
X1659676D01*
G01X1663576Y516713D02*
X1659676D01*
G01X1655776D02*
X1659676D01*
G01X1663576Y509626D02*
X1659676D01*
G01X1655776D02*
X1659676D01*
G01X1663576Y523799D02*
X1659676D01*
G01X1654716Y525483D02*
X1656400Y523799D01*
X1659676D01*
G01X1663576Y537973D02*
X1659676D01*
G01X1652236D02*
X1659676D01*
G01X1663576Y530886D02*
X1659676D01*
G01X1654637Y532756D02*
X1656507Y530886D01*
X1659676D01*
G01X1663576Y559665D02*
X1659676D01*
G01X1655776D02*
X1659676D01*
G01X1663576Y566752D02*
X1659676D01*
G01X1655776D02*
X1659676D01*
G01X1663576Y580925D02*
X1659676D01*
G01X1655626Y579978D02*
X1656573Y580925D01*
X1659676D01*
G01X1663576Y588012D02*
X1659676D01*
G01X1663576Y573839D02*
X1659676D01*
G01X1655776D02*
X1659676D01*
G01X1663576Y602185D02*
X1659676D01*
G01X1663576Y595099D02*
X1659676D01*
G01X1663576Y616358D02*
X1659676D01*
G01X1663576Y609272D02*
X1659676D01*
G01X1655840Y608117D02*
X1656995Y609272D01*
X1659676D01*
G01X1709967Y1167808D02*
Y1173132D01*
X1708889Y1174210D01*
Y1175750D01*
G01X1724586Y116496D02*
X1720334D01*
G01X1724586Y109410D02*
X1720334D01*
G01X1724334Y102323D02*
X1720334D01*
G01Y116496D02*
X1716334D01*
G01X1720334Y109410D02*
X1716334D01*
G01X1720334Y102323D02*
X1716334D01*
G01X1725811Y130670D02*
X1720334D01*
G01X1716334Y123583D02*
X1720334D01*
G01Y130670D02*
X1716334D01*
G01X1720334Y123583D02*
X1723765D01*
X1724758Y124576D01*
G01X1725806Y137756D02*
X1720334D01*
G01D02*
X1716334D01*
G01X1734310Y103037D02*
X1735024Y102323D01*
X1738444D01*
G01X1734444Y116496D02*
X1738444D01*
G01X1742444Y109410D02*
X1738444D01*
G01Y116496D02*
X1742444D01*
G01X1738444Y109410D02*
X1734444D01*
G01X1738444Y102323D02*
X1742444D01*
G01X1734444Y130670D02*
X1738444D01*
G01X1734444Y123583D02*
X1738444D01*
G01Y130670D02*
X1742444D01*
G01X1738444Y123583D02*
X1742444D01*
G01X1730647Y137756D02*
X1738444D01*
G01D02*
X1742444D01*
G54D239*
X976763Y311927D03*
Y320273D03*
X983063Y311927D03*
Y320273D03*
G54D38*
X24792Y1072879D03*
Y1091383D03*
X62945Y170686D03*
Y189190D03*
X165307Y170686D03*
Y189190D03*
X267669Y170686D03*
Y189190D03*
X370031Y170686D03*
Y189190D03*
X414809Y951287D03*
Y969791D03*
X520032Y170686D03*
Y189190D03*
X622394Y170686D03*
Y189190D03*
X724756Y170686D03*
Y189190D03*
X827118Y170686D03*
Y189190D03*
X871249Y1081804D03*
Y1100308D03*
X935382Y1081609D03*
Y1100113D03*
X977118Y170686D03*
Y189190D03*
X1079480Y170686D03*
Y189190D03*
X1181842Y170686D03*
Y189190D03*
X1284204Y170686D03*
Y189190D03*
X1434205Y170686D03*
Y189190D03*
X1536567Y170686D03*
Y189190D03*
X1638929Y170686D03*
Y189190D03*
X1741291Y170686D03*
Y189190D03*
X1779439Y1082446D03*
Y1100950D03*
G54D47*
X37955Y1138071D03*
Y1180649D03*
X885145Y1147074D03*
Y1189652D03*
X949122Y1147074D03*
Y1189652D03*
X1793102Y1147560D03*
Y1190138D03*
G54D29*
X18463Y247292D03*
Y253198D03*
Y267292D03*
Y273198D03*
X25549Y247292D03*
Y253198D03*
Y267292D03*
Y273198D03*
X82918Y146461D03*
Y152367D03*
X84679Y1009260D03*
Y1015166D03*
X90004Y146461D03*
Y152367D03*
X91765Y1009260D03*
Y1015166D03*
X127911Y247292D03*
X120825D03*
Y253198D03*
X127911D03*
X192366Y146461D03*
X185280D03*
Y152367D03*
X192366D03*
X230273Y247292D03*
X223187D03*
Y253198D03*
X230273D03*
X294728Y146461D03*
X287642D03*
Y152367D03*
X294728D03*
X325549Y247292D03*
Y253198D03*
X332635Y247292D03*
Y253198D03*
X408758Y468607D03*
Y474513D03*
X415844Y468607D03*
Y474513D03*
X437643Y146461D03*
Y152367D03*
X444729Y146461D03*
Y152367D03*
X482636Y247292D03*
X475550D03*
Y253198D03*
X482636D03*
X540005Y146461D03*
Y152367D03*
X547091Y146461D03*
Y152367D03*
X548852Y1009260D03*
X541766D03*
Y1015166D03*
X548852D03*
X584998Y247292D03*
X577912D03*
Y253198D03*
X584998D03*
X649453Y146461D03*
X642367D03*
Y152367D03*
X649453D03*
X680274Y247292D03*
Y253198D03*
X687360Y247292D03*
Y253198D03*
X744729Y146461D03*
Y152367D03*
X751815Y146461D03*
Y152367D03*
X782636Y247292D03*
Y253198D03*
X789722Y247292D03*
Y253198D03*
X879997Y480350D03*
X872911D03*
Y486256D03*
X879997D03*
X894729Y146461D03*
Y152367D03*
X901815Y146461D03*
Y152367D03*
X1004177Y146461D03*
X997091D03*
Y152367D03*
X1004177D03*
X1005938Y1009260D03*
X998852D03*
Y1015166D03*
X1005938D03*
X1042084Y247292D03*
X1034998D03*
Y253198D03*
X1042084D03*
X1106539Y146461D03*
X1099453D03*
Y152367D03*
X1106539D03*
X1137360Y247292D03*
Y253198D03*
X1144446Y247292D03*
Y253198D03*
X1201815Y146461D03*
Y152367D03*
X1208901Y146461D03*
Y152367D03*
X1246808Y247292D03*
X1239722D03*
Y253198D03*
X1246808D03*
X1267792Y902371D03*
Y908277D03*
X1274878Y902371D03*
Y908277D03*
X1330017Y468607D03*
X1322931D03*
Y474513D03*
X1330017D03*
X1351816Y146461D03*
Y152367D03*
X1358902Y146461D03*
Y152367D03*
X1396809Y247292D03*
X1389723D03*
Y253198D03*
X1396809D03*
X1421368Y1537432D03*
Y1543338D03*
X1428454D03*
Y1537432D03*
X1420995Y1558072D03*
X1428081D03*
X1420995Y1563978D03*
X1428081D03*
X1461264Y146461D03*
X1454178D03*
Y152367D03*
X1461264D03*
X1463025Y1009260D03*
X1455939D03*
Y1015166D03*
X1463025D03*
X1492085Y247292D03*
Y253198D03*
X1499171Y247292D03*
Y253198D03*
X1556540Y146461D03*
Y152367D03*
X1563626Y146461D03*
Y152367D03*
X1594447Y247292D03*
Y253198D03*
X1601533Y247292D03*
Y253198D03*
X1627155Y699930D03*
Y705836D03*
Y717830D03*
X1627455Y732430D03*
X1627155Y723736D03*
X1627455Y738336D03*
Y750630D03*
Y756536D03*
X1623741Y780736D03*
Y774830D03*
X1616655D03*
Y780736D03*
X1623541Y793436D03*
Y787530D03*
X1616455D03*
Y793436D03*
X1623241Y807536D03*
Y801630D03*
X1616155D03*
Y807536D03*
X1623341Y815730D03*
X1616255D03*
X1623341Y821636D03*
X1616255D03*
X1634241Y699930D03*
Y705836D03*
Y717830D03*
X1634541Y732430D03*
X1634241Y723736D03*
X1634541Y738336D03*
Y750630D03*
Y756536D03*
X1658902Y146461D03*
Y152367D03*
X1665988Y146461D03*
Y152367D03*
X1703895Y247292D03*
X1696809D03*
Y253198D03*
X1703895D03*
X1787104Y468607D03*
X1780018D03*
Y474513D03*
X1787104D03*
X1790264Y1446668D03*
Y1440762D03*
X1783178D03*
Y1446668D03*
X1790141Y1478858D03*
Y1472952D03*
X1783055D03*
Y1478858D03*
G54D257*
X1439234Y938291D03*
Y940850D03*
Y943410D03*
Y945969D03*
X1453800Y943410D03*
Y940850D03*
Y938291D03*
Y945969D03*
G54D176*
X526897Y797102D03*
Y799071D03*
Y812850D03*
Y804976D03*
Y803008D03*
Y801039D03*
Y806945D03*
Y808913D03*
Y810882D03*
Y814819D03*
Y826630D03*
Y824661D03*
Y822693D03*
Y816787D03*
Y818756D03*
Y820724D03*
X571975Y799071D03*
Y797102D03*
Y803008D03*
Y812850D03*
Y814819D03*
Y810882D03*
Y808913D03*
Y806945D03*
Y804976D03*
Y801039D03*
Y824661D03*
Y826630D03*
Y822693D03*
Y820724D03*
Y818756D03*
Y816787D03*
X1491656Y924453D03*
Y926422D03*
Y928390D03*
Y940201D03*
Y932327D03*
Y930359D03*
Y934296D03*
Y936264D03*
Y938233D03*
Y942170D03*
Y944138D03*
Y953981D03*
Y952012D03*
Y950044D03*
Y946107D03*
Y948075D03*
X1536734Y928390D03*
Y926422D03*
Y924453D03*
Y930359D03*
Y940201D03*
Y944138D03*
Y942170D03*
Y938233D03*
Y936264D03*
Y934296D03*
Y932327D03*
Y952012D03*
Y953981D03*
Y950044D03*
Y948075D03*
Y946107D03*
G54D83*
X59134Y875295D03*
Y870295D03*
Y880295D03*
Y885295D03*
Y890295D03*
Y895295D03*
Y905295D03*
Y900295D03*
X96930Y875295D03*
Y880295D03*
Y870295D03*
Y885295D03*
Y890295D03*
Y895295D03*
Y905295D03*
Y900295D03*
X516074Y875295D03*
Y870295D03*
Y880295D03*
Y885295D03*
Y890295D03*
Y895295D03*
Y905295D03*
Y900295D03*
X553870Y875295D03*
Y880295D03*
Y870295D03*
Y885295D03*
Y890295D03*
Y895295D03*
Y905295D03*
Y900295D03*
X972833Y870295D03*
Y875295D03*
Y880295D03*
Y885295D03*
Y890295D03*
Y895295D03*
Y900295D03*
Y905295D03*
X1010629Y880295D03*
Y875295D03*
Y870295D03*
Y895295D03*
Y890295D03*
Y885295D03*
Y905295D03*
Y900295D03*
X1430247Y875295D03*
Y870295D03*
Y880295D03*
Y885295D03*
Y890295D03*
Y895295D03*
Y905295D03*
Y900295D03*
X1468043Y875295D03*
Y880295D03*
Y870295D03*
Y885295D03*
Y890295D03*
Y895295D03*
Y905295D03*
Y900295D03*
G54D149*
X423673Y439314D03*
Y435770D03*
Y446400D03*
Y442857D03*
X918999Y455655D03*
Y452111D03*
Y462741D03*
Y459198D03*
X1337846Y439314D03*
Y435770D03*
Y446400D03*
Y442857D03*
X1794933Y439314D03*
Y435770D03*
Y446400D03*
Y442857D03*
G54D185*
X725006Y-32810D03*
Y-30842D03*
X845006Y-71990D03*
Y-70022D03*
X949942Y-30814D03*
Y-32782D03*
X974786Y-69994D03*
Y-71962D03*
X1008506Y-32810D03*
Y-30842D03*
X1078506Y-71990D03*
Y-70022D03*
X1228086Y-69994D03*
Y-71962D03*
X1233442Y-30944D03*
Y-32912D03*
X1295006Y-32940D03*
Y-30972D03*
X1335006Y-71990D03*
Y-70022D03*
X1484586Y-69994D03*
Y-71962D03*
X1519942Y-31074D03*
Y-33042D03*
X1579506Y-33070D03*
Y-31102D03*
X1589506Y-71990D03*
Y-70022D03*
X1739086Y-69994D03*
Y-71962D03*
X1804442Y-31204D03*
Y-33172D03*
G54D158*
X414519Y1253318D03*
Y1261804D03*
X512830Y1253318D03*
Y1261804D03*
X980085Y1486681D03*
Y1492797D03*
X1017867Y1486681D03*
Y1492797D03*
X1328693Y1253318D03*
Y1261804D03*
X1427004Y1253318D03*
Y1261804D03*
G54D248*
X1028012Y1622787D03*
G54D56*
X51043Y144095D03*
X57933Y66811D03*
X160295D03*
X153405Y144095D03*
X183435Y630650D03*
X190325Y374862D03*
X262657Y66811D03*
X255767Y144095D03*
X279360Y630650D03*
X286250Y374862D03*
X358129Y144095D03*
X365019Y66811D03*
X508130Y144095D03*
X515020Y66811D03*
X617382D03*
X610492Y144095D03*
X647411Y374862D03*
X640521Y630650D03*
X719744Y66811D03*
X712854Y144095D03*
X736446Y630650D03*
X743336Y374862D03*
X815216Y144095D03*
X822106Y66811D03*
X972106D03*
X965216Y144095D03*
X1074468Y66811D03*
X1067578Y144095D03*
X1104498Y374862D03*
X1097608Y630650D03*
X1169940Y144095D03*
X1176830Y66811D03*
X1200423Y374862D03*
X1193533Y630650D03*
X1272302Y144095D03*
X1279192Y66811D03*
X1429193D03*
X1422303Y144095D03*
X1531555Y66811D03*
X1524665Y144095D03*
X1561585Y374862D03*
X1554695Y630650D03*
X1627027Y144095D03*
X1633917Y66811D03*
X1657510Y374862D03*
X1650620Y630650D03*
X1736279Y66811D03*
X1729389Y144095D03*
G54D65*
G01X38230Y487982D02*
X35650D01*
G01X38230Y478982D02*
X35650D01*
G01X38230Y483982D02*
X35650D01*
G01X38230Y499982D02*
X35650D01*
G01X38230Y495982D02*
X35650D01*
G01X28399Y531726D02*
X25819D01*
G01X28399Y536726D02*
X25819D01*
G01X28399Y552726D02*
X25819D01*
G01X28399Y540726D02*
X25819D01*
G01X28399Y548726D02*
X25819D01*
G01X40009Y481467D02*
X41380Y482838D01*
Y483982D01*
G01X68944Y575841D02*
Y574164D01*
X67622Y572842D01*
G01X64408Y575757D02*
Y572975D01*
G01Y582747D02*
Y578907D01*
G01X67684Y599650D02*
Y597232D01*
G01X75684Y602800D02*
Y605443D01*
G01X83684Y602800D02*
Y605443D01*
G01X79684Y602800D02*
Y605443D01*
G01X87652Y578712D02*
Y580795D01*
X86788Y581659D01*
G01X87684Y602800D02*
Y605443D01*
G01X148061Y382600D02*
X151025D01*
G01X146400Y452225D02*
X149246D01*
X150703Y453682D01*
G01X151025Y463600D02*
X147520D01*
G01X144113Y558555D02*
Y554555D01*
G01D02*
X142024Y552466D01*
G01X144113Y562555D02*
Y558555D01*
G01X150425Y603600D02*
X147925D01*
G01X150425Y615600D02*
X147925D01*
G01X150393Y607588D02*
X147893D01*
G01X150425Y619600D02*
X147925D01*
G01X150425Y623600D02*
X147925D01*
G01X150425Y611600D02*
Y615600D01*
G01X230689Y392718D02*
X228267D01*
G01X230689Y408718D02*
X228267D01*
G01X230689Y400718D02*
X228267D01*
G01X230689Y404718D02*
X228267D01*
G01X230689Y396718D02*
X228267D01*
G01X230689Y412718D02*
X228267D01*
G01X221375Y462800D02*
Y464596D01*
X220349Y465622D01*
G01X221575Y562800D02*
X224104D01*
G01X224040Y558800D02*
X221575D01*
G01X248310Y542712D02*
X245362D01*
G01X247278Y620788D02*
Y618288D01*
G01X242102Y653821D02*
Y656321D01*
G01X299833Y321849D02*
X300676D01*
X302966Y324139D01*
G01X304543Y332017D02*
X301943D01*
G01X304543Y328867D02*
X301943D01*
G01X310628Y328844D02*
X310605Y328867D01*
X304543D01*
G01X323427Y321649D02*
X319857D01*
G01X318660Y541912D02*
Y539315D01*
G01X323285Y553287D02*
X320785D01*
G01X328945Y560043D02*
X325677Y556775D01*
X324291D01*
G01X321119Y622912D02*
X318660D01*
G01X389237Y373479D02*
Y371070D01*
G01X385237Y373479D02*
Y370976D01*
G01X391243Y482382D02*
X393652D01*
G01X391243Y478382D02*
X393746D01*
G01X485485Y531726D02*
X482905D01*
G01X485485Y536726D02*
X483226D01*
X482737Y537215D01*
G01X485485Y552726D02*
X482905D01*
G01X485485Y540726D02*
X482905D01*
G01X485485Y548726D02*
X482905D01*
G01X495316Y478982D02*
X492736D01*
G01X495316Y487982D02*
X492736D01*
G01X495316Y483982D02*
X492736D01*
G01X497095Y481467D02*
X498466Y482838D01*
Y483982D01*
G01X495316Y499982D02*
X492736D01*
G01X495316Y495982D02*
X492736D01*
G01X521494Y575757D02*
Y572975D01*
G01Y582747D02*
Y578907D01*
G01X526030Y575841D02*
Y574164D01*
X524708Y572842D01*
G01X532770Y602800D02*
Y605443D01*
G01X524770Y599650D02*
Y597232D01*
G01X536770Y602800D02*
Y605443D01*
G01X544738Y581659D02*
Y578712D01*
G01X540770Y602800D02*
Y605443D01*
G01X544770Y602800D02*
Y605443D01*
G01X603486Y452225D02*
X606332D01*
X607789Y453682D01*
G01X608111Y463600D02*
X604606D01*
G01X601199Y558555D02*
Y554555D01*
G01D02*
X599110Y552466D01*
G01X601199Y562555D02*
Y558555D01*
G01X605147Y382600D02*
X608111D01*
G01X607511Y603600D02*
X605011D01*
G01X607479Y607588D02*
X604979D01*
G01X607511Y615600D02*
X605011D01*
G01X607511Y611600D02*
Y615600D01*
G01Y619600D02*
X605011D01*
G01X607511Y623600D02*
X605011D01*
G01X687775Y392718D02*
X685353D01*
G01X687775Y408718D02*
X685353D01*
G01X687775Y400718D02*
X685353D01*
G01X687775Y404718D02*
X685353D01*
G01X687775Y396718D02*
X685353D01*
G01X687775Y412718D02*
X685353D01*
G01X678461Y462800D02*
Y464631D01*
X677481Y465611D01*
X675237D01*
G01X678661Y558800D02*
X681126D01*
G01X678661Y562800D02*
X681190D01*
G01X699188Y653821D02*
Y656321D01*
G01X705396Y542712D02*
X702448D01*
G01X704364Y620788D02*
Y618288D01*
G01X716623Y702463D02*
X713740D01*
X713439Y702162D01*
X713382D01*
G01X760407Y324494D02*
X757762Y321849D01*
X756919D01*
G01X761629Y332017D02*
X759029D01*
G01X761629Y328867D02*
X759029D01*
G01X767714Y328844D02*
X767691Y328867D01*
X761629D01*
G01X780513Y321649D02*
X776943D01*
G01X781517Y442498D02*
X778985D01*
G01X781549Y446510D02*
X778881D01*
G01X781549Y450510D02*
X779029D01*
G01X775746Y541912D02*
Y539315D01*
G01X780371Y553287D02*
X777708D01*
G01X778205Y622912D02*
X775746D01*
G01X791699Y442510D02*
Y446510D01*
G01Y450510D02*
X794173D01*
G01X791699Y446510D02*
Y450510D01*
G01X786031Y560043D02*
X784665Y561409D01*
Y564843D01*
G01X826804Y887166D02*
Y888166D01*
X828524Y889886D01*
Y890386D01*
G01X846098Y411662D02*
Y408715D01*
G01X864806Y414533D02*
Y416210D01*
X866128Y417532D01*
G01X848329Y461382D02*
X850733D01*
G01X848329Y473382D02*
X850832D01*
G01X848329Y465382D02*
X850748D01*
G01X848329Y477382D02*
X850738D01*
G01X848329Y482382D02*
X850909D01*
G01X872736Y385705D02*
Y383125D01*
G01X876736Y385705D02*
Y383125D01*
G01X869342Y407627D02*
Y411467D01*
G01Y414617D02*
Y417399D01*
G01X884736Y385705D02*
Y383125D01*
G01X893736Y385705D02*
Y383125D01*
G01X888736Y385705D02*
Y383125D01*
G01X942572Y531726D02*
X940449D01*
X939827Y531104D01*
G01X942572Y536726D02*
X939992D01*
G01X942572Y540726D02*
X939992D01*
G01X942572Y552726D02*
X939992D01*
G01X942572Y548726D02*
X939992D01*
G01X952403Y487982D02*
X949823D01*
G01X952403Y478982D02*
X950372D01*
X949876Y478486D01*
G01X952403Y483982D02*
X949823D01*
G01X955553D02*
Y482838D01*
X954182Y481467D01*
G01X952403Y499982D02*
X949823D01*
G01X952403Y495982D02*
X949823D01*
G01X978581Y575757D02*
Y572975D01*
G01X983117Y575841D02*
Y574164D01*
X981795Y572842D01*
G01X978581Y582747D02*
Y578907D01*
G01X989857Y602800D02*
Y605443D01*
G01X981857Y599650D02*
Y597232D01*
G01X993857Y602800D02*
Y605443D01*
G01X1001825Y581659D02*
Y578712D01*
G01X997857Y602800D02*
Y605443D01*
G01X1001857Y602800D02*
Y605443D01*
G01X1058286Y558555D02*
Y554555D01*
G01D02*
X1055885D01*
G01X1058286Y562555D02*
Y558555D01*
G01X1062234Y382600D02*
X1065198D01*
G01X1060573Y452225D02*
X1063419D01*
X1064876Y453682D01*
G01X1065198Y463600D02*
X1061693D01*
G01X1064598Y603600D02*
X1062098D01*
G01X1064598Y615600D02*
X1062098D01*
G01X1064598Y611600D02*
Y615600D01*
G01X1064566Y607588D02*
X1062066D01*
G01X1064598Y619600D02*
X1062098D01*
G01X1064598Y623600D02*
X1062098D01*
G01X1135548Y462800D02*
Y464632D01*
X1134629Y465551D01*
G01X1135748Y558800D02*
X1138213D01*
G01X1135748Y562800D02*
X1138277D01*
G01X1144862Y392718D02*
X1142440D01*
G01X1144862Y404718D02*
X1142440D01*
G01X1144862Y400718D02*
X1142440D01*
G01X1144862Y408718D02*
X1142440D01*
G01X1144862Y396718D02*
X1142440D01*
G01X1144862Y412718D02*
X1142440D01*
G01X1156275Y653821D02*
Y656321D01*
G01X1162483Y542712D02*
X1159535D01*
G01X1161451Y620788D02*
Y618288D01*
G01X1214006Y321849D02*
X1214849D01*
X1217139Y324139D01*
G01X1218716Y332017D02*
X1221337D01*
G01X1215776Y331072D02*
X1217490Y329358D01*
X1218225D01*
X1218716Y328867D01*
G01D02*
X1224778D01*
X1224801Y328844D01*
G01X1237600Y321649D02*
X1236325Y322924D01*
X1234100D01*
G01X1232833Y541912D02*
Y539315D01*
G01X1237458Y553287D02*
X1233865D01*
X1232149Y551571D01*
Y550137D01*
G01X1235292Y622912D02*
X1232833D01*
G01X1243118Y560043D02*
X1241752Y561409D01*
Y564843D01*
G01X1303410Y373479D02*
X1303158Y373227D01*
Y371043D01*
G01X1299410Y373479D02*
Y370976D01*
G01X1305416Y478382D02*
X1307919D01*
G01X1305416Y482382D02*
X1307825D01*
G01X1399659Y531726D02*
X1397079D01*
G01X1399659Y536726D02*
X1397079D01*
G01X1399659Y552726D02*
X1397079D01*
G01X1399659Y540726D02*
X1397079D01*
G01X1399659Y548726D02*
X1397079D01*
G01X1409490Y487982D02*
X1406910D01*
G01X1409490Y478982D02*
X1406910D01*
G01X1409490Y483982D02*
X1406910D01*
G01X1412640D02*
Y482838D01*
X1411269Y481467D01*
G01X1409490Y499982D02*
X1406910D01*
G01X1409490Y495982D02*
X1406910D01*
G01X1440204Y575841D02*
Y574164D01*
X1438882Y572842D01*
G01X1435668Y575757D02*
Y572975D01*
G01Y582747D02*
Y578907D01*
G01X1446944Y602800D02*
Y605443D01*
G01X1438944Y599650D02*
Y597232D01*
G01X1458912Y581659D02*
Y578712D01*
G01X1454944Y602800D02*
Y605443D01*
G01X1450944Y602800D02*
Y605443D01*
G01X1458944Y602800D02*
Y605443D01*
G01X1515373Y554555D02*
X1513284Y552466D01*
G01X1519321Y382600D02*
X1522285D01*
G01X1517660Y452225D02*
X1520506D01*
X1521963Y453682D01*
G01X1522285Y463600D02*
X1518780D01*
G01X1515373Y558555D02*
Y554555D01*
G01Y562555D02*
Y558555D01*
G01X1521685Y603600D02*
X1519185D01*
G01X1521685Y611600D02*
Y615600D01*
G01D02*
X1519185D01*
G01X1521653Y607588D02*
X1519153D01*
G01X1521685Y619600D02*
X1519185D01*
G01X1521685Y623600D02*
X1519185D01*
G01X1592635Y462800D02*
Y464140D01*
X1591443Y465332D01*
G01X1592835Y562800D02*
X1595364D01*
G01X1595300Y558800D02*
X1592835D01*
G01X1601949Y392718D02*
X1599527D01*
G01X1601949Y408718D02*
X1599527D01*
G01X1601949Y400718D02*
X1599527D01*
G01X1601949Y404718D02*
X1599527D01*
G01X1601949Y396718D02*
X1599527D01*
G01X1601949Y412718D02*
X1599527D01*
G01X1619570Y542712D02*
X1616622D01*
G01X1618538Y620788D02*
Y618288D01*
G01X1613362Y653821D02*
Y656321D01*
G01X1671093Y321849D02*
X1671936D01*
X1674226Y324139D01*
G01X1675803Y332017D02*
X1673203D01*
G01X1675803Y328867D02*
X1681865D01*
X1681888Y328844D01*
G01X1673203Y328867D02*
X1675803D01*
G01X1694687Y321649D02*
X1691117D01*
G01X1689920Y541912D02*
Y539315D01*
G01X1694545Y553287D02*
X1690952D01*
X1689236Y551571D01*
Y550137D01*
G01X1692379Y622912D02*
X1689920D01*
G01X1700205Y560043D02*
X1698839Y561409D01*
Y564843D01*
G01X1756497Y373479D02*
Y370976D01*
G01X1760497Y373479D02*
Y371070D01*
G01X1762503Y482382D02*
X1764912D01*
G01X1762503Y478382D02*
X1765006D01*
X51750Y617861D03*
X48207D03*
X44664D03*
X51750Y620661D03*
X48207D03*
X44664D03*
X55294Y617861D03*
Y620661D03*
X73872Y1348187D03*
X81752D03*
X73872Y1360099D03*
X81752D03*
X73872Y1384297D03*
Y1372385D03*
X81752Y1384297D03*
Y1372385D03*
X86112Y1348187D03*
X98352D03*
X93992D03*
X86112Y1360099D03*
X98352D03*
X93992D03*
X86112Y1384297D03*
Y1372385D03*
X98352Y1384297D03*
Y1372385D03*
X93992D03*
Y1384297D03*
X86112Y1396583D03*
X93992D03*
X98352D03*
X86112Y1408495D03*
X93992D03*
X98352D03*
X110592Y1348187D03*
X106232D03*
X110592Y1360099D03*
X106232D03*
X110592Y1384297D03*
X106232D03*
Y1372385D03*
X110592D03*
Y1396583D03*
X106232D03*
X110592Y1408495D03*
X106232D03*
X118472Y1348187D03*
X122832D03*
X130712D03*
X118472Y1360099D03*
X122832D03*
X130712D03*
X118472Y1384297D03*
Y1372385D03*
X122832Y1384297D03*
Y1372385D03*
X130712Y1384297D03*
Y1372385D03*
X118472Y1396583D03*
X122832D03*
X130712D03*
X118472Y1408495D03*
X122832D03*
X130712D03*
X143208Y1084547D03*
Y1092027D03*
X146948Y1077066D03*
Y1080806D03*
Y1084547D03*
Y1092027D03*
Y1088287D03*
X143208D03*
Y1095767D03*
X146948D03*
Y1103247D03*
X143208D03*
X146948Y1099507D03*
X143208D03*
X146948Y1106988D03*
X143208D03*
Y1110728D03*
Y1118208D03*
X146948Y1110728D03*
Y1118208D03*
Y1114468D03*
Y1121948D03*
X143208Y1114468D03*
Y1121948D03*
X146948Y1133169D03*
Y1140649D03*
X139468Y1136909D03*
X143208Y1125688D03*
Y1133169D03*
Y1140649D03*
X146948Y1125688D03*
Y1129429D03*
X143208D03*
X146948Y1136909D03*
X143208D03*
Y1144389D03*
Y1151870D03*
X146948Y1144389D03*
Y1151870D03*
Y1148129D03*
X143208D03*
X140707Y1170569D03*
X143208Y1159350D03*
X146949Y1166830D03*
X146948Y1159350D03*
X146947Y1170570D03*
X143207D03*
X148818Y1183661D03*
X140707Y1178050D03*
X145078Y1187401D03*
Y1183661D03*
X148818Y1187401D03*
X146947Y1174310D03*
Y1178051D03*
X143207D03*
X141337Y1191142D03*
X145078Y1194881D03*
Y1202362D03*
X148818Y1194881D03*
Y1202362D03*
X141337Y1198622D03*
X145078Y1198621D03*
Y1191141D03*
X148818D03*
Y1198621D03*
X145078Y1221062D03*
X148818D03*
X141337Y1206103D03*
X145078Y1209842D03*
Y1217322D03*
X148818Y1209842D03*
Y1217322D03*
X141337Y1213583D03*
Y1221063D03*
X148818Y1213582D03*
X145078D03*
Y1206102D03*
X148818D03*
Y1224803D03*
X145078Y1232283D03*
Y1236023D03*
X148818Y1232283D03*
Y1236023D03*
X145078Y1224803D03*
X141337Y1228542D03*
X145078Y1228543D03*
X148818D03*
Y1247243D03*
X145078D03*
X148818Y1254724D03*
X145078Y1250984D03*
X148818Y1243503D03*
Y1250984D03*
X141336Y1247242D03*
Y1239762D03*
X145078Y1243503D03*
X148818Y1239763D03*
X145078D03*
X135072Y1348187D03*
X142952D03*
X147312D03*
X135072Y1360099D03*
X147312D03*
X142952D03*
X135072Y1384297D03*
Y1372385D03*
X147312Y1384297D03*
Y1372385D03*
X142952Y1384297D03*
Y1372385D03*
X135072Y1396583D03*
X147312D03*
X142952D03*
X135072Y1408495D03*
X147312D03*
X142952D03*
X154429Y1073326D03*
X161909D03*
X165649D03*
X158169D03*
X150689D03*
X154429Y1092027D03*
X161909Y1077066D03*
X165649Y1080807D03*
Y1088287D03*
X161909D03*
Y1092027D03*
X150688Y1077066D03*
X154429D03*
X158169Y1080807D03*
X150689D03*
X158169Y1084547D03*
X150689D03*
X158169Y1088287D03*
X154429D03*
X150689D03*
X165649Y1084547D03*
Y1092027D03*
X158169D03*
X150689D03*
X165649Y1077066D03*
X161909Y1084547D03*
X158169Y1077066D03*
X154429Y1084547D03*
X161909Y1080807D03*
X154429D03*
X158169Y1099507D03*
X150689D03*
X158169Y1103247D03*
X150689D03*
X158169Y1106988D03*
X161909Y1095767D03*
X165649Y1099507D03*
Y1103247D03*
Y1106988D03*
X161909D03*
X154429D03*
X150689D03*
X154429Y1095767D03*
X165649D03*
X161909Y1103247D03*
X158169Y1095767D03*
X154429Y1103247D03*
X150689Y1095767D03*
X161909Y1099507D03*
X154429D03*
X158169Y1110728D03*
Y1114468D03*
X154429D03*
X150689D03*
X158169Y1118208D03*
Y1121948D03*
X154429D03*
X150689D03*
X165649Y1114468D03*
X161909D03*
Y1118208D03*
Y1121948D03*
X165649Y1110728D03*
X161909D03*
X154429D03*
Y1118208D03*
X150689Y1110728D03*
Y1118208D03*
X158169Y1133169D03*
X161909Y1140649D03*
X158169Y1125688D03*
Y1129429D03*
X154429D03*
X150689D03*
Y1136909D03*
X154429Y1140649D03*
X150689D03*
X165649D03*
X161909Y1125688D03*
X165649Y1129429D03*
X161909D03*
X165649Y1136909D03*
X158169Y1140649D03*
X154429Y1125688D03*
X150689D03*
Y1133169D03*
X165649D03*
X161909D03*
X154429D03*
X150689Y1151870D03*
X158169Y1155610D03*
X154429D03*
X150689D03*
X161909Y1144389D03*
Y1148129D03*
Y1151870D03*
Y1155610D03*
X150689Y1144389D03*
X158169Y1151869D03*
X154429D03*
X150689Y1148129D03*
X165649D03*
Y1144389D03*
Y1155610D03*
X150689Y1159350D03*
X158169Y1166830D03*
X154429D03*
X150688D03*
X154429Y1170570D03*
X150688D03*
X161909Y1159350D03*
X165649Y1166830D03*
Y1170570D03*
X160039Y1187401D03*
X156299Y1183661D03*
X152559D03*
X161909Y1174310D03*
Y1178051D03*
X165649Y1181791D03*
X161909D03*
X165649Y1178050D03*
Y1174310D03*
X158169D03*
X154429D03*
X150688Y1178051D03*
Y1174310D03*
X156299Y1179921D03*
X160039Y1183661D03*
X163779D03*
X156299Y1187401D03*
X163779D03*
X152559D03*
X160039Y1176180D03*
X156299D03*
X160039Y1194881D03*
Y1202362D03*
X156299Y1198621D03*
X152559D03*
X163779D03*
X160039D03*
X152559Y1191141D03*
X156299D03*
X160039D03*
X163779D03*
X156299Y1202362D03*
Y1194881D03*
X152559Y1202362D03*
Y1194881D03*
X163779D03*
Y1202362D03*
X160039Y1206102D03*
X156299D03*
X152559D03*
X163779D03*
X160039Y1209842D03*
Y1217322D03*
X156299Y1213582D03*
X152559D03*
X160039Y1221062D03*
X156299D03*
X152559D03*
X163779Y1213582D03*
Y1221062D03*
X160039Y1213582D03*
X156299Y1217322D03*
Y1209842D03*
X152559D03*
X163779D03*
Y1217322D03*
X152559D03*
X160039Y1228543D03*
X152559D03*
X160039Y1224803D03*
X152559D03*
X156299Y1232283D03*
Y1236023D03*
X163779D03*
Y1232283D03*
X160039Y1236023D03*
X163779Y1224803D03*
X156299D03*
Y1228543D03*
X163779D03*
X160039Y1232283D03*
X152559Y1236023D03*
Y1232283D03*
Y1250984D03*
Y1254724D03*
X160039D03*
X156299Y1243503D03*
X160039Y1239763D03*
X152559D03*
Y1243503D03*
X156299Y1250984D03*
X160039Y1247243D03*
Y1243503D03*
X152559Y1247243D03*
X156299Y1239763D03*
X163779Y1250984D03*
X156299Y1254724D03*
X163779D03*
Y1239763D03*
X156299Y1247243D03*
X163779Y1243503D03*
X160039Y1250984D03*
X163779Y1247243D03*
X152559Y1258465D03*
X160039D03*
X159552Y1348187D03*
X155192D03*
X159552Y1360099D03*
X155192D03*
X159552Y1372385D03*
Y1384297D03*
X155192D03*
Y1372385D03*
X159552Y1396583D03*
X155192D03*
X159552Y1408495D03*
X155192D03*
X174998Y1071455D03*
X182479D03*
X178740Y1075196D03*
X171259D03*
X174999D03*
X182480D03*
X178740Y1090157D03*
Y1078936D03*
X174999Y1086417D03*
Y1082677D03*
X171259Y1078936D03*
X174999Y1090157D03*
X171259D03*
X182480Y1086417D03*
Y1082677D03*
Y1090157D03*
X174999Y1078936D03*
X182480D03*
X178740Y1082677D03*
Y1086417D03*
X169389Y1084547D03*
Y1080807D03*
X174999Y1093897D03*
X182480D03*
X178740D03*
Y1097637D03*
X174999Y1101377D03*
X169389Y1106988D03*
X171259Y1093897D03*
Y1097637D03*
X174999Y1105117D03*
X182480Y1101377D03*
Y1105117D03*
Y1097637D03*
X174999D03*
X178740Y1101376D03*
Y1105117D03*
X169389Y1103247D03*
X174999Y1108858D03*
X178740D03*
X169389Y1121948D03*
X176870Y1114468D03*
Y1118208D03*
Y1121948D03*
X178740Y1112598D03*
X173129Y1110728D03*
X169389D03*
X180610Y1114468D03*
Y1118208D03*
Y1121948D03*
X182480Y1112598D03*
Y1108858D03*
X180610Y1136909D03*
X173129Y1133169D03*
X169389D03*
X176870Y1140649D03*
Y1125688D03*
Y1129429D03*
Y1133169D03*
Y1136909D03*
X173129Y1140649D03*
X169389D03*
X173129Y1129428D03*
X169389D03*
X180610Y1140649D03*
Y1125688D03*
Y1129429D03*
Y1133169D03*
X173129Y1136909D03*
X169389D03*
X180610Y1148129D03*
X173129Y1144389D03*
X169389D03*
X173129Y1148129D03*
Y1155610D03*
Y1151870D03*
X180610Y1155610D03*
Y1151870D03*
Y1144389D03*
X176870Y1151870D03*
Y1148129D03*
Y1144389D03*
X169389Y1151870D03*
Y1148129D03*
X176870Y1170570D03*
X173129Y1159350D03*
Y1166830D03*
Y1170570D03*
X180610Y1166830D03*
Y1159350D03*
Y1170570D03*
X176870Y1166830D03*
Y1159350D03*
X169389D03*
X180610Y1174310D03*
Y1181791D03*
X173129Y1174310D03*
Y1178051D03*
Y1181791D03*
X171259Y1187401D03*
X174999D03*
X180610Y1178051D03*
X167519Y1183661D03*
X178740Y1187401D03*
X182480D03*
X176870Y1185531D03*
X173129D03*
X167519Y1187401D03*
X176870Y1174310D03*
Y1178051D03*
Y1181791D03*
X171259Y1202362D03*
X167519Y1198621D03*
X171259Y1194881D03*
X174999Y1202362D03*
Y1194881D03*
X167519Y1191141D03*
X178740D03*
Y1194881D03*
Y1198621D03*
Y1202362D03*
X182480Y1191141D03*
Y1198621D03*
Y1202362D03*
X174999Y1198621D03*
Y1191141D03*
X167519Y1194881D03*
X171259Y1198621D03*
Y1191141D03*
X167519Y1202362D03*
X171259Y1209842D03*
X174999Y1217322D03*
X171259Y1221062D03*
X174999D03*
X171259Y1217322D03*
X174999Y1209842D03*
X167519Y1213582D03*
Y1206102D03*
Y1221062D03*
X178740Y1206102D03*
Y1209842D03*
Y1213582D03*
Y1221062D03*
X182480D03*
X178740Y1217322D03*
X182480Y1206102D03*
Y1209842D03*
Y1213582D03*
Y1217322D03*
X167519Y1209842D03*
X171259Y1213582D03*
Y1206102D03*
X174999D03*
X167519Y1217322D03*
X174999Y1213582D03*
X178740Y1228543D03*
X171259Y1224803D03*
X182480Y1236023D03*
Y1232283D03*
X174999D03*
X171259Y1228543D03*
X178740Y1224803D03*
Y1232283D03*
Y1236023D03*
X174999Y1228543D03*
X171259Y1232283D03*
X174999Y1224803D03*
X171259Y1236023D03*
X182480Y1228543D03*
Y1224803D03*
X167519Y1228543D03*
Y1224803D03*
X174999Y1236023D03*
X167519Y1232283D03*
Y1236023D03*
Y1254724D03*
X182480Y1239763D03*
Y1243503D03*
Y1247243D03*
X171259Y1250984D03*
X178740D03*
Y1239763D03*
X174999Y1243503D03*
Y1247243D03*
X178740Y1254724D03*
X171259D03*
X174999Y1239763D03*
X171259D03*
X167519D03*
Y1243503D03*
Y1247243D03*
Y1250984D03*
X178740Y1247243D03*
X182480Y1254724D03*
Y1250984D03*
X171259Y1247243D03*
X174999Y1250984D03*
X171259Y1243503D03*
X174999Y1254724D03*
X178740Y1243503D03*
X175000Y1258465D03*
X182480D03*
X167519D03*
X167432Y1348187D03*
X171792D03*
X179672D03*
X167432Y1360099D03*
X171792D03*
X179672D03*
X167432Y1384297D03*
Y1372385D03*
X171792Y1384297D03*
Y1372385D03*
X179672Y1384297D03*
Y1372385D03*
X171792Y1396583D03*
X179672D03*
X167432D03*
Y1408495D03*
X171792D03*
X179672D03*
X197439Y1071455D03*
X189959D03*
X186220Y1075196D03*
X193700D03*
X189960D03*
X197440D03*
X193700Y1090157D03*
X189960Y1086417D03*
Y1082677D03*
X193700Y1078936D03*
X186220D03*
X189960Y1090157D03*
X186220D03*
X197440Y1086417D03*
Y1082677D03*
Y1090157D03*
X186220Y1082677D03*
Y1086417D03*
X189960Y1078936D03*
X193700Y1086417D03*
Y1082677D03*
X197440Y1078936D03*
X193700Y1105117D03*
X197440Y1093897D03*
X189960Y1097637D03*
X186220Y1105117D03*
X197440Y1097637D03*
X193700Y1093897D03*
X189960Y1101377D03*
X186220Y1097637D03*
X189960Y1105117D03*
X186220Y1093897D03*
X193700Y1097637D03*
X197440Y1101377D03*
Y1105117D03*
X193700Y1101376D03*
X186220D03*
X189960Y1093897D03*
X195570Y1121948D03*
X191830Y1118208D03*
X188090D03*
X184350D03*
X191830Y1121948D03*
X188090D03*
X184350D03*
X195570Y1118208D03*
X186220Y1108858D03*
X189960D03*
X193700D03*
X197440D03*
X188090Y1114468D03*
X184350D03*
X191830D03*
X195570D03*
X191830Y1125688D03*
X188090D03*
X184350D03*
X188090Y1129429D03*
X184350D03*
X188090Y1133169D03*
X184350D03*
X188090Y1136909D03*
Y1140649D03*
X184350D03*
X195570Y1133169D03*
Y1129429D03*
Y1125688D03*
Y1136909D03*
X191830Y1140649D03*
Y1136909D03*
X195570Y1140649D03*
X184350Y1136909D03*
X191830Y1133169D03*
Y1129429D03*
X188090Y1144389D03*
Y1151870D03*
X191830Y1155610D03*
Y1148129D03*
X195570Y1151869D03*
Y1144389D03*
X191830D03*
Y1151869D03*
X195570Y1148129D03*
Y1155610D03*
X184350Y1144389D03*
X188090Y1155610D03*
X184350Y1151870D03*
X188090Y1148129D03*
Y1159350D03*
Y1170570D03*
X191830Y1166830D03*
X195570Y1159350D03*
Y1170570D03*
X191830Y1159350D03*
Y1170570D03*
X195570Y1166830D03*
X184350Y1159350D03*
Y1170570D03*
X188090Y1166830D03*
Y1185531D03*
Y1178051D03*
X195570Y1189271D03*
X191830Y1181791D03*
Y1174310D03*
X195570Y1185531D03*
Y1178051D03*
X191830Y1185531D03*
Y1178051D03*
X195570Y1181791D03*
Y1174310D03*
X184350Y1185531D03*
X188090Y1181791D03*
Y1174310D03*
X184350Y1178051D03*
X188090Y1193011D03*
Y1196751D03*
Y1200491D03*
Y1204232D03*
X191830D03*
Y1196751D03*
Y1200491D03*
X184350Y1193011D03*
Y1196751D03*
X195570Y1200491D03*
Y1196751D03*
Y1193011D03*
Y1204232D03*
X186220Y1198621D03*
X191830Y1193011D03*
X193700Y1209842D03*
X191830Y1207972D03*
X189960Y1209842D03*
X195570Y1207972D03*
X193700Y1213582D03*
X191830Y1219192D03*
X186220Y1221062D03*
X189960D03*
X193700D03*
X197440D03*
X186220Y1206102D03*
Y1209842D03*
Y1213582D03*
X197440Y1209842D03*
X195570Y1215452D03*
X197440Y1217322D03*
X186220D03*
X189960D03*
Y1213582D03*
X197440Y1236023D03*
X186220Y1224803D03*
X193700Y1228543D03*
X197440Y1232283D03*
Y1224803D03*
X193700Y1232283D03*
X189960Y1228543D03*
X186220Y1232283D03*
X189960Y1224803D03*
X193700Y1236023D03*
X186220D03*
X197440Y1228543D03*
X189960Y1236023D03*
X186220Y1228543D03*
X193700Y1224803D03*
X189960Y1232283D03*
X197440Y1239763D03*
Y1247243D03*
Y1243503D03*
X193700Y1254724D03*
X186220D03*
X193700Y1239763D03*
X186220D03*
X189960D03*
X186220Y1250984D03*
X189960Y1247243D03*
X193700Y1250984D03*
X189960Y1243503D03*
X197440Y1254724D03*
Y1250984D03*
X193700Y1247243D03*
Y1243503D03*
X189960Y1254724D03*
Y1250984D03*
X186220Y1247243D03*
Y1243503D03*
X189960Y1258465D03*
X197441D03*
X184032Y1348187D03*
X191912D03*
X196272D03*
X184032Y1360099D03*
X196272D03*
X191912D03*
X184032Y1384297D03*
Y1372385D03*
X196272Y1384297D03*
Y1372385D03*
X191912Y1384297D03*
Y1372385D03*
X184032Y1396583D03*
X191912D03*
X196272D03*
X184032Y1408495D03*
X191912D03*
X196272D03*
X201181Y1075196D03*
X208661D03*
X204920Y1071455D03*
X212400D03*
X204921Y1075196D03*
X212401D03*
X208661Y1078936D03*
X204921Y1090157D03*
X212401Y1086417D03*
Y1082677D03*
Y1090157D03*
X208661D03*
X201181D03*
X204921Y1086417D03*
Y1082677D03*
X201181Y1078936D03*
X212401D03*
X208661Y1082677D03*
X201181D03*
Y1086417D03*
X208661D03*
X204921Y1078936D03*
Y1097637D03*
X208661Y1101376D03*
X212401Y1097637D03*
X204921Y1101377D03*
X208661Y1097637D03*
X201181D03*
X204921Y1105117D03*
X212401Y1101377D03*
Y1105117D03*
X201181Y1093897D03*
X208661D03*
Y1105117D03*
X212401Y1093897D03*
X201181Y1101376D03*
X204921Y1093897D03*
X201181Y1105117D03*
X199311Y1118208D03*
Y1121948D03*
X206791Y1118208D03*
X203051D03*
Y1121948D03*
X206791D03*
X210531Y1118208D03*
X214271Y1110728D03*
Y1114468D03*
X210531Y1121948D03*
X214271Y1118208D03*
Y1121948D03*
X201181Y1108858D03*
X204921D03*
X208661D03*
X212401D03*
X203051Y1114468D03*
X199311D03*
X206791D03*
X210531D03*
X199311Y1140649D03*
X203051D03*
X206791D03*
X199311Y1125688D03*
X203051D03*
X206791D03*
Y1133169D03*
X203051D03*
X199311D03*
X210531D03*
Y1140649D03*
X214271D03*
Y1125688D03*
X210531D03*
X214271Y1133169D03*
X206791Y1136909D03*
X203051D03*
X199311D03*
X214271D03*
X210531D03*
X199311Y1129429D03*
X206791D03*
X214271D03*
X210531D03*
X203051D03*
Y1148129D03*
X199311D03*
X206791D03*
X214271D03*
X210531D03*
X199311Y1155610D03*
X206791D03*
X214271D03*
X210531D03*
X203051D03*
X206791Y1144389D03*
X203051D03*
X199311D03*
X214271D03*
X210531D03*
X214271Y1151870D03*
X210531D03*
X206791D03*
X203051D03*
X199311D03*
X206791Y1166830D03*
X203051Y1159350D03*
X199311Y1166830D03*
X203051Y1170570D03*
X214271Y1166830D03*
X210531Y1159350D03*
Y1170570D03*
X214271D03*
X210531Y1166830D03*
X214271Y1159350D03*
X206791Y1170570D03*
X203051Y1166830D03*
X199311Y1170570D03*
X206791Y1159350D03*
X199311D03*
X206791Y1181791D03*
X203051D03*
X199311D03*
X206791Y1189271D03*
X203051D03*
X199311D03*
X214271Y1181791D03*
X210531D03*
X214271Y1189271D03*
X210531D03*
X199311Y1174310D03*
X206791D03*
X214271D03*
X203051D03*
X210531D03*
X203051Y1185531D03*
X199311D03*
X206791D03*
X214271D03*
X210531D03*
X206791Y1178051D03*
X203051D03*
X199311D03*
X214271D03*
X210531D03*
X206791Y1196751D03*
X203051D03*
X199311D03*
Y1204232D03*
X203051D03*
X206791D03*
X214271Y1196751D03*
X210531D03*
Y1204232D03*
X214271D03*
Y1193011D03*
X210531D03*
X199311D03*
X203051D03*
X206791D03*
X214271Y1200491D03*
X210531D03*
X199311D03*
X206791D03*
X203051D03*
X206791Y1207972D03*
X203051D03*
X199311D03*
X210531D03*
Y1211712D03*
X214271Y1207972D03*
X212401Y1221062D03*
X208661D03*
X204921D03*
X201181D03*
Y1213582D03*
X214271Y1211712D03*
X208661Y1213582D03*
X203051Y1215452D03*
X214271D03*
X201181Y1217322D03*
X208661D03*
X210531Y1215452D03*
X204921Y1213582D03*
Y1232283D03*
X201181Y1224803D03*
X212401Y1232283D03*
X208661Y1228543D03*
X212401D03*
Y1224803D03*
X208661Y1232283D03*
X204921Y1228543D03*
X201181Y1232283D03*
X204921Y1224803D03*
X201181Y1236023D03*
X208661D03*
X212401D03*
X208661Y1224803D03*
X201181Y1228543D03*
X204921Y1236023D03*
X208661Y1250984D03*
X201181Y1239763D03*
X212401D03*
Y1247243D03*
Y1243503D03*
X201181Y1254724D03*
X208661Y1239763D03*
X204921D03*
Y1243503D03*
X201181Y1250984D03*
X204921Y1247243D03*
X208661Y1254724D03*
Y1243503D03*
X204921Y1250984D03*
X208661Y1247243D03*
X212401Y1254724D03*
X201181Y1243503D03*
X212401Y1250984D03*
X201181Y1247243D03*
X204921Y1254724D03*
X212401Y1258465D03*
X204921D03*
X204152Y1348187D03*
Y1360099D03*
Y1384297D03*
Y1372385D03*
Y1396583D03*
Y1408495D03*
X213969Y1445013D03*
Y1453293D03*
Y1456013D03*
Y1464293D03*
X219880Y1071455D03*
X227361D03*
X223622Y1075196D03*
X231102D03*
X216141D03*
X227362D03*
X219881D03*
X227362Y1086417D03*
Y1082677D03*
Y1090157D03*
X223622D03*
X219881Y1086417D03*
Y1082677D03*
Y1090157D03*
X223622Y1078936D03*
X231102Y1090157D03*
Y1078936D03*
X216141Y1090157D03*
Y1078936D03*
X219881D03*
X216141Y1086417D03*
X231102Y1082677D03*
Y1086417D03*
X223622Y1082677D03*
X227362Y1078936D03*
X216141Y1082677D03*
X223622Y1086417D03*
X216141Y1101376D03*
X231102D03*
X227362Y1093897D03*
X219881Y1097637D03*
X223621Y1101376D03*
Y1105117D03*
X223622Y1093897D03*
X231102D03*
Y1097637D03*
X227362Y1101377D03*
Y1105117D03*
X219881Y1101377D03*
Y1105117D03*
X223622Y1097637D03*
X216141D03*
Y1093897D03*
Y1105117D03*
X219881Y1093897D03*
X227362Y1097637D03*
X231102Y1105117D03*
X225492Y1118208D03*
Y1121948D03*
X218011Y1118208D03*
X221751D03*
X218011Y1121948D03*
X221751D03*
X229232D03*
Y1118208D03*
Y1114468D03*
X216141Y1108858D03*
X219881D03*
X223622D03*
X227362D03*
X231102D03*
X225492Y1114468D03*
X221752D03*
X218011D03*
X225492Y1133169D03*
Y1140649D03*
Y1125688D03*
X218011Y1140649D03*
X221751D03*
X218011Y1125688D03*
X221751D03*
Y1133169D03*
X218011D03*
X229330Y1132677D03*
X229232Y1140649D03*
Y1125688D03*
X225492Y1136909D03*
X221751D03*
X218011D03*
X229232D03*
Y1129429D03*
X218011D03*
X221751D03*
X225492D03*
Y1148129D03*
X221751D03*
X218011D03*
X229232D03*
X221751Y1155610D03*
X229232D03*
X218011D03*
X225492D03*
Y1144389D03*
X221751D03*
X218011D03*
X229232D03*
Y1151870D03*
X221752D03*
X218011D03*
X225492D03*
Y1170570D03*
Y1159350D03*
X218011Y1170570D03*
X221752Y1166830D03*
X218011Y1159350D03*
X229232Y1166830D03*
X225492D03*
X221751Y1170570D03*
X218011Y1166830D03*
X221751Y1159350D03*
X229232Y1170570D03*
Y1159350D03*
X225492Y1181791D03*
Y1189271D03*
X221751Y1181791D03*
X218011D03*
X221751Y1189271D03*
X218011D03*
X229232Y1181791D03*
Y1189271D03*
X221751Y1174310D03*
X229232D03*
X225492D03*
X218011D03*
X225492Y1185531D03*
X218011D03*
X221751D03*
X229232D03*
X225492Y1178051D03*
X221751D03*
X218011D03*
X229232D03*
X218011Y1204232D03*
X229232Y1196751D03*
Y1204232D03*
X225492Y1196751D03*
Y1204232D03*
X221751D03*
Y1196751D03*
X218011D03*
Y1193011D03*
X221751D03*
X225492D03*
X229232D03*
X218011Y1200491D03*
X221751D03*
X225492D03*
X229232D03*
X225492Y1207972D03*
X218011Y1211712D03*
X221751Y1207972D03*
X218011D03*
X229232D03*
X231102Y1221062D03*
X227362D03*
X219881Y1217322D03*
X223622Y1221062D03*
X219881D03*
X216141D03*
X218011Y1215452D03*
X229232Y1211712D03*
Y1215452D03*
X225492Y1211712D03*
X221752D03*
Y1215452D03*
X231102Y1228543D03*
Y1224803D03*
X219881Y1232283D03*
Y1236023D03*
X227362Y1228543D03*
Y1224803D03*
X223622Y1232283D03*
X219881Y1228543D03*
Y1224803D03*
X223622Y1236023D03*
X231102Y1232283D03*
Y1236023D03*
X216141Y1232283D03*
Y1236023D03*
Y1224803D03*
X223622D03*
X227362Y1232283D03*
X223622Y1228543D03*
X216141D03*
X227362Y1236023D03*
X223622Y1254724D03*
X231102D03*
X223622Y1239763D03*
X231102D03*
X227362Y1243503D03*
Y1247243D03*
X219881Y1239763D03*
X223622Y1250984D03*
X219881Y1247243D03*
Y1243503D03*
X231102Y1250984D03*
X227362Y1239763D03*
X216141Y1250984D03*
Y1254724D03*
Y1239763D03*
X231102Y1243503D03*
Y1247243D03*
X223622Y1243503D03*
X216141Y1247243D03*
X223622D03*
X216141Y1243503D03*
X219881Y1250984D03*
Y1254724D03*
X227362D03*
Y1250984D03*
X219882Y1258465D03*
X227363D03*
X227249Y1445013D03*
Y1464293D03*
Y1456013D03*
Y1453293D03*
X246062Y1075196D03*
X234841Y1071454D03*
X242321Y1071455D03*
X238582Y1075196D03*
X234841Y1075195D03*
X242321Y1075196D03*
X234842Y1090157D03*
X246062D03*
Y1078936D03*
X238582D03*
Y1090157D03*
X242322Y1082677D03*
Y1086417D03*
X234842Y1082677D03*
Y1086417D03*
X242322Y1090157D03*
X242321Y1078936D03*
X246061Y1082677D03*
X238581Y1082676D03*
X234841Y1078935D03*
X246061Y1086417D03*
X238581Y1086416D03*
X246062Y1097637D03*
Y1093897D03*
X242322Y1105117D03*
X234842Y1101377D03*
X238582Y1097637D03*
Y1093897D03*
X242322Y1101377D03*
X234842Y1105117D03*
X234841Y1093897D03*
X246062Y1105117D03*
X242321Y1097637D03*
X234841D03*
X238582Y1101376D03*
X246062D03*
X238582Y1105117D03*
X242321Y1093897D03*
X236712Y1121948D03*
X240452D03*
X244192D03*
X234842Y1108858D03*
X238582D03*
X242322D03*
X246062D03*
X240452Y1114468D03*
X244192D03*
X236712Y1118208D03*
X244192D03*
X236712Y1114468D03*
X240452Y1118208D03*
X236712Y1133464D03*
X240452Y1133169D03*
X236712Y1140649D03*
X240452D03*
X236712Y1125688D03*
X240452D03*
X244192Y1133169D03*
Y1140649D03*
Y1125688D03*
X240452Y1136909D03*
X236712D03*
X244192D03*
Y1129429D03*
X240452D03*
X236712D03*
Y1148129D03*
X240452D03*
X244192D03*
X240452Y1155610D03*
X236712D03*
X244192D03*
X240452Y1151869D03*
X236712D03*
X244192D03*
X240452Y1144389D03*
X236712D03*
X244192D03*
X240452Y1166830D03*
X236712Y1170570D03*
Y1159350D03*
X244192Y1170570D03*
Y1159350D03*
X236712Y1166830D03*
X240452Y1170570D03*
Y1159350D03*
X244192Y1166830D03*
X240452Y1181791D03*
X236712D03*
Y1189271D03*
X240452D03*
X244192Y1181791D03*
Y1189271D03*
X240452Y1174310D03*
X236712D03*
X244192D03*
X240452Y1185531D03*
X236712D03*
X244192D03*
X240452Y1178051D03*
X236712D03*
X244192D03*
X240452Y1204232D03*
X236712D03*
Y1196751D03*
X240452D03*
X244192Y1204232D03*
Y1196751D03*
X240452Y1193011D03*
X236712D03*
X244192D03*
X236712Y1200491D03*
X244192D03*
X240452D03*
X246062Y1221062D03*
X240452Y1207972D03*
Y1211712D03*
X242322Y1221062D03*
X244192Y1211712D03*
Y1207972D03*
X236712D03*
X234842Y1221062D03*
X238582D03*
X244192Y1215452D03*
X240452D03*
X242322Y1217322D03*
X236712Y1211712D03*
Y1215452D03*
X238582Y1217322D03*
Y1224803D03*
Y1228543D03*
X242322Y1236023D03*
Y1232283D03*
X246062Y1228543D03*
X234842Y1232283D03*
X246062Y1224803D03*
Y1232283D03*
Y1236023D03*
X238582Y1232283D03*
X234842Y1228543D03*
Y1224803D03*
X238582Y1236023D03*
X242322Y1228543D03*
Y1224803D03*
X234842Y1236023D03*
X246062Y1254724D03*
Y1239763D03*
X238582Y1254724D03*
Y1239763D03*
X234842D03*
X238582Y1250984D03*
X234842Y1243503D03*
Y1247243D03*
X242322Y1243503D03*
Y1239763D03*
Y1247243D03*
X246062Y1250984D03*
X238582Y1247243D03*
X246062Y1243503D03*
X242322Y1250984D03*
X234842D03*
X246062Y1247243D03*
X234842Y1254724D03*
X238582Y1243503D03*
X242322Y1254724D03*
X234842Y1258465D03*
X242322D03*
X239383Y1348187D03*
X247263D03*
Y1360099D03*
X239383D03*
X247263Y1384297D03*
Y1372385D03*
X239383Y1384297D03*
Y1372385D03*
X253543Y1075196D03*
X261023D03*
X249802Y1071455D03*
X257282D03*
X249802Y1075196D03*
X257282D03*
X253543Y1090157D03*
X249803Y1082677D03*
Y1090157D03*
Y1086417D03*
X253543Y1078936D03*
X257283Y1090157D03*
Y1082677D03*
Y1086417D03*
X261023Y1090157D03*
Y1078936D03*
X249802D03*
X261022Y1086417D03*
X253542Y1082676D03*
X257282Y1078936D03*
X253542Y1086416D03*
X261022Y1082677D03*
X249803Y1105117D03*
Y1101377D03*
X253543Y1093897D03*
X257283Y1101377D03*
X253543Y1097637D03*
X257283Y1105117D03*
X261023Y1093897D03*
Y1097637D03*
X249802D03*
X257282D03*
X249802Y1093897D03*
X253543Y1105117D03*
Y1101376D03*
X257282Y1093897D03*
X261023Y1105117D03*
Y1101376D03*
X255413Y1121948D03*
X251673D03*
X247933D03*
X262893D03*
X259153D03*
X249803Y1108858D03*
X253543D03*
X257283D03*
X261023D03*
X262893Y1118208D03*
X259153Y1114468D03*
X262893D03*
X255413Y1118208D03*
Y1114468D03*
X247933D03*
X259153Y1118208D03*
X251673Y1114468D03*
X247933Y1118208D03*
X251673D03*
X247933Y1133169D03*
X251673D03*
X255413D03*
X247933Y1140649D03*
X251673D03*
X255413D03*
X247933Y1125688D03*
X251673D03*
X255413D03*
X259153Y1133169D03*
X262893D03*
Y1140649D03*
X259153Y1125688D03*
X262893D03*
X259153Y1140649D03*
X255413Y1136909D03*
X251673D03*
X247933D03*
X259153D03*
X262893D03*
X247933Y1129429D03*
X259153D03*
X262893D03*
X255413D03*
X251673D03*
X259153Y1148129D03*
X262893D03*
Y1155610D03*
X247933Y1148129D03*
X251673D03*
X255413D03*
X247933Y1155610D03*
X255413D03*
X251673D03*
X259153D03*
X251673Y1144389D03*
X247933D03*
X255413D03*
X259153Y1151869D03*
X262893D03*
X247933D03*
X255413D03*
X251673D03*
X262893Y1144389D03*
X259153D03*
X262893Y1166830D03*
X251673Y1170570D03*
X255413Y1166830D03*
X247933D03*
X251673Y1159350D03*
X259153D03*
Y1170570D03*
X251673Y1166830D03*
X255413Y1170570D03*
X247933D03*
X255413Y1159350D03*
X247933D03*
X259153Y1166830D03*
X262893Y1170570D03*
Y1159350D03*
X247933Y1181791D03*
X251673D03*
X255413D03*
X247933Y1189271D03*
X251673D03*
X255413D03*
X262893D03*
Y1174310D03*
X259153Y1181791D03*
X262893D03*
X259153Y1189271D03*
X255413Y1174310D03*
X247933D03*
X251673D03*
X259153D03*
X247933Y1185531D03*
X255413D03*
X251673D03*
X259153D03*
X262893D03*
X251673Y1178051D03*
X247933D03*
X255413D03*
X259153D03*
X262893D03*
X247933Y1204232D03*
X255413D03*
X251673D03*
X247933Y1196751D03*
X251673D03*
X255413D03*
X259153Y1204232D03*
X262893D03*
X259153Y1196751D03*
X262893D03*
X251673Y1193011D03*
X255413D03*
X247933D03*
X262893D03*
X259153D03*
Y1200491D03*
X262893D03*
X251673D03*
X247933D03*
X255413D03*
X247933Y1207972D03*
X251673D03*
X255413Y1211712D03*
Y1207972D03*
X249803Y1221062D03*
X253543D03*
X262893Y1207972D03*
X259153D03*
X262893Y1211712D03*
X259153D03*
X261023Y1221062D03*
X257283D03*
X255413Y1215452D03*
X262893D03*
X247932Y1215451D03*
X259153Y1215452D03*
X251673D03*
X247932Y1211711D03*
X251673D03*
X261023Y1224803D03*
X253543Y1228543D03*
X249803Y1232283D03*
X257283D03*
Y1236023D03*
X249803Y1228543D03*
X257283D03*
X249803Y1224803D03*
X253543Y1236023D03*
X257283Y1224803D03*
X261023Y1236023D03*
X253543Y1232283D03*
X261023D03*
Y1228543D03*
X253543Y1224803D03*
X249803Y1236023D03*
Y1243503D03*
X253543Y1250984D03*
Y1254724D03*
X249803Y1247243D03*
X253543Y1239763D03*
X249803D03*
X257283Y1243503D03*
Y1247243D03*
X261023Y1250984D03*
Y1239763D03*
Y1254724D03*
X257283Y1239763D03*
X261023Y1243503D03*
X249803Y1250984D03*
X261023Y1247243D03*
X257283Y1250984D03*
X253543Y1247243D03*
X257283Y1254724D03*
X249803D03*
X253543Y1243503D03*
X249803Y1258465D03*
X257283D03*
X263863Y1348187D03*
X259503D03*
X251623D03*
X263863Y1360099D03*
X259503D03*
X251623D03*
X263863Y1384297D03*
Y1372385D03*
X259503Y1384297D03*
Y1372385D03*
X251623D03*
Y1384297D03*
X263863Y1396583D03*
X259503D03*
X251623D03*
X263863Y1408495D03*
X259503D03*
X251623D03*
X279723Y1071455D03*
X264762D03*
X272243D03*
X268503Y1075196D03*
X275984D03*
X279723D03*
X264762D03*
X272243D03*
X279724Y1082677D03*
Y1086417D03*
Y1090157D03*
X275984Y1078936D03*
X272244Y1082677D03*
X275984Y1090157D03*
X272244Y1086417D03*
X264763Y1082677D03*
X268503Y1078936D03*
Y1090157D03*
X264763Y1086417D03*
X272244Y1090157D03*
X264763D03*
X275982Y1082677D03*
Y1086417D03*
X268502Y1082676D03*
X272243Y1078936D03*
X268502Y1086416D03*
X279723Y1078936D03*
X264762D03*
X268503Y1093897D03*
Y1097637D03*
X272244Y1101377D03*
Y1105117D03*
X279724Y1101377D03*
X275984Y1097637D03*
X279724Y1105117D03*
X275984Y1093897D03*
X264763Y1101377D03*
Y1105117D03*
X264762Y1097637D03*
X268503Y1105117D03*
X272243Y1097637D03*
X275984Y1105117D03*
X279723Y1093897D03*
X272243D03*
X279723Y1097637D03*
X268503Y1101376D03*
X275984D03*
X264762Y1093897D03*
X274114Y1118208D03*
Y1121948D03*
X270373Y1118208D03*
X266633Y1121948D03*
X270373D03*
X277854Y1118208D03*
Y1121948D03*
X264763Y1108858D03*
X268503D03*
X272244D03*
X275984D03*
X279724D03*
X270373Y1114468D03*
X274114D03*
X277854D03*
Y1129429D03*
X274114Y1125688D03*
X270373Y1136909D03*
X266633Y1133169D03*
X270373D03*
X266633Y1140649D03*
X270373Y1125688D03*
Y1129429D03*
X266633Y1125688D03*
X270373Y1140649D03*
X277854Y1136909D03*
Y1133169D03*
Y1140649D03*
Y1125688D03*
X266633Y1136909D03*
Y1129429D03*
X274114D03*
Y1140649D03*
Y1136909D03*
Y1155610D03*
Y1151869D03*
Y1148129D03*
X266633D03*
X270373Y1144389D03*
Y1148129D03*
Y1151869D03*
X277854Y1144389D03*
Y1148129D03*
Y1151870D03*
X270373Y1155610D03*
X266633D03*
X277854D03*
X266633Y1151869D03*
Y1144389D03*
X274114D03*
Y1166830D03*
Y1159350D03*
Y1170570D03*
X277854Y1159350D03*
Y1166830D03*
Y1170570D03*
X266633D03*
X270373D03*
X266633Y1159350D03*
X270373D03*
Y1166830D03*
X266633D03*
Y1181791D03*
X270373Y1189271D03*
X277854Y1178051D03*
Y1189271D03*
Y1185531D03*
X270373Y1174310D03*
X277854Y1181791D03*
X274114D03*
Y1174310D03*
X266633Y1189271D03*
X270373Y1178051D03*
Y1185531D03*
X266633Y1174310D03*
X277854D03*
X266633Y1185531D03*
Y1178051D03*
X270373Y1181791D03*
X274114Y1185531D03*
Y1189271D03*
Y1178051D03*
Y1204232D03*
Y1196751D03*
X270393Y1196732D03*
X270373Y1204232D03*
X266633D03*
X270373Y1200491D03*
X266633Y1196751D03*
X270373Y1193011D03*
X277854D03*
X266633D03*
Y1200491D03*
X274114D03*
Y1193011D03*
X277854Y1204232D03*
Y1196751D03*
Y1200491D03*
X274114Y1207972D03*
X270373Y1211712D03*
X266633Y1207972D03*
Y1211712D03*
X264763Y1221062D03*
X270373Y1207972D03*
X277854Y1211712D03*
X279724Y1221062D03*
X275984D03*
X272244D03*
X268503D03*
X274114Y1215452D03*
X277854D03*
X266633D03*
X274114Y1211712D03*
X277854Y1207972D03*
X281594Y1211712D03*
X270374Y1215452D03*
X264763Y1232283D03*
X268503Y1224803D03*
X275984D03*
X272244Y1236023D03*
X279724Y1232283D03*
Y1236023D03*
X275984Y1228543D03*
X272244Y1232283D03*
X279724Y1224803D03*
X272244D03*
X268503Y1236023D03*
Y1232283D03*
X272244Y1228543D03*
X264763Y1224803D03*
X275984Y1232283D03*
Y1236023D03*
X264763Y1228543D03*
X279724D03*
X268503D03*
X264763Y1236023D03*
Y1254724D03*
Y1250984D03*
X268503Y1243503D03*
Y1247243D03*
X272244Y1254724D03*
Y1250984D03*
X275984Y1243503D03*
Y1247243D03*
X279724Y1250984D03*
Y1239763D03*
Y1247243D03*
X268503Y1239763D03*
X275984D03*
X272244Y1243503D03*
Y1247243D03*
X264763Y1239763D03*
Y1247243D03*
X268503Y1250984D03*
X264763Y1243503D03*
X272244Y1239763D03*
X275984Y1250984D03*
X279724Y1243503D03*
X268503Y1254724D03*
X275984D03*
X279724D03*
Y1258465D03*
X264763D03*
X272244D03*
X276103Y1348187D03*
X271743D03*
X276103Y1360099D03*
X271743D03*
X276103Y1384297D03*
Y1372385D03*
X271743Y1384297D03*
Y1372385D03*
X276103Y1396583D03*
X271743D03*
Y1408495D03*
X276103D03*
X294684Y1071455D03*
X290944Y1075196D03*
X287203Y1071455D03*
X283464Y1075196D03*
X287203D03*
X294684D03*
Y1082677D03*
Y1090157D03*
X294685Y1086417D03*
X287204Y1090157D03*
X290944Y1078936D03*
X287204Y1082677D03*
Y1086417D03*
X283464Y1078936D03*
Y1090157D03*
X290943D03*
Y1086417D03*
X287203Y1078936D03*
X290943Y1082677D03*
X283463Y1082676D03*
Y1086416D03*
X294684Y1078936D03*
X290944Y1093897D03*
X283464D03*
X287204Y1101377D03*
X283464Y1097637D03*
X287204Y1105117D03*
X290944Y1097637D03*
X294684Y1101377D03*
X294685Y1105117D03*
X283464Y1101376D03*
X294684Y1093897D03*
X287203D03*
X294684Y1097637D03*
X283464Y1105117D03*
X290944Y1101376D03*
Y1105117D03*
X287203Y1097637D03*
X294684Y1120078D03*
Y1112598D03*
X283464Y1108858D03*
X287204D03*
X290944D03*
X294685D03*
X290944Y1112598D03*
Y1116338D03*
Y1120078D03*
Y1123818D03*
X294684D03*
Y1116338D03*
X285334Y1118208D03*
X281594D03*
X285334Y1114468D03*
X281594D03*
X294685Y1127558D03*
Y1135039D03*
X281594Y1140649D03*
Y1136909D03*
X290944Y1127558D03*
Y1131299D03*
Y1135039D03*
Y1138779D03*
X294684Y1131299D03*
X289074Y1140649D03*
X285334D03*
Y1136909D03*
X292815Y1140649D03*
X281594Y1148129D03*
Y1155610D03*
Y1151869D03*
X285334D03*
X289074D03*
Y1155610D03*
Y1144389D03*
X292814Y1151869D03*
Y1144389D03*
X285334Y1155610D03*
X281594Y1144389D03*
X285334Y1148129D03*
Y1144389D03*
X289074Y1148129D03*
X292815D03*
Y1155610D03*
X281594Y1159350D03*
X289074Y1166830D03*
Y1170570D03*
Y1159350D03*
X281594Y1170570D03*
Y1166830D03*
X292814Y1159350D03*
Y1166830D03*
X285334Y1170570D03*
Y1166830D03*
Y1159350D03*
X292815Y1170570D03*
X292814Y1181791D03*
X285334Y1185531D03*
X289074Y1174310D03*
Y1178051D03*
Y1185531D03*
X281594Y1189271D03*
Y1185531D03*
X285334Y1181791D03*
X281594Y1178051D03*
Y1174310D03*
X292814D03*
Y1189271D03*
X285334Y1174310D03*
X289074Y1189271D03*
X285334D03*
X281594Y1181791D03*
X285334Y1178051D03*
X289074Y1181791D03*
X294685Y1194881D03*
Y1202362D03*
X281594Y1196751D03*
Y1204232D03*
X290944Y1191141D03*
X281594Y1193011D03*
X285334D03*
X290944Y1194881D03*
Y1198621D03*
Y1202362D03*
X294685Y1198621D03*
X285334Y1196751D03*
Y1204232D03*
X281594Y1200491D03*
X285334D03*
X294685Y1209842D03*
Y1221062D03*
Y1217322D03*
X290944Y1221062D03*
X287204D03*
X283464D03*
X290944Y1206102D03*
Y1209842D03*
Y1213582D03*
Y1217322D03*
X294685Y1213582D03*
Y1206102D03*
X285334Y1207972D03*
Y1215452D03*
Y1211712D03*
X281594Y1215452D03*
Y1207972D03*
X287204Y1232283D03*
X283464Y1224803D03*
X294685Y1228543D03*
Y1224803D03*
X290944Y1232283D03*
Y1236023D03*
X283464Y1232283D03*
X287204Y1228543D03*
X283464Y1236023D03*
X287204Y1224803D03*
X283464Y1228543D03*
X287204Y1236023D03*
X294685D03*
X290944Y1224803D03*
X294685Y1232283D03*
X290944Y1228543D03*
X287204Y1254724D03*
X283464Y1243503D03*
X294685Y1247243D03*
Y1243503D03*
X283464Y1250984D03*
X287204Y1247243D03*
Y1243503D03*
Y1239763D03*
X294685D03*
X290944Y1250984D03*
X283464Y1254724D03*
X290944D03*
X283464Y1239763D03*
X290944D03*
X283464Y1247243D03*
X287204Y1250984D03*
X294685Y1254724D03*
Y1250984D03*
X290944Y1247243D03*
Y1243503D03*
X294685Y1258465D03*
X287204D03*
X288343Y1348187D03*
X296223D03*
X283983D03*
X288343Y1360099D03*
X296223D03*
X283983D03*
X288343Y1384297D03*
Y1372385D03*
X296223Y1384297D03*
Y1372385D03*
X283983D03*
Y1384297D03*
X288343Y1396583D03*
X296223D03*
X283983D03*
X288343Y1408495D03*
X296223D03*
X283983D03*
X309645Y1071455D03*
X302165D03*
X298425Y1075196D03*
X305906D03*
X302164D03*
X309644D03*
X298424Y1090157D03*
X302164Y1082677D03*
X298426Y1078936D03*
X302164Y1090157D03*
X302165Y1086417D03*
X305904Y1090157D03*
X309644Y1082677D03*
X305906Y1078936D03*
X309645Y1086417D03*
X309644Y1090157D03*
X305904Y1082677D03*
X302164Y1078936D03*
X305904Y1086417D03*
X309644Y1078936D03*
X298424Y1086416D03*
Y1082676D03*
X302165Y1101377D03*
X298425Y1097637D03*
X302165Y1105117D03*
X309645D03*
Y1101377D03*
X305905Y1097637D03*
X298425Y1093897D03*
X305905D03*
X298425Y1105117D03*
Y1101376D03*
X309644Y1097637D03*
X302164D03*
X305905Y1105117D03*
X309644Y1093897D03*
X305905Y1101376D03*
X302164Y1093897D03*
X302165Y1123818D03*
X309645D03*
X305904Y1108857D03*
X309644Y1108858D03*
X302165Y1116338D03*
X298425Y1108858D03*
X302165D03*
X298425Y1112598D03*
X309645D03*
Y1116338D03*
Y1120078D03*
X305905Y1116338D03*
X298425Y1120078D03*
X305905Y1123818D03*
X302165Y1120078D03*
X305905Y1112598D03*
X298425Y1116338D03*
X305905Y1120078D03*
X302165Y1112598D03*
X298425Y1123818D03*
X309645Y1135039D03*
Y1127558D03*
Y1131299D03*
X311515Y1136909D03*
X307775Y1140649D03*
X304035D03*
X305905Y1131299D03*
X300295Y1140649D03*
X298425Y1135039D03*
X302165Y1131299D03*
X298425Y1127558D03*
X305905Y1127559D03*
Y1135039D03*
X302165D03*
Y1127559D03*
X298425Y1131299D03*
X311515Y1140649D03*
X296555Y1151869D03*
X304035Y1155610D03*
Y1148129D03*
X300295Y1155610D03*
Y1151869D03*
Y1148129D03*
Y1144389D03*
X296555D03*
X311515D03*
X307775Y1148129D03*
X311515Y1151869D03*
X307775Y1155610D03*
X304035Y1144389D03*
Y1151869D03*
X307775Y1144389D03*
Y1151869D03*
X296555Y1155610D03*
X311515Y1148129D03*
Y1155610D03*
X307775Y1159350D03*
X296555D03*
X300295D03*
X296555Y1166830D03*
X304035Y1170570D03*
X300295D03*
Y1166830D03*
X311515D03*
X307775Y1170570D03*
X311515Y1159350D03*
X304035Y1166830D03*
Y1159350D03*
X307775Y1166830D03*
X296555Y1170570D03*
X311515D03*
X300295Y1185531D03*
Y1181791D03*
Y1178051D03*
Y1174310D03*
X296555D03*
X298425Y1187401D03*
X304035Y1185531D03*
Y1178051D03*
X300295Y1189271D03*
X311515Y1174310D03*
X307775Y1178051D03*
X311515Y1181791D03*
X307775Y1185531D03*
X311515Y1189271D03*
X304035Y1174310D03*
Y1181791D03*
Y1189271D03*
X307775Y1174310D03*
Y1181791D03*
Y1189271D03*
X311515Y1178051D03*
Y1185531D03*
X304035Y1193011D03*
X302165Y1198621D03*
X298425Y1202362D03*
Y1194881D03*
X309645Y1198621D03*
X307775Y1193011D03*
X311515Y1196751D03*
X305905Y1198621D03*
X309645Y1202362D03*
X298425Y1198621D03*
X305905Y1202362D03*
X302165D03*
X311515Y1193011D03*
X305905Y1206102D03*
X302165Y1213582D03*
X298425Y1209842D03*
X302165Y1206102D03*
X298425Y1221062D03*
X302165D03*
X298425Y1217322D03*
X309645D03*
Y1209842D03*
X305905Y1213582D03*
X309645D03*
Y1206102D03*
Y1221062D03*
X305905D03*
X298425Y1213582D03*
X305905Y1209842D03*
Y1217322D03*
X302165Y1209842D03*
X298425Y1206102D03*
X302165Y1217322D03*
X298425Y1236023D03*
Y1232283D03*
X302165Y1228543D03*
Y1224803D03*
X305905Y1232283D03*
X309645Y1228543D03*
Y1224803D03*
X305905Y1236023D03*
X302165Y1232283D03*
X309645D03*
X298425Y1224803D03*
Y1228543D03*
X309645Y1236023D03*
X305905Y1228543D03*
Y1224803D03*
X302165Y1236023D03*
X309645Y1247243D03*
Y1243503D03*
X298425Y1250984D03*
X302165Y1247243D03*
Y1243503D03*
X305905Y1239763D03*
X302165D03*
X305905Y1250984D03*
X298425Y1254724D03*
X305905D03*
X298425Y1239763D03*
X309645D03*
Y1254724D03*
X298425Y1247243D03*
X309645Y1250984D03*
X298425Y1243503D03*
X305905D03*
Y1247243D03*
X302165Y1254724D03*
Y1250984D03*
X309645Y1258465D03*
X302165D03*
X308463Y1348187D03*
X300583D03*
X308463Y1360099D03*
X300583D03*
X308463Y1372385D03*
X300583D03*
Y1384297D03*
X308463D03*
Y1396583D03*
X300583D03*
X308463Y1408495D03*
X300583D03*
X317125Y1071455D03*
X320866Y1075196D03*
X313386D03*
X317124D03*
X320866Y1086417D03*
Y1078936D03*
X313384Y1090157D03*
X317125D03*
X317126Y1086417D03*
X317125Y1082677D03*
X313386Y1078936D03*
X324606Y1086417D03*
X328347Y1082677D03*
Y1090158D03*
X324606Y1078936D03*
X320866Y1090157D03*
X324606D03*
Y1082676D03*
X317124Y1078936D03*
X313384Y1082677D03*
Y1086417D03*
X320866Y1082676D03*
Y1093897D03*
X313385D03*
X324606D03*
Y1105117D03*
Y1097637D03*
X328347Y1101378D03*
X320866Y1105117D03*
Y1097637D03*
X317126Y1105117D03*
X317125Y1101377D03*
X313385Y1097637D03*
Y1101377D03*
X317125Y1093897D03*
X320866Y1101377D03*
X313385Y1105117D03*
X324606Y1101377D03*
X317125Y1097637D03*
Y1116338D03*
X324606Y1112598D03*
Y1120078D03*
X328347Y1116339D03*
Y1123819D03*
X320866Y1112598D03*
Y1120078D03*
X317125Y1123818D03*
X328347Y1108859D03*
X313385Y1108858D03*
X317125D03*
X313385Y1123818D03*
Y1116338D03*
Y1120078D03*
X324606Y1123818D03*
Y1108858D03*
X320866D03*
X317125Y1112598D03*
X324606Y1116338D03*
X313385Y1112598D03*
X317125Y1120078D03*
X320866Y1116338D03*
Y1123818D03*
X328347Y1131300D03*
X320866Y1127558D03*
Y1135039D03*
X322736Y1140649D03*
X318996D03*
X315255Y1136909D03*
X318996D03*
X313384Y1131299D03*
X317125D03*
X324606Y1127558D03*
Y1135039D03*
X326476Y1140649D03*
X313385Y1127558D03*
X317125Y1135039D03*
X313385D03*
X324606Y1131299D03*
X317125Y1127558D03*
X320866Y1131299D03*
X322736Y1136909D03*
X326476D03*
X315255Y1140649D03*
X322736Y1155610D03*
X318996Y1144389D03*
X315255D03*
X318996Y1155610D03*
X315255Y1151869D03*
X318996D03*
Y1148129D03*
X326476D03*
Y1155610D03*
X322736Y1148129D03*
Y1144389D03*
Y1151870D03*
X326476Y1144389D03*
X315255Y1148129D03*
X326476Y1151870D03*
X315255Y1155610D03*
X322736Y1170570D03*
Y1166830D03*
X315255Y1159350D03*
X318996D03*
X315255Y1166830D03*
X318996Y1170570D03*
Y1166830D03*
X326476D03*
Y1170570D03*
X322736Y1159350D03*
X326476D03*
X315255Y1170570D03*
Y1181791D03*
Y1189271D03*
X318996D03*
Y1185531D03*
Y1181791D03*
Y1178051D03*
X315255Y1174310D03*
X318996D03*
X326476Y1178051D03*
Y1185531D03*
X322736Y1178051D03*
Y1185531D03*
Y1174310D03*
Y1181791D03*
Y1189271D03*
X326476Y1174310D03*
X315255Y1178051D03*
X326476Y1181791D03*
X315255Y1185531D03*
X326476Y1189271D03*
X328347Y1198621D03*
X322736Y1193011D03*
X320866Y1202362D03*
X318996Y1193011D03*
X313385Y1198621D03*
X317125D03*
X326416Y1193011D03*
X324606Y1202362D03*
X320866Y1198621D03*
X313385Y1202362D03*
X324606Y1198621D03*
X317125Y1202362D03*
X315255Y1193011D03*
X328347Y1206102D03*
X317125D03*
X313385D03*
X328347Y1221062D03*
Y1213582D03*
X320866Y1217322D03*
Y1209842D03*
X313385Y1221062D03*
X317125D03*
X313385Y1213582D03*
X317125D03*
X324606Y1209842D03*
Y1217322D03*
X317125D03*
Y1209842D03*
X324606Y1213582D03*
X320866Y1221062D03*
X313385Y1209842D03*
X320866Y1206102D03*
Y1213582D03*
X324606Y1221062D03*
Y1206102D03*
X313385Y1217322D03*
X320866Y1236023D03*
Y1224803D03*
Y1232283D03*
X313385D03*
X317125Y1228543D03*
Y1224803D03*
X313385Y1236023D03*
X324606Y1232283D03*
Y1236023D03*
Y1224803D03*
X328347Y1228543D03*
X317125Y1236023D03*
X313385Y1224803D03*
X324606Y1228543D03*
X317125Y1232283D03*
X313385Y1228543D03*
X320866D03*
X328347Y1239762D03*
Y1247243D03*
X320866Y1250984D03*
Y1243503D03*
X313385Y1250984D03*
X317125Y1247243D03*
Y1243503D03*
X324606D03*
Y1250984D03*
X313385Y1254724D03*
X317125Y1239763D03*
X313385D03*
X320866Y1254724D03*
X317125D03*
X324606Y1239763D03*
X313385Y1247243D03*
X320866D03*
X317125Y1250984D03*
X320866Y1239763D03*
X313385Y1243503D03*
X324606Y1247243D03*
X317125Y1258465D03*
X320703Y1348187D03*
X312823D03*
X325063D03*
X320703Y1360099D03*
X312823D03*
X325063D03*
X320703Y1372385D03*
Y1384297D03*
X312823Y1372385D03*
Y1384297D03*
X325063Y1372385D03*
Y1384297D03*
Y1396583D03*
X320703D03*
X312823D03*
X320703Y1408495D03*
X312823D03*
X325063D03*
X337303Y1348187D03*
X332943D03*
Y1360099D03*
X337303D03*
X332943Y1384297D03*
Y1372385D03*
X337303D03*
Y1384297D03*
X332943Y1396583D03*
X337303D03*
X332943Y1408495D03*
X337303D03*
X349543Y1348187D03*
X357423D03*
X345183D03*
X349543Y1360099D03*
X357423D03*
X345183D03*
Y1372385D03*
Y1384297D03*
X349543D03*
Y1372385D03*
X357423D03*
Y1384297D03*
X345183Y1396583D03*
X349543D03*
X357423D03*
X345183Y1408495D03*
X349543D03*
X357423D03*
X369663Y1348187D03*
X361783D03*
X369663Y1360099D03*
X361783D03*
X369663Y1372385D03*
Y1384297D03*
X361783D03*
Y1372385D03*
X369663Y1396583D03*
X361783D03*
X369663Y1408495D03*
X361783D03*
X425023Y441086D03*
Y433999D03*
Y437543D03*
X422223Y441086D03*
Y433999D03*
Y437543D03*
X425023Y444629D03*
X422223D03*
X438162Y1348187D03*
Y1360099D03*
Y1384297D03*
Y1372385D03*
X450402Y1348187D03*
X458282D03*
X446042D03*
X450402Y1360099D03*
X458282D03*
X446042D03*
X458282Y1372385D03*
X446042D03*
X458282Y1384297D03*
X446042D03*
X450402D03*
Y1372385D03*
X458282Y1396583D03*
X450402D03*
X458282Y1408495D03*
X450402D03*
X462642Y1348187D03*
X474882D03*
X470522D03*
X462642Y1360099D03*
X474882D03*
X470522D03*
X462642Y1384297D03*
X470522D03*
X474882D03*
X462642Y1372385D03*
X470522D03*
X474882D03*
X470522Y1396583D03*
X474882D03*
X462642D03*
X470522Y1408495D03*
X474882D03*
X462642D03*
X482762Y1348187D03*
X487122D03*
X482762Y1360099D03*
X487122D03*
Y1372385D03*
Y1384297D03*
X482762D03*
Y1372385D03*
Y1396583D03*
X487122D03*
X482762Y1408495D03*
X487122D03*
X501750Y620661D03*
X505293D03*
X501750Y617861D03*
X505293D03*
X507242Y1348187D03*
X495002D03*
X499362D03*
X507242Y1360099D03*
X495002D03*
X499362D03*
Y1372385D03*
Y1384297D03*
X495002D03*
X507242D03*
X495002Y1372385D03*
X507242D03*
Y1396583D03*
X495002D03*
X499362D03*
X507242Y1408495D03*
X495002D03*
X499362D03*
X512380Y617861D03*
X508836Y620661D03*
Y617861D03*
X512380Y620661D03*
X519482Y1348187D03*
X511602D03*
X519482Y1360099D03*
X511602D03*
X519482Y1384297D03*
Y1372385D03*
X511602D03*
Y1384297D03*
X519482Y1396583D03*
X511602D03*
X519482Y1408495D03*
X511602D03*
X536082Y1348187D03*
X523842D03*
X531722D03*
X536082Y1360099D03*
X523842D03*
X531722D03*
Y1384297D03*
Y1372385D03*
X523842Y1384297D03*
Y1372385D03*
X536082Y1384297D03*
Y1372385D03*
X531722Y1396583D03*
X536082D03*
X523842D03*
X531722Y1408495D03*
X536082D03*
X523842D03*
X548322Y1348187D03*
X556202D03*
X543962D03*
X548322Y1360099D03*
X556202D03*
X543962D03*
Y1372385D03*
Y1384297D03*
X556202D03*
X548322D03*
X556202Y1372385D03*
X548322D03*
X556202Y1396583D03*
X543962D03*
X548322D03*
X556202Y1408495D03*
X543962D03*
X548322D03*
X568442Y1348187D03*
X560562D03*
X568442Y1360099D03*
X560562D03*
Y1384297D03*
X568442D03*
X560562Y1372385D03*
X568442D03*
Y1396583D03*
X560562D03*
X568442Y1408495D03*
X560562D03*
X600295Y1084547D03*
Y1092027D03*
X604035Y1077066D03*
Y1080806D03*
Y1084547D03*
Y1092027D03*
X600295Y1088287D03*
X604035D03*
Y1103247D03*
X600295D03*
Y1095767D03*
X604035D03*
X600295Y1099507D03*
X604035D03*
X600295Y1106988D03*
X604035D03*
X600295Y1110728D03*
Y1118208D03*
X604035Y1110728D03*
Y1118208D03*
Y1121948D03*
X600295D03*
Y1114468D03*
X604035D03*
X600295Y1125688D03*
Y1133169D03*
Y1140649D03*
X604035Y1125688D03*
Y1133169D03*
Y1140649D03*
X600295Y1136909D03*
X604035D03*
X600295Y1129429D03*
X604035D03*
X600295Y1144389D03*
Y1151870D03*
X604035Y1144389D03*
Y1151870D03*
Y1148129D03*
X600295D03*
Y1159350D03*
X604036Y1166830D03*
X604035Y1159350D03*
X597795Y1170570D03*
X604034D03*
X600294D03*
X604034Y1174310D03*
X597795Y1178050D03*
X602165Y1183661D03*
Y1187401D03*
X604034Y1178051D03*
X600294D03*
X602165Y1202362D03*
Y1194881D03*
X598424Y1198622D03*
Y1191142D03*
X602165Y1191141D03*
Y1198621D03*
Y1217322D03*
Y1209842D03*
X598424Y1221063D03*
Y1213583D03*
Y1206103D03*
X602165Y1221062D03*
Y1206102D03*
Y1213582D03*
Y1224803D03*
Y1236023D03*
Y1232283D03*
X598424Y1228542D03*
X602165Y1228543D03*
Y1243503D03*
Y1250984D03*
X598423Y1239762D03*
Y1247242D03*
X602165Y1247243D03*
Y1239763D03*
X611516Y1073326D03*
X618996D03*
X615256D03*
X607776D03*
X618996Y1088287D03*
Y1092027D03*
X607775Y1077066D03*
X611516D03*
X615256Y1080807D03*
X607776D03*
X615256Y1084547D03*
X607776D03*
X615256Y1088287D03*
X611516D03*
X607776D03*
X611516Y1092027D03*
X618996Y1077066D03*
Y1084547D03*
Y1080807D03*
X615256Y1077066D03*
X611516Y1080807D03*
Y1084547D03*
X607776Y1092027D03*
X615256D03*
X611516Y1106988D03*
X607776D03*
X611516Y1095767D03*
X615256Y1099507D03*
X607776D03*
X615256Y1103247D03*
X607776D03*
X615256Y1106988D03*
X618996Y1095767D03*
Y1106988D03*
X607776Y1095767D03*
X615256D03*
X618996Y1103247D03*
X611516D03*
X618996Y1099507D03*
X611516D03*
X615256Y1110728D03*
Y1114468D03*
X611516D03*
X607776D03*
X615256Y1118208D03*
Y1121948D03*
X611516D03*
X607776D03*
X618996Y1114468D03*
Y1118208D03*
Y1121948D03*
X611516Y1118208D03*
X607776D03*
X611516Y1110728D03*
X618996D03*
X607776D03*
X615256Y1125688D03*
Y1129429D03*
X611516D03*
X607776D03*
Y1136909D03*
X615256Y1140649D03*
X611516D03*
X607776D03*
X618996D03*
Y1125688D03*
Y1129429D03*
Y1133169D03*
X611516Y1125688D03*
X607776D03*
Y1133169D03*
X618996Y1144389D03*
Y1148129D03*
Y1151870D03*
Y1155610D03*
X607776Y1144389D03*
X615256Y1151869D03*
X611516D03*
X607776Y1148129D03*
Y1151870D03*
X615256Y1155610D03*
X611516D03*
X607776D03*
Y1159350D03*
X615256Y1166830D03*
X611516D03*
X607775D03*
X611516Y1170570D03*
X607775D03*
X618996Y1159350D03*
Y1174310D03*
Y1178051D03*
X607775Y1174310D03*
Y1178051D03*
X611516Y1174310D03*
X615256D03*
X613386Y1183661D03*
X617126Y1187401D03*
Y1183661D03*
X613386Y1179921D03*
X620866Y1183661D03*
X609646D03*
X605905D03*
Y1187401D03*
X613386D03*
X609646D03*
X620866D03*
X615256Y1178051D03*
X611516D03*
X613386Y1198621D03*
X609646Y1191141D03*
X613386D03*
X617126Y1202362D03*
Y1194881D03*
Y1198621D03*
X620866D03*
X617126Y1191141D03*
X620866D03*
X605905Y1202362D03*
Y1194881D03*
X609646Y1198621D03*
X605905Y1191141D03*
X613386Y1194881D03*
X605905Y1198621D03*
X609646Y1194881D03*
Y1202362D03*
X613386D03*
X620866D03*
Y1194881D03*
X613386Y1221062D03*
X609646D03*
Y1213582D03*
X613386D03*
X620866Y1206102D03*
X617126D03*
Y1213582D03*
Y1209842D03*
X620866Y1213582D03*
Y1221062D03*
X617126D03*
Y1217322D03*
X613386Y1206102D03*
X605905Y1217322D03*
Y1209842D03*
X609646Y1206102D03*
X613386Y1217322D03*
X605905Y1221062D03*
X609646Y1217322D03*
Y1209842D03*
X605905Y1206102D03*
Y1213582D03*
X620866Y1209842D03*
X613386D03*
X620866Y1217322D03*
X605905Y1224803D03*
Y1232283D03*
Y1236023D03*
X620866D03*
Y1232283D03*
X617126Y1228543D03*
Y1224803D03*
X609646D03*
Y1228543D03*
X613386Y1232283D03*
Y1236023D03*
X605905Y1228543D03*
X620866D03*
Y1224803D03*
X609646Y1232283D03*
X617126Y1236023D03*
X613386Y1228543D03*
X617126Y1232283D03*
X609646Y1236023D03*
X613386Y1224803D03*
X617126Y1243503D03*
Y1239763D03*
X620866D03*
X613386D03*
X609646Y1243503D03*
Y1239763D03*
X620866Y1254724D03*
Y1250984D03*
X617126Y1247243D03*
X609646D03*
X613386Y1254724D03*
Y1250984D03*
X605905Y1243503D03*
Y1254724D03*
Y1250984D03*
Y1247243D03*
X617126Y1250984D03*
X620866Y1243503D03*
Y1247243D03*
X609646Y1254724D03*
X613386Y1247243D03*
X617126Y1254724D03*
X613386Y1243503D03*
X609646Y1250984D03*
X605905Y1239763D03*
X617126Y1258465D03*
X609646D03*
X626476Y1073326D03*
X635827Y1075196D03*
X628346D03*
X632085Y1071455D03*
X632086Y1075196D03*
X622736Y1073326D03*
X626476Y1077066D03*
Y1088287D03*
Y1092027D03*
X622736Y1080807D03*
Y1084547D03*
Y1088287D03*
X635827Y1090157D03*
X628346Y1078936D03*
Y1090157D03*
X635827Y1078936D03*
X632086Y1090157D03*
Y1082677D03*
Y1086417D03*
Y1078936D03*
X635827Y1086417D03*
Y1082677D03*
X622736Y1077066D03*
X626476Y1084547D03*
X622736Y1092027D03*
X626476Y1080807D03*
X632086Y1097637D03*
X630216Y1099507D03*
X622736D03*
Y1103247D03*
X626476Y1106988D03*
X622736D03*
X626476Y1095767D03*
Y1099507D03*
X630216Y1103247D03*
X635827Y1093897D03*
X632086Y1101377D03*
Y1105117D03*
X628346Y1097637D03*
Y1093897D03*
X635827Y1097637D03*
Y1105117D03*
X632086Y1093897D03*
X635827Y1101376D03*
X622736Y1095767D03*
X626476Y1103247D03*
X633957Y1110728D03*
X630216D03*
X626476D03*
X622736Y1114468D03*
X630216Y1118208D03*
X626476D03*
Y1121948D03*
X633957Y1114468D03*
Y1118208D03*
Y1121948D03*
X635827Y1108858D03*
X632086D03*
X622736Y1118208D03*
X626476Y1114468D03*
X622736Y1110728D03*
X630216Y1114468D03*
X633957Y1140649D03*
Y1125688D03*
Y1129429D03*
Y1133169D03*
Y1136909D03*
X630216Y1140649D03*
X626476D03*
X622736D03*
X630216Y1129428D03*
X626476D03*
X622736Y1129429D03*
X630216Y1136909D03*
X626476D03*
X630216Y1144389D03*
X626476D03*
X630216Y1148129D03*
Y1155610D03*
Y1151870D03*
X633957D03*
Y1148129D03*
Y1144389D03*
X626476Y1148129D03*
X622736Y1144389D03*
Y1148129D03*
X626476Y1151870D03*
X622736Y1155610D03*
Y1166830D03*
Y1170570D03*
X630216Y1159350D03*
Y1166830D03*
Y1170570D03*
X633957D03*
Y1166830D03*
Y1159350D03*
X626476D03*
X622736Y1174310D03*
X633957Y1185531D03*
X628346Y1183661D03*
X630216Y1174310D03*
Y1178051D03*
Y1181791D03*
X622736Y1178050D03*
X632086Y1187401D03*
X628346D03*
X624606Y1183661D03*
X635827Y1187401D03*
X624606D03*
X633957Y1174310D03*
Y1178051D03*
Y1181791D03*
X624606Y1191141D03*
X632086Y1202362D03*
X628346D03*
X624606Y1198621D03*
X632086Y1194881D03*
X628346D03*
X635827Y1191141D03*
Y1194881D03*
Y1198621D03*
Y1202362D03*
X628346Y1191141D03*
X624606Y1194881D03*
X632086Y1191141D03*
X628346Y1198621D03*
X624606Y1202362D03*
X632086Y1198621D03*
X624606Y1206102D03*
Y1213582D03*
X632086Y1209842D03*
X628346D03*
Y1217322D03*
Y1221062D03*
X624606D03*
X632086D03*
Y1217322D03*
X635827Y1221062D03*
Y1206102D03*
Y1209842D03*
Y1213582D03*
Y1217322D03*
X628346Y1206102D03*
X632086D03*
X624606Y1217322D03*
X628346Y1213582D03*
X632086D03*
X624606Y1209842D03*
X632086Y1228543D03*
Y1224803D03*
X624606D03*
Y1228543D03*
X628346Y1236023D03*
Y1232283D03*
X635827Y1236023D03*
Y1232283D03*
X628346Y1224803D03*
Y1228543D03*
X635827D03*
X632086Y1232283D03*
Y1236023D03*
X624606Y1232283D03*
Y1236023D03*
X635827Y1224803D03*
X632086Y1247243D03*
Y1243503D03*
X635827Y1239763D03*
X632086D03*
X628346D03*
Y1250984D03*
X624606Y1243503D03*
Y1239763D03*
X635827Y1254724D03*
Y1250984D03*
X628346Y1254724D03*
X624606Y1247243D03*
Y1254724D03*
Y1250984D03*
X632086Y1254724D03*
X635827Y1243503D03*
X632086Y1250984D03*
X635827Y1247243D03*
X628346Y1243503D03*
Y1247243D03*
X632087Y1258465D03*
X624606D03*
X636288Y1372385D03*
Y1384297D03*
X631928Y1396583D03*
X636288D03*
X624048D03*
X631928Y1408495D03*
X636288D03*
X624048D03*
X643307Y1075196D03*
X650787D03*
X647046Y1071455D03*
X639566D03*
X639567Y1075196D03*
X647047D03*
X650787Y1078936D03*
X643307Y1090157D03*
X639567D03*
X647047Y1082677D03*
Y1086417D03*
X643307Y1078936D03*
X650787Y1090157D03*
X647047D03*
X639567Y1086417D03*
Y1082677D03*
X643307Y1086417D03*
Y1082677D03*
X647047Y1078936D03*
X639567D03*
X650787Y1082677D03*
Y1086417D03*
Y1105117D03*
X639567Y1101377D03*
Y1105117D03*
X647047D03*
Y1101377D03*
X650787Y1097637D03*
X643307D03*
Y1093897D03*
X650787D03*
X647047D03*
X639567Y1097637D03*
X643307Y1105117D03*
X647047Y1097637D03*
X639567Y1093897D03*
X643307Y1101376D03*
X650787D03*
X637697Y1114468D03*
X648917Y1118208D03*
X645177D03*
X641437D03*
X637697D03*
X648917Y1121948D03*
X645177D03*
X641437D03*
X637697D03*
Y1110728D03*
X652657Y1118208D03*
Y1121948D03*
X650787Y1108858D03*
X647047D03*
X643307D03*
X639567D03*
X645177Y1114468D03*
X641437D03*
X648917D03*
X652657D03*
X641437Y1133169D03*
X637697D03*
X645177Y1136909D03*
X637697D03*
X645177Y1140649D03*
X641437D03*
X652657Y1133169D03*
Y1129429D03*
Y1125688D03*
Y1136909D03*
X637697Y1140649D03*
X648917Y1125688D03*
X645177D03*
X641437D03*
X637697D03*
X645177Y1129429D03*
X641437D03*
X637697D03*
X645177Y1133169D03*
X648917Y1140649D03*
Y1136909D03*
X652657Y1140649D03*
X641437Y1136909D03*
X648917Y1129429D03*
Y1133169D03*
X637697Y1155610D03*
Y1151870D03*
X645177Y1144389D03*
X637697D03*
Y1148129D03*
X645177Y1151870D03*
X648917Y1155610D03*
Y1148129D03*
X652657Y1151869D03*
Y1144389D03*
Y1148129D03*
Y1155610D03*
X648917Y1144389D03*
Y1151869D03*
X641437Y1144389D03*
Y1151870D03*
X645177Y1155610D03*
Y1148129D03*
Y1170570D03*
X637697Y1166830D03*
X645177Y1159350D03*
X637697D03*
Y1170570D03*
X648917Y1166830D03*
X652657Y1159350D03*
Y1170570D03*
X648917Y1159350D03*
Y1170570D03*
X652657Y1166830D03*
X641437Y1170570D03*
X645177Y1166830D03*
X641437Y1159350D03*
X637697Y1189271D03*
X645177Y1185531D03*
X637697D03*
Y1178051D03*
Y1174310D03*
X645177Y1178051D03*
X637697Y1181791D03*
X652657Y1189271D03*
X648917Y1181791D03*
Y1174310D03*
X652657Y1185531D03*
Y1178051D03*
X648917Y1185531D03*
Y1178051D03*
X652657Y1181791D03*
Y1174310D03*
X641437Y1185531D03*
Y1178051D03*
X645177Y1181791D03*
Y1174310D03*
X652657Y1193011D03*
Y1204232D03*
X637697Y1193011D03*
X645177D03*
Y1196751D03*
Y1200491D03*
X641437D03*
Y1204232D03*
X645177D03*
X648917D03*
Y1196751D03*
Y1200491D03*
X641437Y1193011D03*
Y1196751D03*
X652657Y1200491D03*
Y1196751D03*
X648917Y1193011D03*
X652657Y1211712D03*
X648917Y1219192D03*
X641437D03*
Y1211712D03*
X645177D03*
X648917D03*
Y1207972D03*
X645177D03*
X641437D03*
X652657D03*
X639567Y1221062D03*
X647047D03*
X643307D03*
X650787D03*
X652657Y1215452D03*
Y1219192D03*
X641437Y1215452D03*
X648917D03*
X645177D03*
X639567Y1224803D03*
Y1228543D03*
X643307Y1236023D03*
Y1232283D03*
X650787Y1236023D03*
X647047Y1228543D03*
Y1224803D03*
X650787Y1232283D03*
X639567Y1236023D03*
X647047D03*
X639567Y1232283D03*
X643307Y1224803D03*
X647047Y1232283D03*
X643307Y1228543D03*
X650787D03*
Y1224803D03*
X639567Y1243503D03*
Y1239763D03*
Y1247243D03*
X647047Y1243503D03*
X650787Y1239763D03*
X647047D03*
X643307D03*
X650787Y1254724D03*
Y1250984D03*
X647047Y1247243D03*
X643307Y1254724D03*
Y1250984D03*
X639567D03*
Y1254724D03*
X650787Y1247243D03*
Y1243503D03*
X647047Y1254724D03*
Y1250984D03*
X643307Y1247243D03*
Y1243503D03*
X647047Y1258465D03*
X639567D03*
X648528Y1348187D03*
Y1360099D03*
X644168Y1384297D03*
Y1372385D03*
X648528D03*
Y1384297D03*
X644168Y1396583D03*
X648528D03*
X644168Y1408495D03*
X648528D03*
X658268Y1075196D03*
X665748D03*
X669487Y1071455D03*
X662007D03*
X654526D03*
X662008Y1075196D03*
X654527D03*
X669488D03*
Y1090157D03*
Y1086417D03*
X665748Y1078936D03*
X669488Y1082677D03*
X665748Y1090157D03*
X654527Y1082677D03*
Y1086417D03*
Y1090157D03*
X658268D03*
X662008Y1082677D03*
Y1086417D03*
Y1090157D03*
X658268Y1078936D03*
X662008D03*
X665748Y1082677D03*
X658268D03*
X654527Y1078936D03*
X665748Y1086417D03*
X658268D03*
X669488Y1078936D03*
X662008Y1097637D03*
X654527Y1093897D03*
X669488D03*
X662008Y1101377D03*
X665748Y1093897D03*
X658268D03*
X654527Y1105117D03*
Y1101377D03*
X662008Y1105117D03*
X658268Y1097637D03*
X669488Y1101377D03*
Y1105117D03*
X665748Y1097637D03*
Y1105117D03*
X654527Y1097637D03*
X662008Y1093897D03*
X669488Y1097637D03*
X665748Y1101376D03*
X658268Y1105117D03*
Y1101376D03*
X656398Y1118208D03*
Y1121948D03*
X663878Y1118208D03*
X660138D03*
Y1121948D03*
X663878D03*
X667618Y1118208D03*
Y1121948D03*
X669488Y1108858D03*
X665748D03*
X662008D03*
X658268D03*
X654527D03*
X660138Y1114468D03*
X656398D03*
X663878D03*
X667618D03*
X656398Y1140649D03*
X660138D03*
X663878D03*
X656398Y1125688D03*
X660138D03*
X663878D03*
Y1133169D03*
X660138D03*
X656398D03*
X667618D03*
Y1140649D03*
Y1125688D03*
Y1129429D03*
X660138D03*
X656398D03*
X663878D03*
Y1136909D03*
X660138D03*
X656398D03*
X667618D03*
Y1148129D03*
X660138D03*
X656398D03*
X663878D03*
X656398Y1155610D03*
X663878D03*
X660138D03*
X667618D03*
Y1144389D03*
X663878D03*
X660138D03*
X656398D03*
X667618Y1151870D03*
X663878D03*
X660138D03*
X656398D03*
X663878Y1166830D03*
X660138Y1159350D03*
X656398Y1166830D03*
X660138Y1170570D03*
X667618Y1159350D03*
Y1170570D03*
X663878D03*
X660138Y1166830D03*
X656398Y1170570D03*
X663878Y1159350D03*
X656398D03*
X667618Y1166830D03*
X663878Y1181791D03*
X660138D03*
X656398D03*
X663878Y1189271D03*
X660138D03*
X656398D03*
X667618Y1181791D03*
Y1189271D03*
X656398Y1174310D03*
X663878D03*
X667618D03*
X660138D03*
X667618Y1185531D03*
X660138D03*
X656398D03*
X663878D03*
X667618Y1178051D03*
X663878D03*
X660138D03*
X656398D03*
X663878Y1196751D03*
X660138D03*
X656398D03*
Y1204232D03*
X660138D03*
X663878D03*
X667618Y1196751D03*
Y1204232D03*
Y1200491D03*
X656398D03*
X663878D03*
X660138D03*
X663878Y1193011D03*
X660138D03*
X656398D03*
X667618D03*
X663878Y1207972D03*
X660138D03*
X656398D03*
X667618D03*
Y1211712D03*
X654527Y1221062D03*
X658268D03*
X662008D03*
X665748D03*
X669488D03*
X663878Y1211712D03*
X656398D03*
X660138Y1215452D03*
X656398D03*
X663878D03*
X667618D03*
X660138Y1211712D03*
X654527Y1224803D03*
Y1228543D03*
X658268Y1236023D03*
Y1232283D03*
X662008Y1228543D03*
Y1224803D03*
X665748Y1236023D03*
Y1232283D03*
X669488Y1228543D03*
Y1224803D03*
Y1232283D03*
X654527Y1236023D03*
X662008Y1232283D03*
X665748Y1224803D03*
X662008Y1236023D03*
X658268Y1224803D03*
X665748Y1228543D03*
X658268D03*
X669488Y1236023D03*
X654527Y1232283D03*
Y1239763D03*
Y1243503D03*
Y1247243D03*
X662008Y1239763D03*
X658268D03*
X669488D03*
X665748D03*
Y1250984D03*
Y1254724D03*
X669488Y1247243D03*
Y1243503D03*
X662008D03*
Y1247243D03*
X658268Y1254724D03*
Y1250984D03*
X662008Y1254724D03*
X665748Y1247243D03*
X669488Y1250984D03*
X658268Y1247243D03*
X662008Y1250984D03*
X665748Y1243503D03*
X669488Y1254724D03*
X658268Y1243503D03*
X654527Y1254724D03*
Y1250984D03*
X662008Y1258465D03*
X669488D03*
X654528D03*
X660768Y1348187D03*
X668648D03*
X656408D03*
X660768Y1360099D03*
X668648D03*
X656408D03*
Y1384297D03*
Y1372385D03*
X668648D03*
X660768D03*
X668648Y1384297D03*
X660768D03*
X668648Y1396583D03*
X656408D03*
X660768D03*
X668648Y1408495D03*
X656408D03*
X660768D03*
X680709Y1075196D03*
X673228D03*
X684448Y1071455D03*
X676967D03*
X676968Y1075196D03*
X684449D03*
X680709Y1090157D03*
X676968D03*
X684449D03*
Y1082677D03*
Y1086417D03*
X673228Y1090157D03*
Y1078936D03*
X680709D03*
X676968Y1082677D03*
Y1086417D03*
Y1078936D03*
X680709Y1086417D03*
X684449Y1078936D03*
X673228Y1086417D03*
Y1082677D03*
X680709D03*
X673228Y1105117D03*
X684449Y1093897D03*
X676968D03*
Y1105117D03*
X684449Y1101377D03*
Y1105117D03*
X680709Y1093897D03*
X676968Y1101377D03*
X680709Y1097637D03*
X673228D03*
Y1093897D03*
X684449Y1097637D03*
X676968D03*
X680708Y1105117D03*
X673228Y1101376D03*
X680708D03*
X682579Y1118208D03*
Y1121948D03*
X671358Y1114468D03*
Y1118208D03*
X675098D03*
X678838D03*
X675098Y1121948D03*
X678838D03*
X671358D03*
X684449Y1108858D03*
X680709D03*
X676968D03*
X673228D03*
X682579Y1114468D03*
X678839D03*
X675098D03*
X682579Y1133169D03*
Y1140649D03*
Y1125688D03*
X671358Y1140649D03*
X675098D03*
X678838D03*
X675098Y1125688D03*
X671358D03*
X678838D03*
Y1133169D03*
X675098D03*
X671358D03*
X675098Y1129429D03*
X671358D03*
X678838D03*
X682579D03*
Y1136909D03*
X678838D03*
X675098D03*
X671358D03*
X682579Y1148129D03*
X678838D03*
X675098D03*
X671358D03*
Y1155610D03*
X678838D03*
X682579D03*
X675098D03*
X678839Y1151870D03*
X675098D03*
X671358D03*
X682579D03*
Y1144389D03*
X671358D03*
X678838D03*
X675098D03*
X682579Y1170570D03*
Y1159350D03*
X675098Y1170570D03*
X678839Y1166830D03*
X671358D03*
X675098Y1159350D03*
X682579Y1166830D03*
X678838Y1170570D03*
X671358D03*
X675098Y1166830D03*
X671358Y1159350D03*
X678838D03*
X675098Y1181791D03*
X671358D03*
X678838Y1189271D03*
X675098D03*
X671358D03*
X682579Y1181791D03*
Y1189271D03*
X678838Y1181791D03*
X671358Y1174310D03*
X678838D03*
X682579D03*
X675098D03*
X682579Y1185531D03*
X675098D03*
X671358D03*
X678838D03*
X682579Y1178051D03*
X678838D03*
X675098D03*
X671358D03*
X682579Y1196751D03*
Y1204232D03*
X678838D03*
Y1196751D03*
X675098D03*
X671358D03*
Y1204232D03*
X675098D03*
Y1200491D03*
X671358D03*
X678838D03*
X682579D03*
Y1193011D03*
X678838D03*
X675098D03*
X671358D03*
X682579Y1207972D03*
X675098Y1211712D03*
X678838Y1219192D03*
Y1207972D03*
X675098D03*
X671358D03*
X673228Y1221062D03*
X676968D03*
X680709D03*
X684449D03*
X682579Y1211712D03*
X678839D03*
Y1215452D03*
X671358Y1211712D03*
Y1215452D03*
X675098D03*
X673228Y1236023D03*
Y1232283D03*
X676968Y1224803D03*
Y1228543D03*
X680709Y1236023D03*
Y1232283D03*
X684449Y1224803D03*
Y1228543D03*
X676968Y1236023D03*
X684449Y1232283D03*
X673228Y1228543D03*
X680709Y1224803D03*
X684449Y1236023D03*
X676968Y1232283D03*
X673228Y1224803D03*
X680709Y1228543D03*
X673228Y1239763D03*
X676968D03*
X680709D03*
Y1254724D03*
Y1250984D03*
X676968Y1243503D03*
Y1247243D03*
X673228Y1254724D03*
Y1250984D03*
X684449Y1247243D03*
Y1243503D03*
Y1239763D03*
X673228Y1243503D03*
X680709Y1247243D03*
X673228D03*
X684449Y1254724D03*
Y1250984D03*
X676968Y1254724D03*
Y1250984D03*
X680709Y1243503D03*
X684450Y1258465D03*
X676969D03*
X680888Y1348187D03*
X673008D03*
X685248D03*
X680888Y1360099D03*
X673008D03*
X685248D03*
Y1372385D03*
Y1384297D03*
X673008Y1372385D03*
Y1384297D03*
X680888Y1372385D03*
Y1384297D03*
Y1396583D03*
X685248D03*
X673008D03*
X680888Y1408495D03*
X685248D03*
X673008D03*
X688189Y1075196D03*
X695669D03*
X699408Y1071455D03*
X691928Y1071454D03*
X699408Y1075196D03*
X691928Y1075195D03*
X688189Y1078936D03*
Y1090157D03*
X691929Y1082677D03*
Y1086417D03*
X695669Y1090157D03*
X699409D03*
Y1086417D03*
X691929Y1090157D03*
X695669Y1078936D03*
X699409Y1082677D03*
X688189Y1086417D03*
Y1082677D03*
X691928Y1078935D03*
X699408Y1078936D03*
X695668Y1086416D03*
Y1082676D03*
X688189Y1105117D03*
Y1097637D03*
X695669Y1093897D03*
X688189D03*
X699409Y1105117D03*
X691929Y1101377D03*
X699409D03*
X695669Y1097637D03*
X691929Y1105117D03*
X695669Y1101376D03*
X699408Y1097637D03*
X695669Y1105117D03*
X691928Y1093897D03*
Y1097637D03*
X699408Y1093897D03*
X688189Y1101376D03*
X693799Y1121948D03*
X697539D03*
X701279D03*
X686319D03*
Y1118208D03*
Y1114468D03*
X699409Y1108858D03*
X695669D03*
X691929D03*
X688189D03*
X693799Y1114468D03*
Y1118208D03*
X701279Y1114468D03*
X697539Y1118208D03*
Y1114468D03*
X701279Y1118208D03*
X693799Y1133464D03*
X697539Y1133169D03*
X686417Y1132677D03*
X693799Y1140649D03*
X697539D03*
X693799Y1125688D03*
X697539D03*
X701279D03*
Y1140649D03*
Y1133169D03*
X686319Y1140649D03*
Y1125688D03*
X701279Y1129429D03*
X697539D03*
X693799D03*
X686319D03*
X697539Y1136909D03*
X693799D03*
X701279D03*
X686319D03*
X697539Y1148129D03*
X701279D03*
X693799D03*
X697539Y1155610D03*
X686319Y1148129D03*
Y1155610D03*
X701279D03*
X693799D03*
X701279Y1151869D03*
X697539D03*
X693799D03*
X701279Y1144389D03*
X697539D03*
X693799D03*
X686319D03*
Y1151870D03*
X697539Y1166830D03*
X693799Y1170570D03*
Y1159350D03*
X701279D03*
Y1170570D03*
X686319Y1166830D03*
X693799D03*
X697539Y1170570D03*
Y1159350D03*
X701279Y1166830D03*
X686319Y1170570D03*
Y1159350D03*
X693799Y1181791D03*
Y1189271D03*
X697539D03*
X701279D03*
Y1181791D03*
X697539D03*
Y1174310D03*
X686319Y1181791D03*
Y1189271D03*
Y1174310D03*
X701279D03*
X693799D03*
X701279Y1185531D03*
X697539D03*
X693799D03*
X701279Y1178051D03*
X697539D03*
X693799D03*
X686319Y1185531D03*
Y1178051D03*
X697539Y1204232D03*
X693799D03*
Y1196751D03*
X697539D03*
X701279D03*
Y1204232D03*
X686319Y1196751D03*
Y1204232D03*
X701279Y1200491D03*
X697539D03*
X693799D03*
X686319D03*
X701279Y1193011D03*
X697539D03*
X693799D03*
X686319D03*
X693799Y1207972D03*
X697539D03*
Y1211712D03*
X701279Y1207972D03*
Y1211712D03*
X686319Y1207972D03*
X695669Y1221062D03*
X699409D03*
X691929D03*
X688189D03*
X686319Y1211712D03*
Y1215452D03*
X699409Y1217322D03*
X697539Y1215452D03*
X693799D03*
Y1211712D03*
X701279Y1215452D03*
X695669Y1217322D03*
X688189Y1228543D03*
X691929Y1236023D03*
X699409Y1232283D03*
X688189Y1236023D03*
Y1232283D03*
X691929Y1224803D03*
Y1228543D03*
X699409Y1224803D03*
Y1228543D03*
X695669Y1236023D03*
Y1232283D03*
X688189Y1224803D03*
X699409Y1236023D03*
X691929Y1232283D03*
X695669Y1228543D03*
Y1224803D03*
X688189Y1254724D03*
Y1250984D03*
Y1239763D03*
X699409Y1247243D03*
Y1243503D03*
Y1239763D03*
X695669D03*
X691929D03*
Y1243503D03*
Y1247243D03*
X695669Y1250984D03*
Y1254724D03*
X699409D03*
X691929Y1250984D03*
X688189Y1247243D03*
Y1243503D03*
X691929Y1254724D03*
X695669Y1247243D03*
X699409Y1250984D03*
X695669Y1243503D03*
X699409Y1258465D03*
X691929D03*
X693128Y1348187D03*
X697488D03*
X693128Y1360099D03*
X697488D03*
Y1384297D03*
Y1372385D03*
X693128D03*
Y1384297D03*
Y1396583D03*
X697488D03*
X693128Y1408495D03*
X697488D03*
X703149Y1075196D03*
X718110D03*
X710630D03*
X714369Y1071455D03*
X706889D03*
Y1075196D03*
X714369D03*
X710630Y1078936D03*
X706890Y1082677D03*
Y1086417D03*
Y1090157D03*
X718110Y1078936D03*
X714370Y1082677D03*
Y1086417D03*
Y1090157D03*
X710630D03*
X718110D03*
X703149Y1078936D03*
Y1090157D03*
X706889Y1078936D03*
X718109Y1086417D03*
X714369Y1078936D03*
X703148Y1082677D03*
X710629Y1086416D03*
X703148Y1086417D03*
X718109Y1082677D03*
X710629Y1082676D03*
X706890Y1101377D03*
Y1105117D03*
X714370D03*
Y1101377D03*
X710630Y1097637D03*
Y1093897D03*
X718110Y1097637D03*
Y1093897D03*
X703149D03*
Y1097637D03*
X714369D03*
X706889Y1093897D03*
X703149Y1105117D03*
X718110D03*
Y1101376D03*
X710630Y1105117D03*
X714369Y1093897D03*
X706889Y1097637D03*
X703149Y1101376D03*
X710630D03*
X716240Y1121948D03*
X705020D03*
X708760D03*
X712500D03*
X718110Y1108858D03*
X714370D03*
X710630D03*
X706890D03*
X703149D03*
X708760Y1114468D03*
X716240Y1118208D03*
X705020Y1114468D03*
X712500D03*
X716240D03*
X705020Y1118208D03*
X712500D03*
X708760D03*
X716240Y1140649D03*
Y1125688D03*
Y1133169D03*
X712500Y1125688D03*
X708760D03*
X705020D03*
X712500Y1140649D03*
X708760D03*
X705020D03*
X712500Y1133169D03*
X708760D03*
X705020D03*
Y1129429D03*
X708760D03*
X712500D03*
X716240D03*
Y1136909D03*
X705020D03*
X708760D03*
X712500D03*
X716240Y1148129D03*
X712500D03*
X708760D03*
X705020D03*
X712500Y1155610D03*
X705020D03*
X708760D03*
X716240D03*
Y1151869D03*
X708760D03*
X712500D03*
X705020D03*
X712500Y1144389D03*
X705020D03*
X708760D03*
X716240D03*
Y1170570D03*
Y1159350D03*
X708760D03*
X705020Y1166830D03*
X712500D03*
X708760Y1170570D03*
X716240Y1166830D03*
X705020Y1159350D03*
X712500D03*
X705020Y1170570D03*
X712500D03*
X708760Y1166830D03*
X716240Y1189271D03*
Y1181791D03*
X712500Y1189271D03*
X708760D03*
X705020D03*
X712500Y1181791D03*
X708760D03*
X705020D03*
Y1174310D03*
X712500D03*
X716240D03*
X708760D03*
X716240Y1185531D03*
X708760D03*
X712500D03*
X705020D03*
X716240Y1178051D03*
X712500D03*
X705020D03*
X708760D03*
X716240Y1196751D03*
Y1204232D03*
X712500Y1196751D03*
X708760D03*
X705020D03*
X708760Y1204232D03*
X712500D03*
X705020D03*
X712500Y1200491D03*
X705020D03*
X708760D03*
X716240D03*
X708760Y1193011D03*
X712500D03*
X705020D03*
X716240D03*
Y1211712D03*
Y1207972D03*
X712500D03*
Y1211712D03*
X708760Y1207972D03*
X705020D03*
X703149Y1221062D03*
X706890D03*
X710630D03*
X714370D03*
X718110D03*
X716240Y1215452D03*
X708760D03*
X712500D03*
X705019Y1215451D03*
Y1211711D03*
X708760D03*
X706890Y1236023D03*
X718110Y1228543D03*
X714370Y1236023D03*
X710630Y1228543D03*
X703149D03*
Y1236023D03*
Y1232283D03*
X710630Y1236023D03*
X718110D03*
Y1232283D03*
X710630D03*
X714370Y1224803D03*
Y1228543D03*
X706890Y1224803D03*
Y1228543D03*
X714370Y1232283D03*
X703149Y1224803D03*
X718110D03*
X710630D03*
X706890Y1232283D03*
X703149Y1254724D03*
Y1250984D03*
Y1239763D03*
X714370D03*
X718110Y1250984D03*
Y1239763D03*
X714370Y1243503D03*
Y1247243D03*
X710630Y1254724D03*
Y1250984D03*
Y1239763D03*
X706890Y1247243D03*
Y1243503D03*
Y1239763D03*
X718110Y1254724D03*
Y1243503D03*
Y1247243D03*
X706890Y1250984D03*
X703149Y1243503D03*
X714370Y1254724D03*
Y1250984D03*
X710630Y1247243D03*
X706890Y1254724D03*
X710630Y1243503D03*
X703149Y1247243D03*
X714370Y1258465D03*
X706890D03*
X705368Y1348187D03*
X717608D03*
X709728D03*
X705368Y1360099D03*
X717608D03*
X709728D03*
Y1384297D03*
Y1372385D03*
X705368D03*
Y1384297D03*
X717608Y1372385D03*
Y1384297D03*
Y1396583D03*
X705368D03*
X709728D03*
X717608Y1408495D03*
X705368D03*
X709728D03*
X725590Y1075196D03*
X733071D03*
X729330Y1071455D03*
X721849D03*
Y1075196D03*
X729330D03*
X721850Y1082677D03*
X729331Y1086417D03*
Y1082677D03*
X733071Y1090157D03*
Y1078936D03*
X729331Y1090157D03*
X725590D03*
X721850D03*
X725590Y1078936D03*
X721850Y1086417D03*
X725589Y1086416D03*
X733069Y1086417D03*
X721849Y1078936D03*
X729330D03*
X733069Y1082677D03*
X725589Y1082676D03*
X729331Y1101377D03*
X725590Y1097637D03*
X721850Y1101377D03*
Y1105117D03*
X725590Y1093897D03*
X729331Y1105117D03*
X733071Y1093897D03*
Y1097637D03*
X725590Y1101376D03*
X733071Y1105117D03*
X725590D03*
X721849Y1097637D03*
Y1093897D03*
X729330Y1097637D03*
X733071Y1101376D03*
X729330Y1093897D03*
X734941Y1121948D03*
Y1118208D03*
X727460Y1121948D03*
X719980D03*
X723720D03*
X727460Y1118208D03*
X731201Y1121948D03*
Y1118208D03*
X733071Y1108858D03*
X729331D03*
X725590D03*
X721850D03*
X731201Y1114468D03*
X734941D03*
X727460D03*
X719980Y1118208D03*
Y1114468D03*
X734941Y1129429D03*
Y1125688D03*
Y1140649D03*
Y1133169D03*
Y1136909D03*
X727460Y1140649D03*
X723720Y1125688D03*
X719980D03*
X727460Y1129429D03*
Y1125688D03*
X723720Y1140649D03*
X719980D03*
X727460Y1133169D03*
X723720D03*
X719980D03*
X727460Y1136909D03*
X731201Y1125688D03*
X719980Y1129429D03*
X723720D03*
X731201D03*
X719980Y1136909D03*
X723720D03*
X731201D03*
Y1140649D03*
X727460Y1151869D03*
Y1148129D03*
Y1144389D03*
X723720Y1148129D03*
X719980D03*
X731201D03*
Y1151869D03*
Y1155610D03*
X734941Y1151870D03*
Y1148129D03*
Y1144389D03*
X719980Y1155610D03*
X727460D03*
X723720D03*
X719980Y1151869D03*
X723720D03*
Y1144389D03*
X719980D03*
X734941Y1155610D03*
X731201Y1144389D03*
Y1170570D03*
X719980Y1166830D03*
X731201Y1159350D03*
Y1166830D03*
X719980Y1159350D03*
X727460D03*
X723720D03*
Y1166830D03*
X727460D03*
X719980Y1170570D03*
X727460D03*
X723720D03*
X734941Y1159350D03*
Y1166830D03*
Y1170570D03*
X727460Y1185531D03*
X734941Y1181791D03*
Y1185531D03*
Y1189271D03*
Y1178051D03*
X727460Y1189271D03*
X723720Y1181791D03*
X719980D03*
Y1174310D03*
X727460Y1178051D03*
X723720Y1189271D03*
X719980D03*
X731201Y1174310D03*
Y1181791D03*
X727460Y1174310D03*
X723720D03*
X727460Y1181791D03*
X719980Y1185531D03*
Y1178051D03*
X723720D03*
Y1185531D03*
X734941Y1174310D03*
X731201Y1189271D03*
Y1185531D03*
Y1178051D03*
X719980Y1204232D03*
X727460D03*
X727480Y1196732D03*
X731201Y1196751D03*
Y1204232D03*
X734941Y1193011D03*
X727460D03*
X723720Y1196751D03*
X719980D03*
X727460Y1200491D03*
X723720Y1204232D03*
X719980Y1200491D03*
X723720D03*
X731201D03*
X719980Y1193011D03*
X723720D03*
X731201D03*
X734941Y1196751D03*
Y1204232D03*
Y1200491D03*
Y1211712D03*
X727460Y1207972D03*
X723720Y1211712D03*
Y1207972D03*
X719980Y1211712D03*
Y1207972D03*
X727460Y1211712D03*
X731201Y1207972D03*
X733071Y1221062D03*
X721850D03*
X725590D03*
X729331D03*
X731201Y1215452D03*
X734941D03*
X723720D03*
X719980D03*
X731201Y1211712D03*
X734941Y1207972D03*
X727461Y1215452D03*
X725590Y1228543D03*
X733071D03*
X729331Y1224803D03*
Y1228543D03*
X733071Y1236023D03*
Y1232283D03*
X725590Y1236023D03*
Y1232283D03*
X721850Y1224803D03*
Y1228543D03*
Y1236023D03*
X733071Y1224803D03*
X721850Y1232283D03*
X725590Y1224803D03*
X729331Y1236023D03*
Y1232283D03*
X733071Y1239763D03*
X729331Y1243503D03*
X721850D03*
X725590Y1239763D03*
X729331D03*
X721850D03*
X729331Y1247243D03*
X733071Y1250984D03*
Y1254724D03*
X725590D03*
Y1250984D03*
X721850Y1247243D03*
X729331Y1250984D03*
X733071Y1247243D03*
X721850Y1250984D03*
Y1254724D03*
X725590Y1243503D03*
X729331Y1254724D03*
X733071Y1243503D03*
X725590Y1247243D03*
X729331Y1258465D03*
X721850D03*
X734208Y1348187D03*
X729848D03*
X721968D03*
X734208Y1360099D03*
X729848D03*
X721968D03*
X729848Y1372385D03*
Y1384297D03*
X721968D03*
Y1372385D03*
X734208D03*
Y1384297D03*
X729848Y1396489D03*
X721968D03*
X734208D03*
X729848Y1408401D03*
X721968D03*
X734208D03*
X740551Y1075196D03*
X748031D03*
X744290Y1071455D03*
X736810D03*
Y1075196D03*
X744290D03*
X748030Y1090157D03*
X744291Y1082677D03*
X748031Y1078936D03*
X744291Y1090157D03*
Y1086417D03*
X740551Y1078936D03*
Y1090157D03*
X736811Y1086417D03*
Y1090157D03*
Y1082677D03*
X744290Y1078936D03*
X748030Y1086417D03*
X740550Y1086416D03*
Y1082676D03*
X736810Y1078936D03*
X748030Y1082677D03*
X744291Y1101377D03*
X740551Y1097637D03*
X748031Y1093897D03*
Y1097637D03*
X740551Y1093897D03*
X744291Y1105117D03*
X736811D03*
Y1101377D03*
X736810Y1097637D03*
X748031Y1105117D03*
X744290Y1093897D03*
X740551Y1105117D03*
X744290Y1097637D03*
X736810Y1093897D03*
X740551Y1101376D03*
X748031D03*
Y1123818D03*
Y1120078D03*
Y1116338D03*
Y1112598D03*
Y1108858D03*
X744291D03*
X740551D03*
X736811D03*
X738681Y1118208D03*
X742421D03*
X738681Y1114468D03*
X742421D03*
X738681Y1136909D03*
Y1140649D03*
X748031Y1138779D03*
Y1135039D03*
Y1131299D03*
Y1127558D03*
X742421Y1140649D03*
Y1136909D03*
X746161Y1140649D03*
X749902D03*
X738681Y1155610D03*
Y1148129D03*
X749901Y1144389D03*
Y1151869D03*
X746161Y1144389D03*
Y1155610D03*
Y1151869D03*
X742421D03*
X738681D03*
X742421Y1155610D03*
X746161Y1148129D03*
X738681Y1144389D03*
X742421Y1148129D03*
Y1144389D03*
X749902Y1155610D03*
Y1148129D03*
X738681Y1166830D03*
X746161Y1170570D03*
Y1166830D03*
X738681Y1159350D03*
X749901Y1166830D03*
Y1159350D03*
X738681Y1170570D03*
X746161Y1159350D03*
X742421D03*
Y1166830D03*
Y1170570D03*
X749902D03*
X749901Y1181791D03*
Y1174310D03*
X738681D03*
Y1178051D03*
X742421Y1181791D03*
X738681Y1185531D03*
Y1189271D03*
X746161Y1185531D03*
Y1178051D03*
Y1174310D03*
X742421Y1185531D03*
Y1189271D03*
X746161D03*
X742421Y1174310D03*
X738681Y1181791D03*
X746161D03*
X742421Y1178051D03*
X748031Y1191141D03*
X738681Y1204232D03*
X748031Y1194881D03*
X738681Y1193011D03*
Y1196751D03*
X742421Y1193011D03*
X748031Y1202362D03*
Y1198621D03*
X742421Y1196751D03*
X738681Y1200491D03*
X742421Y1204232D03*
Y1200491D03*
X736811Y1221062D03*
X740551D03*
X748031D03*
X744291D03*
X748031Y1217322D03*
Y1213582D03*
Y1209842D03*
Y1206102D03*
X742421Y1211712D03*
Y1215452D03*
Y1207972D03*
X738681Y1215452D03*
Y1207972D03*
Y1211712D03*
X744291Y1236023D03*
X736811Y1232283D03*
Y1224803D03*
Y1228543D03*
X748031Y1236023D03*
Y1232283D03*
X740551Y1236023D03*
X744291Y1228543D03*
X740551Y1232283D03*
X744291Y1224803D03*
Y1232283D03*
X736811Y1236023D03*
X740551Y1224803D03*
Y1228543D03*
X748031Y1224803D03*
Y1228543D03*
X736811Y1243503D03*
Y1239763D03*
Y1247243D03*
X748031Y1239763D03*
X744291Y1243503D03*
Y1239763D03*
X740551D03*
X748031Y1254724D03*
Y1250984D03*
X744291Y1247243D03*
X740551Y1254724D03*
Y1250984D03*
X744291Y1254724D03*
X740551Y1243503D03*
Y1247243D03*
X744291Y1250984D03*
X736811Y1254724D03*
Y1250984D03*
X748031Y1247243D03*
Y1243503D03*
X744291Y1258465D03*
X736811D03*
X746448Y1348187D03*
X742088D03*
X746448Y1360099D03*
X742088D03*
Y1384297D03*
Y1372385D03*
X746448D03*
Y1384297D03*
X742088Y1396489D03*
Y1408401D03*
X755512Y1075196D03*
X762993D03*
X766732Y1071455D03*
X759252D03*
X751771D03*
Y1075196D03*
X766731D03*
X759251D03*
Y1082677D03*
X766731Y1090157D03*
X751772Y1086417D03*
X751771Y1090157D03*
Y1082677D03*
X759251Y1090157D03*
X762991D03*
X759252Y1086417D03*
X755511Y1090157D03*
X766732Y1086417D03*
X762993Y1078936D03*
X766731Y1082677D03*
X755513Y1078936D03*
X762991Y1086417D03*
X766731Y1078936D03*
X755511Y1086416D03*
X759251Y1078936D03*
X755511Y1082676D03*
X762991Y1082677D03*
X751771Y1078936D03*
Y1101377D03*
X751772Y1105117D03*
X762992Y1097637D03*
Y1093897D03*
X759252Y1105117D03*
X766732D03*
X755512Y1097637D03*
X759252Y1101377D03*
X766732D03*
X755512Y1093897D03*
X751771Y1097637D03*
X762992Y1101376D03*
Y1105117D03*
X755512D03*
X759251Y1097637D03*
Y1093897D03*
X766731Y1097637D03*
X755512Y1101376D03*
X766731Y1093897D03*
X751771D03*
X762992Y1116338D03*
X766732Y1120078D03*
X762991Y1108857D03*
X766731Y1108858D03*
X766732Y1116338D03*
Y1123818D03*
X762992D03*
X766732Y1112598D03*
X755512Y1108858D03*
X759252D03*
X751772D03*
X759252Y1116338D03*
X755512Y1120078D03*
X759252Y1123818D03*
X751771Y1112598D03*
Y1120078D03*
X755512Y1123818D03*
X759252Y1112598D03*
X751771Y1123818D03*
X762992Y1112598D03*
X755512Y1116338D03*
X751771D03*
X759252Y1120078D03*
X762992D03*
X757382Y1140649D03*
X761122D03*
X764862D03*
X762992Y1131299D03*
X766732D03*
Y1135039D03*
Y1127558D03*
X755512D03*
X759252Y1131299D03*
X755512Y1135039D03*
X751772Y1127558D03*
Y1135039D03*
X751771Y1131299D03*
X762992Y1135039D03*
X755512Y1131299D03*
X762992Y1127559D03*
X759252Y1135039D03*
Y1127559D03*
X764862Y1155610D03*
Y1148129D03*
X753642Y1144389D03*
X757382D03*
Y1148129D03*
Y1151869D03*
Y1155610D03*
X761122Y1148129D03*
Y1155610D03*
X753642Y1151869D03*
X761122Y1144389D03*
Y1151869D03*
X753642Y1155610D03*
X764862Y1151869D03*
Y1144389D03*
Y1159350D03*
Y1170570D03*
X757382Y1166830D03*
Y1170570D03*
X761122D03*
X753642Y1166830D03*
X757382Y1159350D03*
X753642D03*
X764862Y1166830D03*
X761122D03*
Y1159350D03*
X753642Y1170570D03*
Y1181791D03*
Y1174310D03*
X757382D03*
Y1178051D03*
Y1181791D03*
Y1185531D03*
X764862D03*
Y1178051D03*
X755512Y1187401D03*
X761122Y1178051D03*
Y1185531D03*
X753642Y1189271D03*
X764862D03*
Y1174310D03*
X761122Y1181791D03*
X764862D03*
X761122Y1174310D03*
X766732Y1194881D03*
X759252Y1191141D03*
X762992D03*
X755512Y1194881D03*
X751772D03*
X755512Y1202362D03*
X766732D03*
Y1198621D03*
X762992D03*
X759252D03*
X751772Y1202362D03*
X762992D03*
X755512Y1198621D03*
X759252Y1202362D03*
X751772Y1198621D03*
X766732Y1221062D03*
Y1217322D03*
X762992Y1221062D03*
X759252D03*
X755512D03*
Y1217322D03*
X759252Y1213582D03*
X762992D03*
X766732D03*
Y1209842D03*
X755512D03*
X766732Y1206102D03*
X762992D03*
X759252D03*
X751772Y1221062D03*
Y1217322D03*
Y1209842D03*
X762992Y1217322D03*
X751772Y1213582D03*
X762992Y1209842D03*
X755512Y1213582D03*
X751772Y1206102D03*
X759252Y1217322D03*
Y1209842D03*
X755512Y1206102D03*
X759252Y1224803D03*
Y1228543D03*
X755512Y1232283D03*
Y1236023D03*
X766732Y1224803D03*
Y1228543D03*
X762992Y1232283D03*
Y1236023D03*
X751772Y1224803D03*
Y1228543D03*
X755512D03*
X751772Y1236023D03*
X762992Y1228543D03*
X751772Y1232283D03*
X766732D03*
Y1236023D03*
X759252Y1232283D03*
X762992Y1224803D03*
X759252Y1236023D03*
X755512Y1224803D03*
Y1250984D03*
Y1254724D03*
X759252Y1247243D03*
Y1243503D03*
X762992Y1250984D03*
Y1254724D03*
X766732Y1247243D03*
Y1243503D03*
X755512Y1239763D03*
X759252D03*
X762992D03*
X766732D03*
X751772Y1247243D03*
Y1243503D03*
Y1239763D03*
X766732Y1250984D03*
X755512Y1243503D03*
X762992D03*
Y1247243D03*
X751772Y1250984D03*
Y1254724D03*
X759252D03*
X766732D03*
X759252Y1250984D03*
X755512Y1247243D03*
X766732Y1258465D03*
X759252D03*
X751772D03*
X766568Y1348187D03*
X758688D03*
X754328D03*
X766568Y1360099D03*
X758688D03*
X754328D03*
Y1372385D03*
Y1384297D03*
X758688Y1372385D03*
X766568D03*
X758688Y1384297D03*
X766568D03*
X777953Y1075196D03*
X770473D03*
X774212Y1071455D03*
X774211Y1075196D03*
X774212Y1090157D03*
X777953Y1078936D03*
X781693D03*
X770473D03*
X774213Y1086417D03*
X774212Y1082677D03*
X770471Y1090157D03*
X781693Y1086417D03*
X777953D03*
X781693Y1090157D03*
X777953D03*
X781693Y1082676D03*
X774211Y1078936D03*
X770471Y1086417D03*
Y1082677D03*
X777953Y1082676D03*
X770472Y1097637D03*
X777953Y1093897D03*
X774212Y1101377D03*
X777953Y1105117D03*
X774213D03*
X770472Y1093897D03*
X781693D03*
Y1097637D03*
X777953D03*
X781693Y1105117D03*
X770472Y1101377D03*
X781693D03*
X777953D03*
X774212Y1097637D03*
X770472Y1105117D03*
X774212Y1093897D03*
X781693Y1112598D03*
X770472Y1123818D03*
X777953Y1120078D03*
X781693D03*
X774212Y1123818D03*
X770472Y1108858D03*
X774212D03*
X770472Y1116338D03*
X774212D03*
X777953Y1112598D03*
X774212D03*
X770472D03*
X781693Y1123818D03*
X777953D03*
X781693Y1116338D03*
X777953Y1108858D03*
X770472Y1120078D03*
X781693Y1108858D03*
X777953Y1116338D03*
X774212Y1120078D03*
X783563Y1140649D03*
X776083D03*
X779823D03*
X781693Y1127558D03*
X777953D03*
X774212Y1131299D03*
X770471D03*
X777953Y1135039D03*
X781693D03*
X770472Y1138779D03*
Y1127558D03*
Y1135039D03*
X781693Y1131299D03*
X774212Y1127558D03*
Y1135039D03*
X777953Y1131299D03*
X768602Y1140649D03*
X772342D03*
X783563Y1155610D03*
Y1148129D03*
X776083D03*
Y1151869D03*
X772342D03*
X776083Y1155610D03*
X772342Y1144389D03*
X768602Y1151869D03*
Y1144389D03*
X776083D03*
X779823Y1155610D03*
Y1148129D03*
X772342D03*
Y1155610D03*
X783563Y1151870D03*
X779823D03*
Y1144389D03*
X783563D03*
X768602Y1155610D03*
Y1148129D03*
X783563Y1170570D03*
Y1166830D03*
X776083D03*
Y1170570D03*
X772342Y1166830D03*
X768602Y1159350D03*
X776083D03*
X772342D03*
X768602Y1166830D03*
X779823D03*
Y1170570D03*
Y1159350D03*
X772342Y1170570D03*
X768602D03*
X783563Y1159350D03*
X776083Y1174310D03*
X772342D03*
X776083Y1178051D03*
Y1181791D03*
Y1185531D03*
X772342Y1181791D03*
X779823Y1185531D03*
Y1178051D03*
X783563Y1185531D03*
Y1178051D03*
X768602Y1181791D03*
Y1174310D03*
X772342Y1189271D03*
X783563D03*
X768602Y1185531D03*
X772342Y1178051D03*
X779823Y1189271D03*
X772342Y1185531D03*
X783563Y1174310D03*
X779823D03*
X783563Y1181791D03*
X768602Y1178051D03*
X779823Y1181791D03*
X783503Y1193011D03*
X776083Y1196751D03*
X772342D03*
X776083Y1193011D03*
X779823D03*
X781693Y1202362D03*
X777953D03*
X774212Y1198621D03*
X770472D03*
X781693D03*
X774212Y1202362D03*
X770472D03*
X777953Y1198621D03*
X768602Y1193011D03*
X772342D03*
X781693Y1217322D03*
X777953D03*
X774212Y1221062D03*
X770472D03*
X781693Y1209842D03*
X777953D03*
X774212Y1213582D03*
X770472D03*
X774212Y1206102D03*
X770472D03*
X777953D03*
X770472Y1209842D03*
X781693Y1213582D03*
X774212Y1209842D03*
X777953Y1221062D03*
X781693D03*
Y1206102D03*
X770472Y1217322D03*
X774212D03*
X777953Y1213582D03*
X781693Y1224803D03*
X777953D03*
X774212D03*
Y1228543D03*
X770472Y1236023D03*
Y1232283D03*
X781693D03*
X777953D03*
Y1236023D03*
X781693D03*
X770472Y1228543D03*
X781693D03*
X770472Y1224803D03*
X777953Y1228543D03*
X774212Y1232283D03*
Y1236023D03*
X770472Y1250984D03*
Y1254724D03*
X781693Y1250984D03*
X777953D03*
X774212Y1247243D03*
Y1243503D03*
X777953D03*
X781693D03*
X770472Y1239763D03*
X774212D03*
X777953Y1254724D03*
Y1239763D03*
X781693D03*
X777953Y1247243D03*
X770472Y1243503D03*
X781693Y1247243D03*
X770472D03*
X774212Y1250984D03*
Y1254724D03*
Y1258465D03*
X778808Y1348187D03*
X770928D03*
X778808Y1360099D03*
X770928D03*
X785434Y1090158D03*
Y1082677D03*
Y1101378D03*
Y1123819D03*
Y1116339D03*
Y1108859D03*
Y1131300D03*
Y1198621D03*
Y1221062D03*
Y1213582D03*
Y1206102D03*
Y1228543D03*
Y1247243D03*
Y1239762D03*
X879794Y837418D03*
Y840568D03*
Y843717D03*
Y846867D03*
Y850016D03*
Y853166D03*
Y856316D03*
Y859465D03*
Y862615D03*
Y865764D03*
Y872064D03*
Y878363D03*
Y868914D03*
Y875213D03*
Y881512D03*
Y884662D03*
X886093Y846867D03*
X882944Y840568D03*
X889243Y846867D03*
X882944D03*
X895542D03*
Y840568D03*
X892392D03*
X895542Y837418D03*
Y843717D03*
X889243Y837418D03*
X892392Y846867D03*
X889243Y843717D03*
X892392D03*
X886093Y840568D03*
X882944Y837418D03*
X886093Y843717D03*
Y837418D03*
X882944Y843717D03*
X892392Y837418D03*
X889243Y840568D03*
X892392Y859465D03*
Y856316D03*
X895542Y862615D03*
Y859465D03*
Y856316D03*
X886093Y850016D03*
X889243Y856316D03*
Y853166D03*
Y850016D03*
X882944D03*
X886093Y856316D03*
Y853166D03*
X882944D03*
X892392D03*
X895542Y850016D03*
Y853166D03*
X892392Y850016D03*
X889243Y859465D03*
X886093D03*
X892392Y862615D03*
X889243D03*
X882944Y856316D03*
Y859465D03*
X886093Y862615D03*
X882944D03*
X892392Y865764D03*
Y868914D03*
X889243Y875213D03*
X895542Y872064D03*
Y868914D03*
Y865764D03*
X882944Y868914D03*
X886093Y872064D03*
X882944Y875213D03*
X886093D03*
X892392Y878363D03*
X882944Y865764D03*
X886093Y868914D03*
X882944Y872064D03*
X889243D03*
X882944Y878363D03*
X889243D03*
X886093Y865764D03*
X889243Y868914D03*
Y865764D03*
X892392Y872064D03*
X895542Y878363D03*
X886093D03*
X892392Y875213D03*
X895542D03*
X882944Y881512D03*
X886093D03*
X882944Y884662D03*
X886093D03*
X889243Y881512D03*
Y884662D03*
X892392Y881512D03*
Y884662D03*
X895542Y881512D03*
Y884662D03*
X904991Y840568D03*
X908140Y846867D03*
X911290D03*
X908140Y843717D03*
X911290D03*
X908140Y840568D03*
X901841D03*
Y843717D03*
X904991Y837418D03*
X901841Y846867D03*
X898692Y840568D03*
Y837418D03*
X901841D03*
X911290D03*
Y840568D03*
X908140Y837418D03*
X904991Y843717D03*
Y846867D03*
X898692Y843717D03*
Y846867D03*
X901841Y853166D03*
X904991D03*
X898692D03*
X901841Y850016D03*
X904991D03*
X898692D03*
X901841Y862615D03*
X904991D03*
X908140D03*
X911290D03*
X898692D03*
X901841Y859465D03*
X904991D03*
X908140D03*
X911290D03*
X898692D03*
X901841Y856316D03*
X904991D03*
X908140D03*
X911290D03*
X898692D03*
X911290Y853166D03*
Y850016D03*
X908140Y853166D03*
Y850016D03*
X901841Y875213D03*
X904991D03*
X911290Y872064D03*
X908140Y875213D03*
X898692D03*
X901841Y872064D03*
X904991D03*
X908140D03*
X898692D03*
X901841Y868914D03*
X904991D03*
X908140D03*
X911290D03*
X898692D03*
X901841Y865764D03*
X904991D03*
X908140D03*
X911290D03*
X898692D03*
Y878363D03*
X901841D03*
X904991D03*
X911290Y875213D03*
X908140Y878363D03*
X911290D03*
X898692Y881512D03*
Y884662D03*
X901841Y881512D03*
Y884662D03*
X904991D03*
Y881512D03*
X908140Y884662D03*
Y881512D03*
X911290Y884662D03*
Y881512D03*
X920349Y450340D03*
X917549D03*
X920349Y453884D03*
Y457427D03*
X917549Y453884D03*
Y457427D03*
X920349Y460970D03*
X917549D03*
X927038Y837418D03*
X914440Y840568D03*
X917589D03*
Y837418D03*
X914440D03*
Y843717D03*
Y846867D03*
X920739Y843717D03*
X917589D03*
X923888Y837418D03*
X920739Y840568D03*
Y837418D03*
X917589Y846867D03*
X923888D03*
X927038D03*
X923888Y843717D03*
X920739Y846867D03*
X927038Y843717D03*
Y840568D03*
X923888D03*
X914440Y859465D03*
Y856316D03*
X917589Y859465D03*
Y856316D03*
X920739D03*
Y853166D03*
X917589Y850016D03*
Y853166D03*
X914440D03*
Y850016D03*
X920739Y862615D03*
X923888Y850016D03*
X920739Y859465D03*
X927038Y850016D03*
Y856316D03*
X923888Y853166D03*
Y856316D03*
X927038Y853166D03*
X914440Y862615D03*
X927038Y859465D03*
X923888D03*
X920739Y850016D03*
X927038Y862615D03*
X923888D03*
X917589D03*
X914440Y868914D03*
Y865764D03*
X923888D03*
X917589D03*
X920739D03*
X927038Y875213D03*
X923888D03*
X920739D03*
X927038Y872064D03*
X923888D03*
X920739D03*
X927038Y868914D03*
X923888D03*
X917589Y872064D03*
Y868914D03*
X920739D03*
X927038Y865764D03*
X914440Y872064D03*
Y875213D03*
X920739Y878363D03*
X923888D03*
X914440D03*
X927038D03*
X917589D03*
Y875213D03*
X914440Y884662D03*
X917589D03*
X914440Y881512D03*
X917589D03*
X920739Y884662D03*
X923888D03*
X920739Y881512D03*
X927038Y884662D03*
X923888Y881512D03*
X927038D03*
X962380Y617861D03*
X958837D03*
X962380Y620661D03*
X958837D03*
X969467D03*
X965923Y617861D03*
Y620661D03*
X969467Y617861D03*
X1057381Y1092027D03*
Y1084547D03*
Y1088287D03*
Y1095767D03*
Y1103247D03*
Y1106988D03*
Y1099507D03*
Y1118208D03*
Y1110728D03*
Y1114468D03*
Y1121948D03*
Y1140649D03*
Y1133169D03*
Y1125688D03*
Y1129429D03*
Y1136909D03*
Y1151870D03*
Y1144389D03*
Y1148129D03*
X1054881Y1170570D03*
X1057381Y1159350D03*
X1057380Y1170570D03*
X1054881Y1178050D03*
X1059251Y1187401D03*
Y1183661D03*
X1057380Y1178051D03*
X1059251Y1194881D03*
Y1202362D03*
X1055510Y1198622D03*
Y1191142D03*
X1059251Y1198621D03*
Y1191141D03*
Y1209842D03*
Y1217322D03*
X1055510Y1221063D03*
Y1213583D03*
Y1206103D03*
X1059251Y1221062D03*
Y1206102D03*
Y1213582D03*
Y1232283D03*
Y1236023D03*
Y1224803D03*
X1055510Y1228542D03*
X1059251Y1228543D03*
Y1243503D03*
Y1250984D03*
X1055509Y1239762D03*
Y1247242D03*
X1059251Y1247243D03*
Y1239763D03*
X1052473Y1348187D03*
Y1360099D03*
Y1384297D03*
Y1372385D03*
X1068602Y1073326D03*
X1072342D03*
X1064862D03*
X1072342Y1088287D03*
Y1084547D03*
Y1080807D03*
X1064861Y1077066D03*
X1061121Y1092027D03*
X1068602D03*
X1064862Y1088287D03*
X1068602D03*
X1061121Y1084547D03*
X1064862D03*
Y1080807D03*
X1061121Y1080806D03*
Y1077066D03*
X1068602D03*
X1064862Y1092027D03*
X1072342Y1077066D03*
X1068602Y1084547D03*
Y1080807D03*
X1061121Y1088287D03*
X1072342Y1092027D03*
Y1099507D03*
Y1106988D03*
Y1103247D03*
X1061121Y1095767D03*
X1068602D03*
X1064862Y1106988D03*
X1068602D03*
X1061121Y1103247D03*
X1064862D03*
Y1099507D03*
X1068602D03*
X1072342Y1095767D03*
X1061121Y1106988D03*
X1068602Y1103247D03*
X1064862Y1095767D03*
X1061121Y1099507D03*
X1072342Y1121948D03*
Y1118208D03*
Y1114468D03*
Y1110728D03*
X1064862Y1121948D03*
X1068602D03*
X1061121Y1118208D03*
X1064862Y1114468D03*
X1068602D03*
X1061121Y1110728D03*
Y1114468D03*
X1068602Y1110728D03*
Y1118208D03*
X1064862Y1110728D03*
Y1118208D03*
X1061121Y1121948D03*
X1072342Y1140649D03*
Y1129429D03*
Y1125688D03*
X1061121D03*
Y1140649D03*
X1064862D03*
X1068602D03*
X1064862Y1136909D03*
X1061121Y1133169D03*
X1064862Y1129429D03*
X1068602D03*
X1064862Y1125688D03*
X1068602D03*
X1061121Y1129429D03*
X1064862Y1133169D03*
X1061121Y1136909D03*
X1072342Y1155610D03*
Y1151869D03*
X1064862Y1155610D03*
X1068602D03*
X1061121Y1151870D03*
X1064862D03*
Y1148129D03*
X1068602Y1151869D03*
X1061121Y1144389D03*
X1064862D03*
X1061121Y1148129D03*
X1072342Y1166830D03*
X1064861Y1170570D03*
X1068602D03*
X1064861Y1166830D03*
X1068602D03*
X1061121Y1159350D03*
X1064862D03*
X1061122Y1166830D03*
X1061120Y1170570D03*
X1072342Y1181791D03*
Y1174310D03*
X1061120Y1181791D03*
X1064861D03*
X1068602D03*
Y1174310D03*
X1064861Y1178051D03*
X1061120Y1174310D03*
X1064861D03*
X1074212Y1187401D03*
X1062991D03*
Y1183661D03*
X1066732D03*
X1070472D03*
X1074212D03*
X1070472Y1187401D03*
X1066732D03*
X1072342Y1178051D03*
X1068602D03*
X1061120D03*
X1074212Y1191141D03*
Y1198621D03*
Y1194881D03*
Y1202362D03*
X1070472Y1191141D03*
X1066732D03*
X1070472Y1198621D03*
X1066732D03*
X1062991Y1194881D03*
Y1202362D03*
Y1198621D03*
X1066732Y1194881D03*
X1062991Y1191141D03*
X1070472Y1194881D03*
Y1202362D03*
X1066732D03*
X1074212Y1206102D03*
X1066732D03*
X1070472D03*
X1074212Y1217322D03*
Y1209842D03*
Y1213582D03*
X1070472D03*
X1066732D03*
X1062991Y1209842D03*
Y1217322D03*
X1074212Y1221062D03*
X1066732D03*
X1070472D03*
Y1217322D03*
X1066732D03*
X1062991Y1221062D03*
Y1206102D03*
X1070472Y1209842D03*
X1062991Y1213582D03*
X1066732Y1209842D03*
X1070472Y1236023D03*
Y1232283D03*
X1066732Y1228543D03*
Y1224803D03*
X1074212D03*
Y1228543D03*
X1062991Y1236023D03*
Y1232283D03*
Y1224803D03*
X1070472Y1228543D03*
X1066732Y1236023D03*
Y1232283D03*
X1074212Y1236023D03*
Y1232283D03*
X1070472Y1224803D03*
X1062991Y1228543D03*
X1070472Y1250984D03*
Y1254724D03*
X1066732Y1247243D03*
X1074212D03*
X1066732Y1239763D03*
Y1243503D03*
X1070472Y1239763D03*
X1074212D03*
Y1243503D03*
X1062991Y1250984D03*
Y1254724D03*
Y1243503D03*
X1074212Y1250984D03*
X1066732Y1254724D03*
X1070472Y1247243D03*
X1074212Y1254724D03*
X1062991Y1247243D03*
X1070472Y1243503D03*
X1062991Y1239763D03*
X1066732Y1250984D03*
X1074212Y1258465D03*
X1066732D03*
X1072593Y1348187D03*
X1064713D03*
X1060353D03*
X1072593Y1360099D03*
X1064713D03*
X1060353D03*
X1072593Y1384297D03*
Y1372385D03*
X1064713D03*
Y1384297D03*
X1060353D03*
Y1372385D03*
X1072593Y1396583D03*
X1064713D03*
X1072593Y1408495D03*
X1064713D03*
X1083562Y1073326D03*
X1076082D03*
X1089171Y1071455D03*
X1089172Y1075196D03*
X1079822Y1073326D03*
X1083562Y1092027D03*
Y1088287D03*
Y1077066D03*
X1079822Y1088287D03*
Y1084547D03*
Y1080807D03*
X1076082Y1092027D03*
Y1088287D03*
Y1077066D03*
X1089172Y1082677D03*
Y1086417D03*
Y1090157D03*
Y1078936D03*
X1079822Y1092027D03*
X1083562Y1084547D03*
X1079822Y1077066D03*
X1076082Y1084547D03*
Y1080807D03*
X1083562D03*
X1089172Y1097637D03*
Y1093897D03*
X1083562Y1099507D03*
Y1095767D03*
X1087302Y1106988D03*
X1079822D03*
X1083562D03*
X1079822Y1103247D03*
Y1099507D03*
X1076082Y1106988D03*
Y1095767D03*
X1089172Y1101377D03*
Y1105117D03*
X1076082Y1103247D03*
X1079822Y1095767D03*
X1076082Y1099507D03*
X1083562Y1103247D03*
Y1121948D03*
Y1118208D03*
X1087302D03*
X1079822Y1114468D03*
X1083562Y1110728D03*
X1087302D03*
X1091043D03*
Y1121948D03*
Y1118208D03*
Y1114468D03*
X1076082D03*
X1089172Y1108858D03*
X1079822Y1118208D03*
X1076082Y1121948D03*
Y1118208D03*
X1079822Y1110728D03*
X1083562Y1114468D03*
X1087302D03*
X1076082Y1110728D03*
X1091043Y1125688D03*
Y1140649D03*
X1083562Y1136909D03*
X1087302D03*
X1079822Y1129429D03*
X1083562Y1129428D03*
X1087302D03*
X1079822Y1140649D03*
X1083562D03*
X1087302D03*
X1091043Y1136909D03*
Y1133169D03*
Y1129429D03*
X1076082Y1133169D03*
Y1129429D03*
Y1125688D03*
Y1140649D03*
X1087302Y1151870D03*
Y1155610D03*
Y1148129D03*
X1083562Y1144389D03*
X1087302D03*
X1076082Y1155610D03*
Y1151870D03*
Y1148129D03*
Y1144389D03*
X1091043Y1151870D03*
Y1148129D03*
Y1144389D03*
X1083562Y1148129D03*
X1079822Y1144389D03*
Y1148129D03*
X1083562Y1151870D03*
X1079822Y1155610D03*
X1087302Y1170570D03*
Y1166830D03*
Y1159350D03*
X1079822Y1170570D03*
Y1166830D03*
X1091043Y1170570D03*
X1076082Y1159350D03*
X1091043Y1166830D03*
Y1159350D03*
X1083562D03*
X1079822Y1174310D03*
Y1178050D03*
X1081692Y1179921D03*
X1083562Y1181791D03*
X1087302D03*
Y1178051D03*
Y1174310D03*
X1076082Y1181791D03*
Y1178051D03*
Y1174310D03*
X1077952Y1183661D03*
X1081692D03*
X1085432D03*
X1089172Y1187401D03*
X1085432D03*
X1091043Y1185531D03*
X1077952Y1187401D03*
X1081692D03*
X1091043Y1181791D03*
Y1178051D03*
Y1174310D03*
X1077952Y1191141D03*
Y1198621D03*
X1081692D03*
Y1191141D03*
X1085432Y1194881D03*
X1089172D03*
X1085432Y1202362D03*
X1089172D03*
X1077952Y1194881D03*
Y1202362D03*
X1089172Y1191141D03*
Y1198621D03*
X1081692Y1202362D03*
X1085432Y1198621D03*
X1081692Y1194881D03*
X1085432Y1191141D03*
X1077952Y1206102D03*
Y1213582D03*
X1081692Y1206102D03*
Y1213582D03*
X1085432Y1209842D03*
X1089172D03*
X1077952Y1221062D03*
X1089172Y1217322D03*
Y1221062D03*
X1081692D03*
X1085432D03*
Y1217322D03*
X1089172Y1206102D03*
X1077952Y1209842D03*
X1081692D03*
Y1217322D03*
X1089172Y1213582D03*
X1077952Y1217322D03*
X1085432Y1206102D03*
Y1213582D03*
X1077952Y1232283D03*
Y1236023D03*
X1085432Y1232283D03*
Y1236023D03*
X1081692Y1228543D03*
Y1224803D03*
X1089172D03*
Y1228543D03*
Y1232283D03*
X1081692D03*
Y1236023D03*
X1089172D03*
X1077952Y1224803D03*
Y1228543D03*
X1085432Y1224803D03*
Y1228543D03*
X1077952Y1250984D03*
Y1254724D03*
Y1239763D03*
X1081692Y1247243D03*
X1085432Y1254724D03*
X1081692Y1239763D03*
Y1243503D03*
X1085432Y1250984D03*
Y1239763D03*
X1089172D03*
Y1243503D03*
Y1247243D03*
X1077952Y1243503D03*
X1081692Y1250984D03*
X1077952Y1247243D03*
X1081692Y1254724D03*
X1085432Y1243503D03*
X1089172Y1254724D03*
Y1250984D03*
X1085432Y1247243D03*
X1089173Y1258465D03*
X1081692D03*
X1089193Y1348187D03*
X1084833D03*
X1076953D03*
X1089193Y1360099D03*
X1084833D03*
X1076953D03*
X1089193Y1384297D03*
Y1372385D03*
X1084833Y1384297D03*
Y1372385D03*
X1076953Y1384297D03*
Y1372385D03*
X1089193Y1396583D03*
X1084833D03*
X1076953D03*
X1089193Y1408495D03*
X1084833D03*
X1076953D03*
X1092913Y1075196D03*
X1107873D03*
X1100393D03*
X1104132Y1071455D03*
X1096652D03*
X1096653Y1075196D03*
X1104133D03*
X1092913Y1078936D03*
Y1090157D03*
X1104133Y1086417D03*
Y1090157D03*
Y1082677D03*
X1107873Y1090157D03*
Y1078936D03*
X1100393D03*
Y1090157D03*
X1096653Y1082677D03*
Y1086417D03*
Y1090157D03*
X1100393Y1082677D03*
X1104133Y1078936D03*
X1107873Y1082677D03*
Y1086417D03*
X1092913Y1082677D03*
X1100393Y1086417D03*
X1092913D03*
X1096653Y1078936D03*
X1092913Y1105117D03*
X1104133Y1097637D03*
X1096653D03*
X1100393Y1105117D03*
X1104133Y1093897D03*
X1100393Y1101376D03*
X1096653Y1093897D03*
X1092913Y1101376D03*
X1107873Y1105117D03*
X1092913Y1093897D03*
Y1097637D03*
X1107873Y1093897D03*
Y1097637D03*
X1104133Y1101377D03*
X1100393Y1097637D03*
Y1093897D03*
X1096653Y1101377D03*
X1104133Y1105117D03*
X1096653D03*
X1107873Y1101376D03*
X1094783Y1110728D03*
Y1121948D03*
X1098523D03*
X1102263D03*
X1106003D03*
X1094783Y1118208D03*
X1098523D03*
X1102263D03*
X1106003D03*
X1094783Y1114468D03*
X1107873Y1108858D03*
X1104133D03*
X1100393D03*
X1096653D03*
X1092913D03*
X1102263Y1114468D03*
X1098523D03*
X1106003D03*
X1098523Y1140649D03*
X1102263D03*
X1094783Y1136909D03*
X1102263D03*
X1094783Y1133169D03*
X1098523D03*
X1102263D03*
X1094783Y1129429D03*
X1098523D03*
X1102263D03*
X1094783Y1125688D03*
X1098523D03*
X1102263D03*
X1106003D03*
X1094783Y1140649D03*
X1106003D03*
Y1136909D03*
X1098523D03*
X1106003Y1129429D03*
Y1133169D03*
X1094783Y1151870D03*
Y1155610D03*
X1102263Y1151870D03*
X1094783Y1148129D03*
Y1144389D03*
X1102263D03*
X1106003Y1148129D03*
Y1155610D03*
Y1151869D03*
Y1144389D03*
X1098523D03*
Y1151870D03*
X1102263Y1148129D03*
Y1155610D03*
Y1170570D03*
X1094783D03*
Y1159350D03*
X1102263D03*
X1094783Y1166830D03*
X1106003D03*
Y1170570D03*
Y1159350D03*
X1102263Y1166830D03*
X1098523Y1159350D03*
Y1170570D03*
X1102263Y1178051D03*
X1094783Y1181791D03*
X1102263Y1185531D03*
X1094783Y1174310D03*
Y1178051D03*
X1106003Y1181791D03*
Y1174310D03*
X1092913Y1187401D03*
X1106003Y1178051D03*
Y1185531D03*
X1098523D03*
X1102263Y1174310D03*
X1098523Y1178051D03*
X1102263Y1181791D03*
X1098523Y1196751D03*
Y1193011D03*
X1106003Y1200491D03*
Y1196751D03*
Y1204232D03*
X1102263D03*
X1098523D03*
Y1200491D03*
X1102263D03*
Y1196751D03*
Y1193011D03*
X1092913Y1191141D03*
Y1194881D03*
Y1198621D03*
Y1202362D03*
X1106003Y1193011D03*
X1098523Y1207972D03*
X1102263D03*
X1106003D03*
Y1211712D03*
X1102263D03*
X1098523D03*
Y1219192D03*
X1106003D03*
X1092913Y1206102D03*
Y1209842D03*
Y1213582D03*
Y1217322D03*
X1107873Y1221062D03*
X1104133D03*
X1100393D03*
X1096653D03*
X1092913D03*
X1106003Y1215452D03*
X1098523D03*
X1102263D03*
X1092913Y1232283D03*
Y1236023D03*
X1107873Y1232283D03*
X1104133Y1224803D03*
Y1228543D03*
X1107873Y1236023D03*
X1100393Y1232283D03*
Y1236023D03*
X1096653Y1228543D03*
Y1224803D03*
X1100393Y1228543D03*
X1104133Y1236023D03*
X1092913Y1224803D03*
X1104133Y1232283D03*
X1107873Y1224803D03*
X1096653Y1236023D03*
X1100393Y1224803D03*
X1107873Y1228543D03*
X1096653Y1232283D03*
X1092913Y1228543D03*
Y1250984D03*
Y1254724D03*
Y1239763D03*
X1100393Y1250984D03*
Y1254724D03*
X1104133Y1247243D03*
X1107873Y1250984D03*
Y1254724D03*
X1100393Y1239763D03*
X1104133D03*
X1107873D03*
X1104133Y1243503D03*
X1096653Y1247243D03*
Y1239763D03*
Y1243503D03*
Y1254724D03*
X1104133D03*
X1092913Y1247243D03*
X1096653Y1250984D03*
X1092913Y1243503D03*
X1107873D03*
X1100393D03*
X1107873Y1247243D03*
X1100393D03*
X1104133Y1250984D03*
Y1258465D03*
X1096653D03*
X1101433Y1348187D03*
X1097073D03*
X1101433Y1360099D03*
X1097073D03*
X1101433Y1384297D03*
Y1372385D03*
X1097073D03*
Y1384297D03*
X1101433Y1396583D03*
X1097073D03*
X1101433Y1408495D03*
X1097073D03*
X1115354Y1075196D03*
X1122834D03*
X1119093Y1071455D03*
X1111612D03*
X1111613Y1075196D03*
X1119094D03*
X1115354Y1090157D03*
Y1078936D03*
X1119094Y1082677D03*
Y1086417D03*
Y1090157D03*
X1122834D03*
Y1078936D03*
X1111613Y1082677D03*
Y1086417D03*
Y1090157D03*
X1122834Y1086417D03*
X1119094Y1078936D03*
X1115354Y1082677D03*
X1111613Y1078936D03*
X1115354Y1086417D03*
X1122834Y1082677D03*
X1119094Y1097637D03*
X1115354Y1101376D03*
X1111613Y1093897D03*
Y1097637D03*
X1122834Y1105117D03*
X1119094Y1093897D03*
X1122834D03*
X1115354D03*
X1122834Y1097637D03*
X1115354D03*
X1119094Y1101377D03*
X1111613D03*
X1119094Y1105117D03*
X1111613D03*
X1122834Y1101376D03*
X1115354Y1105117D03*
X1117224Y1121948D03*
Y1118208D03*
X1120964D03*
X1109743Y1121948D03*
X1113484D03*
X1109743Y1118208D03*
X1113484D03*
X1124704Y1121948D03*
Y1118208D03*
X1120964Y1121948D03*
X1122834Y1108858D03*
X1119094D03*
X1115354D03*
X1111613D03*
X1117224Y1114468D03*
X1113484D03*
X1120964D03*
X1124704D03*
X1109743D03*
Y1136909D03*
X1124704Y1125688D03*
Y1140649D03*
Y1133169D03*
X1113484D03*
X1117224D03*
X1120964D03*
X1109743Y1125688D03*
X1120964D03*
X1117224D03*
X1113484D03*
X1120964Y1140649D03*
X1117224D03*
X1113484D03*
X1109743Y1129429D03*
Y1133169D03*
X1120964Y1129429D03*
X1113484D03*
X1117224D03*
X1124704D03*
Y1136909D03*
X1113484D03*
X1117224D03*
X1120964D03*
X1109743Y1140649D03*
X1113484Y1155610D03*
X1109743Y1144389D03*
X1120964Y1155610D03*
X1109743Y1151869D03*
X1120964Y1148129D03*
X1113484D03*
X1117224D03*
X1124704D03*
Y1144389D03*
X1113484D03*
X1117224D03*
X1120964D03*
X1113484Y1151870D03*
X1117224D03*
X1120964D03*
X1124704D03*
Y1155610D03*
X1109743D03*
Y1148129D03*
X1117224Y1155610D03*
Y1170570D03*
X1109743D03*
X1113484Y1166830D03*
X1117224Y1159350D03*
X1120964Y1166830D03*
X1109743Y1159350D03*
X1124704Y1170570D03*
Y1159350D03*
X1113484D03*
X1120964D03*
X1109743Y1166830D03*
X1113484Y1170570D03*
X1117224Y1166830D03*
X1120964Y1170570D03*
X1124704Y1166830D03*
X1109743Y1189271D03*
X1113484D03*
X1117224D03*
X1120964D03*
X1113484Y1181791D03*
X1117224D03*
X1120964D03*
X1124704Y1189271D03*
Y1181791D03*
X1109743Y1178051D03*
X1120964Y1174310D03*
X1109743Y1185531D03*
X1113484Y1174310D03*
Y1178051D03*
X1117224D03*
X1120964D03*
X1124704D03*
X1120964Y1185531D03*
X1113484D03*
X1117224D03*
X1124704D03*
X1109743Y1174310D03*
Y1181791D03*
X1117224Y1174310D03*
X1124704D03*
Y1204232D03*
Y1196751D03*
X1120964Y1204232D03*
X1117224D03*
X1113484D03*
X1109743D03*
Y1193011D03*
Y1196751D03*
Y1200491D03*
X1113484Y1196751D03*
X1117224D03*
X1120964D03*
X1117224Y1200491D03*
X1120964D03*
X1113484D03*
X1124704D03*
X1120964Y1193011D03*
X1117224D03*
X1113484D03*
X1124704D03*
X1113484Y1207972D03*
X1117224D03*
X1120964D03*
X1109743Y1211712D03*
Y1207972D03*
X1124704Y1211712D03*
Y1207972D03*
X1122834Y1221062D03*
X1119094D03*
X1115354D03*
X1111613D03*
X1124704Y1215452D03*
X1120964D03*
Y1211712D03*
X1117224Y1215452D03*
X1109743D03*
X1113484Y1211712D03*
X1111613Y1217322D03*
X1115354D03*
X1117224Y1211712D03*
X1122834Y1224803D03*
Y1232283D03*
Y1236023D03*
X1119094Y1224803D03*
Y1228543D03*
X1115354Y1232283D03*
Y1236023D03*
X1111613Y1228543D03*
Y1224803D03*
X1119094Y1232283D03*
X1115354Y1228543D03*
X1111613Y1232283D03*
X1119094Y1236023D03*
X1115354Y1224803D03*
X1111613Y1236023D03*
X1122834Y1228543D03*
X1115354Y1250984D03*
Y1254724D03*
X1119094Y1247243D03*
Y1243503D03*
X1122834Y1254724D03*
Y1250984D03*
Y1239763D03*
X1115354D03*
X1119094D03*
X1111613Y1247243D03*
Y1243503D03*
Y1239763D03*
X1122834Y1243503D03*
X1119094Y1250984D03*
X1111613Y1254724D03*
X1119094D03*
X1122834Y1247243D03*
X1115354Y1243503D03*
Y1247243D03*
X1111613Y1250984D03*
X1119094Y1258465D03*
X1111614D03*
X1113673Y1348187D03*
X1121553D03*
X1109313D03*
X1113673Y1360099D03*
X1121553D03*
X1109313D03*
X1113673Y1372385D03*
Y1384297D03*
X1121553Y1372385D03*
Y1384297D03*
X1109313D03*
Y1372385D03*
X1113673Y1396583D03*
X1121553D03*
X1109313D03*
X1113673Y1408495D03*
X1121553D03*
X1109313D03*
X1130314Y1075196D03*
X1137795D03*
X1134053Y1071455D03*
X1126573D03*
X1126574Y1075196D03*
X1134054D03*
X1126574Y1090157D03*
Y1086417D03*
Y1082677D03*
X1130314Y1090157D03*
Y1078936D03*
X1134054Y1082677D03*
Y1086417D03*
Y1090157D03*
X1137795D03*
Y1078936D03*
X1134054D03*
X1126574D03*
X1130314Y1086417D03*
Y1082677D03*
X1137795Y1086417D03*
Y1082677D03*
X1126574Y1093897D03*
X1130314Y1105117D03*
X1134054Y1093897D03*
X1130314Y1101376D03*
X1134054Y1097637D03*
X1137794Y1105117D03*
X1126574Y1097637D03*
X1137794Y1101376D03*
X1126574Y1101377D03*
X1130314Y1097637D03*
Y1093897D03*
X1137795D03*
Y1097637D03*
X1134054Y1101377D03*
X1126574Y1105117D03*
X1134054D03*
X1139665Y1121948D03*
X1128444Y1114468D03*
X1130314Y1112598D03*
X1128444Y1118208D03*
X1132184D03*
X1135924D03*
X1132184Y1121948D03*
X1135924D03*
X1128444D03*
X1139665Y1118208D03*
X1137795Y1108858D03*
X1134054D03*
X1130314D03*
X1126574D03*
X1139665Y1114468D03*
X1135925D03*
X1132184D03*
X1139665Y1125688D03*
X1128444Y1140649D03*
X1132184D03*
X1135924D03*
X1132184Y1125688D03*
X1128444D03*
X1135924D03*
Y1133169D03*
X1132184D03*
X1128444D03*
X1139665D03*
Y1140649D03*
X1132184Y1129429D03*
X1128444D03*
X1135924D03*
X1139665D03*
Y1136909D03*
X1135924D03*
X1132184D03*
X1128444D03*
X1135924Y1148129D03*
X1132184D03*
X1128444D03*
X1139665D03*
X1128444Y1155610D03*
X1135924D03*
X1128444Y1144389D03*
X1135924D03*
X1132184D03*
X1139665D03*
X1135925Y1151870D03*
X1132184D03*
X1128444D03*
X1139665D03*
Y1155610D03*
X1132184D03*
X1139665Y1170570D03*
Y1159350D03*
X1132184Y1170570D03*
X1135925Y1166830D03*
X1128444D03*
X1132184Y1159350D03*
X1139665Y1166830D03*
X1135924Y1170570D03*
X1128444D03*
X1132184Y1166830D03*
X1128444Y1159350D03*
X1135924D03*
Y1181791D03*
X1132184D03*
X1128444D03*
X1135924Y1189271D03*
X1132184D03*
X1128444D03*
Y1174310D03*
X1135924D03*
X1139665Y1181791D03*
Y1189271D03*
Y1178051D03*
X1135924D03*
X1132184D03*
X1128444D03*
X1139665Y1185531D03*
X1132184D03*
X1128444D03*
X1135924D03*
X1139665Y1174310D03*
X1132184D03*
X1139665Y1196751D03*
Y1204232D03*
X1135924D03*
Y1196751D03*
X1132184D03*
X1128444D03*
Y1204232D03*
X1132184D03*
Y1200491D03*
X1128444D03*
X1135924D03*
X1139665D03*
X1128444Y1193011D03*
X1132184D03*
X1135924D03*
X1139665D03*
Y1207972D03*
X1132184Y1211712D03*
X1134054Y1217322D03*
X1135924Y1207972D03*
X1132184D03*
X1128444D03*
X1137795Y1221062D03*
X1134054D03*
X1130314D03*
X1126574D03*
X1139665Y1211712D03*
X1135925D03*
Y1215452D03*
X1128444D03*
X1132184D03*
X1128444Y1211712D03*
X1126574Y1224803D03*
Y1228543D03*
X1137795Y1232283D03*
Y1236023D03*
X1134054Y1228543D03*
Y1224803D03*
X1130314Y1232283D03*
Y1236023D03*
X1134054D03*
X1137795Y1228543D03*
X1134054Y1232283D03*
X1126574D03*
Y1236023D03*
X1137795Y1224803D03*
X1130314Y1228543D03*
Y1224803D03*
X1126574Y1243503D03*
Y1247243D03*
Y1239763D03*
X1130314Y1250984D03*
Y1254724D03*
X1134054Y1247243D03*
Y1243503D03*
X1137795Y1250984D03*
Y1254724D03*
Y1239763D03*
X1134054D03*
X1130314D03*
X1126574Y1254724D03*
X1137795Y1243503D03*
X1130314Y1247243D03*
X1126574Y1250984D03*
X1137795Y1247243D03*
X1130314Y1243503D03*
X1134054Y1250984D03*
Y1254724D03*
X1134055Y1258465D03*
X1126574D03*
X1138153Y1348187D03*
X1133793D03*
X1125913D03*
X1138153Y1360099D03*
X1133793D03*
X1125913D03*
X1138153Y1384297D03*
Y1372385D03*
X1133793Y1384297D03*
Y1372385D03*
X1125913Y1384297D03*
Y1372385D03*
X1138153Y1396583D03*
X1133793D03*
X1125913D03*
X1138153Y1408495D03*
X1133793D03*
X1125913D03*
X1152755Y1075196D03*
X1145275D03*
X1156494Y1071455D03*
X1149014Y1071454D03*
X1141534Y1071455D03*
X1141535Y1075196D03*
X1156494D03*
X1149014Y1075195D03*
X1141535Y1082677D03*
Y1086417D03*
Y1090157D03*
X1149015Y1082677D03*
Y1086417D03*
X1152755Y1090157D03*
X1156495D03*
Y1086417D03*
X1149015Y1090157D03*
X1152755Y1078936D03*
X1156495Y1082677D03*
X1145275Y1090157D03*
Y1078936D03*
Y1086417D03*
Y1082677D03*
X1141535Y1078936D03*
X1149014Y1078935D03*
X1156494Y1078936D03*
X1152754Y1086416D03*
Y1082676D03*
X1145275Y1105117D03*
X1141535Y1093897D03*
X1145275Y1101376D03*
X1141535Y1097637D03*
Y1101377D03*
X1149015D03*
X1152755Y1093897D03*
Y1097637D03*
X1156495Y1101377D03*
X1145275Y1093897D03*
Y1097637D03*
X1141535Y1105117D03*
X1149015D03*
X1156495D03*
X1149014Y1097637D03*
X1156494Y1093897D03*
X1152755Y1101376D03*
X1156494Y1097637D03*
X1149014Y1093897D03*
X1152755Y1105117D03*
X1150885Y1121948D03*
X1143405D03*
Y1118208D03*
Y1114468D03*
X1154625Y1121948D03*
X1156495Y1108858D03*
X1152755D03*
X1149015D03*
X1145275D03*
X1141535D03*
X1154625Y1118208D03*
X1150885D03*
X1154625Y1114468D03*
X1150885D03*
X1154625Y1125688D03*
X1150885Y1133464D03*
X1154625Y1133169D03*
X1143503Y1132677D03*
X1143405Y1140649D03*
Y1125688D03*
X1150885Y1140649D03*
X1154625D03*
X1150885Y1125688D03*
X1154625Y1129429D03*
X1150885D03*
X1143405D03*
Y1136909D03*
X1154625D03*
X1150885D03*
X1143405Y1148129D03*
X1150885D03*
X1154625D03*
X1143405Y1155610D03*
X1154625D03*
X1143405Y1144389D03*
X1150885Y1151869D03*
X1154625D03*
Y1144389D03*
X1150885D03*
X1143405Y1151870D03*
X1150885Y1155610D03*
X1154625Y1166830D03*
X1150885Y1170570D03*
X1143405Y1166830D03*
X1150885Y1159350D03*
X1143405Y1170570D03*
X1154625Y1159350D03*
X1143405D03*
X1150885Y1166830D03*
X1154625Y1170570D03*
X1143405Y1181791D03*
X1154625D03*
X1150885D03*
Y1189271D03*
X1154625D03*
X1143405D03*
Y1174310D03*
X1154625D03*
X1143405Y1178051D03*
Y1185531D03*
X1154625D03*
X1150885D03*
X1154625Y1178051D03*
X1150885D03*
Y1174310D03*
Y1196751D03*
X1154625Y1204232D03*
X1150885D03*
X1154625Y1196751D03*
X1143405D03*
Y1204232D03*
Y1200491D03*
X1154625D03*
X1150885D03*
Y1193011D03*
X1154625D03*
X1143405D03*
X1150885Y1207972D03*
X1154625D03*
Y1211712D03*
X1143405Y1207972D03*
X1149015Y1221062D03*
X1156495D03*
X1152755D03*
X1145275D03*
X1141535D03*
X1143405Y1211712D03*
Y1215452D03*
X1150885Y1211712D03*
Y1215452D03*
X1154625D03*
X1156495Y1217322D03*
X1152755D03*
X1149015Y1236023D03*
Y1232283D03*
X1152755Y1228543D03*
X1145275Y1224803D03*
X1156495Y1232283D03*
Y1236023D03*
X1141535Y1228543D03*
Y1224803D03*
X1152755Y1232283D03*
Y1236023D03*
X1156495Y1228543D03*
Y1224803D03*
X1149015Y1228543D03*
Y1224803D03*
X1145275Y1232283D03*
Y1236023D03*
X1141535D03*
X1145275Y1228543D03*
X1152755Y1224803D03*
X1141535Y1232283D03*
Y1239763D03*
Y1243503D03*
Y1247243D03*
X1152755Y1254724D03*
Y1250984D03*
X1149015Y1247243D03*
Y1243503D03*
Y1239763D03*
X1152755D03*
X1156495D03*
Y1243503D03*
Y1247243D03*
X1145275Y1239763D03*
Y1250984D03*
Y1254724D03*
X1141535D03*
Y1250984D03*
X1149015Y1254724D03*
X1145275Y1247243D03*
X1152755Y1243503D03*
X1156495Y1254724D03*
X1145275Y1243503D03*
X1152755Y1247243D03*
X1149015Y1250984D03*
X1156495D03*
Y1258465D03*
X1149015D03*
X1141536D03*
X1150393Y1348187D03*
X1146033D03*
X1150393Y1360099D03*
X1146033D03*
X1150393Y1384297D03*
Y1372385D03*
X1146033D03*
Y1384297D03*
X1150393Y1396583D03*
X1146033D03*
X1150393Y1408495D03*
X1146033D03*
X1167716Y1075196D03*
X1160235D03*
X1171455Y1071455D03*
X1163975D03*
Y1075196D03*
X1171455D03*
X1167716Y1078936D03*
X1163976Y1082677D03*
Y1086417D03*
Y1090157D03*
X1171456Y1082677D03*
Y1086417D03*
Y1090157D03*
X1167716D03*
X1160235Y1078936D03*
Y1090157D03*
X1160234Y1086417D03*
X1167715Y1086416D03*
X1163975Y1078936D03*
X1160234Y1082677D03*
X1171455Y1078936D03*
X1167715Y1082676D03*
X1163976Y1101377D03*
X1171456D03*
X1167716Y1097637D03*
Y1093897D03*
X1160235D03*
Y1097637D03*
X1163976Y1105117D03*
X1171456D03*
X1160235D03*
Y1101376D03*
X1171455Y1093897D03*
X1167716Y1105117D03*
X1171455Y1097637D03*
X1163975Y1093897D03*
Y1097637D03*
X1167716Y1101376D03*
X1169586Y1121948D03*
X1165846D03*
X1162106D03*
X1158365D03*
X1173326D03*
X1171456Y1108858D03*
X1167716D03*
X1163976D03*
X1160235D03*
X1162106Y1114468D03*
X1169586D03*
X1162106Y1118208D03*
X1173326Y1114468D03*
X1158365Y1118208D03*
X1173326D03*
X1165846Y1114468D03*
X1158365D03*
X1169586Y1118208D03*
X1165846D03*
X1162106Y1133169D03*
X1165846D03*
X1169586D03*
X1158365Y1140649D03*
X1162106D03*
X1165846D03*
X1169586D03*
X1158365Y1125688D03*
X1162106D03*
X1165846D03*
X1169586D03*
X1173326Y1133169D03*
Y1125688D03*
Y1140649D03*
X1158365Y1133169D03*
X1169586Y1129429D03*
X1165846D03*
X1162106D03*
X1158365D03*
X1173326D03*
Y1136909D03*
X1169586D03*
X1165846D03*
X1158365D03*
X1162106D03*
X1173326Y1148129D03*
X1158365D03*
X1162106D03*
X1165846D03*
X1169586D03*
X1162106Y1155610D03*
X1169586D03*
X1173326Y1151869D03*
X1158365D03*
X1162106D03*
X1169586D03*
X1165846D03*
X1173326Y1144389D03*
X1165846D03*
X1158365D03*
X1162106D03*
X1169586D03*
X1173326Y1155610D03*
X1165846D03*
X1158365D03*
Y1170570D03*
X1165846D03*
X1169586Y1166830D03*
X1158365Y1159350D03*
X1162106Y1166830D03*
X1165846Y1159350D03*
X1173326D03*
Y1170570D03*
Y1166830D03*
X1165846D03*
X1169586Y1170570D03*
X1158365Y1166830D03*
X1162106Y1170570D03*
X1169586Y1159350D03*
X1162106D03*
X1173326Y1189271D03*
X1158365Y1181791D03*
X1162106D03*
X1165846D03*
X1169586D03*
X1158365Y1189271D03*
X1162106D03*
X1165846D03*
X1169586D03*
X1173326Y1181791D03*
X1169586Y1174310D03*
X1162106D03*
X1158365Y1185531D03*
X1162106D03*
X1169586D03*
X1165846D03*
X1173326D03*
X1165846Y1178051D03*
X1158365D03*
X1162106D03*
X1169586D03*
X1173326D03*
X1165846Y1174310D03*
X1158365D03*
X1173326D03*
X1162106Y1204232D03*
X1158365D03*
X1169586D03*
X1165846D03*
X1158365Y1196751D03*
X1162106D03*
X1165846D03*
X1169586D03*
X1173326Y1204232D03*
Y1196751D03*
Y1200491D03*
X1165846D03*
X1162106D03*
X1158365D03*
X1169586D03*
X1165846Y1193011D03*
X1169586D03*
X1158365D03*
X1162106D03*
X1173326D03*
X1158365Y1211712D03*
Y1207972D03*
X1173326D03*
Y1211712D03*
X1162106Y1207972D03*
X1165846D03*
X1169586Y1211712D03*
Y1207972D03*
X1171456Y1221062D03*
X1167716D03*
X1163976D03*
X1160235D03*
X1173326Y1215452D03*
X1165846D03*
X1169586D03*
X1162105Y1215451D03*
X1158365Y1215452D03*
X1162105Y1211711D03*
X1165846D03*
X1160235Y1224803D03*
X1163976Y1232283D03*
X1167716Y1224803D03*
X1160235Y1228543D03*
X1171456Y1232283D03*
X1163976Y1236023D03*
Y1228543D03*
Y1224803D03*
X1171456Y1228543D03*
Y1224803D03*
X1167716Y1232283D03*
Y1236023D03*
X1160235Y1232283D03*
Y1236023D03*
X1171456D03*
X1167716Y1228543D03*
X1163976Y1239763D03*
Y1243503D03*
Y1247243D03*
X1167716Y1239763D03*
Y1250984D03*
Y1254724D03*
X1171456Y1247243D03*
Y1243503D03*
Y1239763D03*
X1160235D03*
Y1250984D03*
Y1254724D03*
X1171456Y1250984D03*
X1167716Y1247243D03*
X1163976Y1250984D03*
X1160235Y1247243D03*
Y1243503D03*
X1167716D03*
X1171456Y1254724D03*
X1163976D03*
X1171456Y1258465D03*
X1163976D03*
X1162633Y1348187D03*
X1170513D03*
X1158273D03*
X1162633Y1360099D03*
X1170513D03*
X1158273D03*
X1162633Y1372385D03*
Y1384297D03*
X1170513Y1372385D03*
Y1384297D03*
X1158273D03*
Y1372385D03*
X1162633Y1396583D03*
X1170513D03*
X1158273D03*
X1162633Y1408495D03*
X1170513D03*
X1158273D03*
X1175196Y1075196D03*
X1182676D03*
X1186416Y1071455D03*
X1178935D03*
Y1075196D03*
X1186416D03*
X1175196Y1078936D03*
Y1090157D03*
X1178936D03*
X1182676Y1078936D03*
X1178936Y1082677D03*
Y1086417D03*
X1182676Y1090157D03*
X1186417D03*
Y1086417D03*
Y1082677D03*
X1175195Y1086417D03*
X1182675Y1086416D03*
X1175195Y1082677D03*
X1178935Y1078936D03*
X1182675Y1082676D03*
X1186416Y1078936D03*
X1175196Y1097637D03*
Y1093897D03*
X1178936Y1101377D03*
X1186417D03*
X1182676Y1097637D03*
Y1093897D03*
X1178936Y1105117D03*
X1186417D03*
X1178935Y1097637D03*
X1186416Y1093897D03*
X1182676Y1105117D03*
X1175196D03*
X1178935Y1093897D03*
X1182676Y1101376D03*
X1175196D03*
X1186416Y1097637D03*
X1188287Y1118208D03*
Y1121948D03*
X1184546Y1118208D03*
X1180806Y1121948D03*
X1177066D03*
X1184546D03*
X1186417Y1108858D03*
X1182676D03*
X1178936D03*
X1175196D03*
X1188287Y1114468D03*
X1177066D03*
Y1118208D03*
X1184546Y1114468D03*
X1188287Y1125688D03*
X1184546Y1136909D03*
X1177066Y1133169D03*
X1180806D03*
X1184546D03*
X1177066Y1140649D03*
X1180806D03*
X1184546Y1125688D03*
Y1129429D03*
X1177066Y1125688D03*
X1180806D03*
X1184546Y1140649D03*
X1180806Y1129429D03*
X1177066D03*
X1188287D03*
X1180806Y1136909D03*
X1177066D03*
X1188287D03*
Y1140649D03*
Y1155610D03*
Y1151869D03*
Y1148129D03*
X1177066D03*
X1180806D03*
X1184546Y1144389D03*
Y1148129D03*
Y1151869D03*
X1177066Y1155610D03*
X1184546D03*
X1180806Y1151869D03*
X1177066D03*
Y1144389D03*
X1180806D03*
Y1155610D03*
X1188287Y1144389D03*
X1177066Y1166830D03*
X1188287D03*
Y1159350D03*
Y1170570D03*
X1180806D03*
X1184546D03*
X1177066D03*
X1184546Y1166830D03*
X1180806D03*
X1177066Y1159350D03*
X1180806D03*
X1184546D03*
X1188287Y1181791D03*
Y1174310D03*
X1177066Y1189271D03*
X1180806D03*
X1184546Y1178051D03*
X1177066Y1174310D03*
X1184546Y1185531D03*
X1177066Y1181791D03*
X1180806D03*
X1184546Y1189271D03*
Y1174310D03*
X1177066Y1185531D03*
Y1178051D03*
X1180806Y1185531D03*
Y1178051D03*
Y1174310D03*
X1184546Y1181791D03*
X1188287Y1185531D03*
Y1189271D03*
Y1178051D03*
X1184546Y1204232D03*
X1177066D03*
X1180806D03*
X1184546Y1200491D03*
X1177066Y1196751D03*
X1180806D03*
X1184546Y1193011D03*
X1188287Y1204232D03*
Y1196751D03*
X1184566Y1196732D03*
X1180806Y1200491D03*
X1177066D03*
X1188287D03*
X1177066Y1193011D03*
X1180806D03*
X1188287D03*
Y1207972D03*
X1184546Y1211712D03*
X1177066Y1207972D03*
Y1211712D03*
X1180806Y1207972D03*
Y1211712D03*
X1184546Y1207972D03*
X1186417Y1221062D03*
X1182676D03*
X1178936D03*
X1175196D03*
X1188287Y1215452D03*
X1180806D03*
X1177066D03*
X1188287Y1211712D03*
X1184547Y1215452D03*
X1182676Y1228543D03*
X1186417Y1236023D03*
X1178936D03*
X1186417Y1232283D03*
X1175196Y1228543D03*
X1178936Y1232283D03*
X1182676Y1224803D03*
X1175196D03*
Y1232283D03*
Y1236023D03*
X1178936Y1228543D03*
Y1224803D03*
X1182676Y1232283D03*
Y1236023D03*
X1186417Y1228543D03*
Y1224803D03*
X1175196Y1254724D03*
Y1239763D03*
Y1250984D03*
X1178936Y1247243D03*
X1182676Y1250984D03*
Y1254724D03*
X1186417Y1247243D03*
X1178936Y1239763D03*
X1186417D03*
X1182676D03*
X1178936Y1243503D03*
X1186417D03*
X1178936Y1254724D03*
X1175196Y1243503D03*
X1182676Y1247243D03*
X1178936Y1250984D03*
X1186417D03*
X1182676Y1243503D03*
X1186417Y1254724D03*
X1175196Y1247243D03*
X1186417Y1258465D03*
X1178936D03*
X1182753Y1348187D03*
X1174873D03*
X1182753Y1360099D03*
X1174873D03*
X1182753Y1384297D03*
Y1372385D03*
X1174873Y1384297D03*
Y1372385D03*
X1182753Y1396583D03*
X1174873D03*
X1182753Y1408495D03*
X1174873D03*
X1190157Y1075196D03*
X1197637D03*
X1205117D03*
X1201376Y1071455D03*
X1193896D03*
Y1075196D03*
X1201376D03*
X1190157Y1078936D03*
Y1090157D03*
X1197637Y1078936D03*
Y1090157D03*
X1201377D03*
Y1086417D03*
Y1082677D03*
X1205117Y1078936D03*
X1205116Y1090157D03*
X1193897Y1082677D03*
Y1086417D03*
Y1090157D03*
X1190155Y1086417D03*
X1205116Y1082677D03*
X1190155D03*
X1197636Y1082676D03*
X1193896Y1078936D03*
X1205116Y1086417D03*
X1201376Y1078936D03*
X1197636Y1086416D03*
X1190157Y1093897D03*
Y1097637D03*
X1197637D03*
X1201377Y1101377D03*
X1197637Y1093897D03*
X1205117D03*
Y1097637D03*
X1193897Y1101377D03*
X1201377Y1105117D03*
X1193897D03*
X1201376Y1093897D03*
X1193896Y1097637D03*
X1197637Y1105117D03*
X1205117D03*
X1197637Y1101376D03*
X1205117D03*
X1190157D03*
X1193896Y1093897D03*
X1201376Y1097637D03*
X1190157Y1105117D03*
X1192027Y1118208D03*
Y1121948D03*
X1205117Y1123818D03*
Y1120078D03*
Y1116338D03*
Y1108858D03*
X1201377D03*
X1197637D03*
X1193897D03*
X1190157D03*
X1199507Y1118208D03*
X1195767D03*
Y1114468D03*
X1192027D03*
X1199507D03*
X1192027Y1136909D03*
X1195767Y1140649D03*
X1192027Y1133169D03*
Y1140649D03*
X1195767Y1136909D03*
X1192027Y1125688D03*
Y1129429D03*
X1205117Y1135039D03*
Y1131299D03*
Y1127558D03*
X1199507Y1140649D03*
Y1136909D03*
X1203247Y1140649D03*
X1195767Y1148129D03*
X1192027Y1144389D03*
X1195767Y1155610D03*
X1192027Y1148129D03*
X1195767Y1151869D03*
X1199507D03*
X1203247D03*
Y1155610D03*
Y1144389D03*
X1192027Y1151870D03*
X1199507Y1155610D03*
X1192027D03*
X1203247Y1148129D03*
X1195767Y1144389D03*
X1199507Y1148129D03*
Y1144389D03*
X1195767Y1170570D03*
Y1159350D03*
X1203247Y1166830D03*
Y1170570D03*
Y1159350D03*
X1195767Y1166830D03*
X1199507Y1170570D03*
Y1166830D03*
Y1159350D03*
X1192027Y1166830D03*
Y1170570D03*
Y1159350D03*
Y1181791D03*
X1199507Y1185531D03*
X1203247Y1174310D03*
Y1178051D03*
Y1185531D03*
X1192027Y1178051D03*
Y1189271D03*
X1195767D03*
X1192027Y1185531D03*
X1195767D03*
X1199507Y1181791D03*
X1195767Y1178051D03*
Y1174310D03*
X1203247Y1189271D03*
X1199507D03*
Y1174310D03*
X1195767Y1181791D03*
X1192027Y1174310D03*
X1199507Y1178051D03*
X1203247Y1181791D03*
X1195767Y1204232D03*
X1199507Y1193011D03*
X1203247D03*
X1195767Y1196751D03*
Y1193011D03*
X1192027D03*
X1205117Y1198621D03*
Y1202362D03*
X1199507Y1196751D03*
Y1204232D03*
X1195767Y1200491D03*
X1192027Y1196751D03*
Y1200491D03*
Y1204232D03*
X1199507Y1200491D03*
X1192027Y1211712D03*
X1205117Y1206102D03*
Y1209842D03*
Y1213582D03*
Y1217322D03*
Y1221062D03*
X1201377D03*
X1197637D03*
X1193897D03*
X1190157D03*
X1192027Y1215452D03*
X1199507Y1211712D03*
Y1215452D03*
Y1207972D03*
X1195767Y1215452D03*
X1192027Y1207972D03*
X1195767D03*
Y1211712D03*
X1197637Y1224803D03*
X1193897Y1236023D03*
X1190157Y1228543D03*
X1201377Y1236023D03*
X1190157Y1224803D03*
X1193897Y1232283D03*
X1197637Y1228543D03*
X1190157Y1232283D03*
Y1236023D03*
X1197637Y1232283D03*
X1201377Y1228543D03*
X1197637Y1236023D03*
X1201377Y1224803D03*
X1205117Y1232283D03*
Y1236023D03*
X1193897Y1228543D03*
Y1224803D03*
X1201377Y1232283D03*
X1205117Y1228543D03*
Y1224803D03*
X1190157Y1254724D03*
Y1250984D03*
Y1239763D03*
X1197637Y1250984D03*
Y1254724D03*
X1201377Y1247243D03*
X1205117Y1250984D03*
Y1254724D03*
X1197637Y1239763D03*
X1201377D03*
Y1243503D03*
X1205117Y1239763D03*
X1193897Y1247243D03*
Y1239763D03*
Y1243503D03*
X1190157D03*
X1201377Y1250984D03*
X1197637Y1247243D03*
X1193897Y1250984D03*
X1201377Y1254724D03*
X1197637Y1243503D03*
X1193897Y1254724D03*
X1190157Y1247243D03*
X1205117Y1243503D03*
Y1247243D03*
X1201377Y1258465D03*
X1193897D03*
X1212598Y1075196D03*
X1220079D03*
X1216338Y1071455D03*
X1208857D03*
X1216337Y1075196D03*
X1208857D03*
X1220079Y1078936D03*
X1212599D03*
X1216337Y1082677D03*
X1216338Y1086417D03*
X1212597Y1090157D03*
X1216337D03*
X1220077D03*
X1208857Y1082677D03*
X1208858Y1086417D03*
X1208857Y1090157D03*
X1212597Y1082676D03*
Y1086416D03*
X1220077Y1086417D03*
X1208857Y1078936D03*
X1216337D03*
X1220077Y1082677D03*
X1212598Y1093897D03*
X1220078D03*
X1212598Y1097637D03*
X1220078D03*
X1216338Y1101377D03*
X1208857D03*
X1216338Y1105117D03*
X1208858D03*
X1220078D03*
X1216337Y1093897D03*
X1212598Y1101376D03*
Y1105117D03*
X1208857Y1093897D03*
X1216337Y1097637D03*
X1220078Y1101376D03*
X1208857Y1097637D03*
X1212598Y1108858D03*
X1216338D03*
Y1116338D03*
X1212598Y1120078D03*
X1216338Y1123818D03*
X1208857Y1112598D03*
Y1120078D03*
X1220077Y1108857D03*
X1220078Y1116338D03*
Y1123818D03*
X1208858Y1108858D03*
X1212598Y1123818D03*
X1208857Y1116338D03*
X1212598D03*
X1216338Y1120078D03*
Y1112598D03*
X1208857Y1123818D03*
X1220078Y1112598D03*
Y1120078D03*
X1221948Y1140649D03*
X1218208D03*
X1214468D03*
X1206987Y1136909D03*
X1212598Y1127558D03*
X1216338Y1131299D03*
X1208858Y1127558D03*
X1220078Y1131299D03*
X1212598Y1135039D03*
X1208858D03*
X1216338Y1127559D03*
Y1135039D03*
X1212598Y1131299D03*
X1208857D03*
X1220078Y1135039D03*
Y1127559D03*
X1206988Y1140649D03*
X1221948Y1155610D03*
X1210728Y1151869D03*
X1206987D03*
X1218208Y1155610D03*
Y1148129D03*
X1214468Y1155610D03*
Y1151869D03*
Y1148129D03*
Y1144389D03*
X1206987D03*
X1210728D03*
X1221948Y1148129D03*
X1218208Y1144389D03*
Y1151869D03*
X1206988Y1155610D03*
Y1148129D03*
X1210728Y1155610D03*
X1221948Y1151869D03*
Y1144389D03*
X1206987Y1159350D03*
X1210728D03*
X1214468D03*
X1210728Y1166830D03*
X1206987D03*
X1218208Y1170570D03*
X1214468D03*
Y1166830D03*
X1221948Y1170570D03*
Y1159350D03*
X1218208Y1166830D03*
Y1159350D03*
X1221948Y1166830D03*
X1210728Y1170570D03*
X1206988D03*
X1210728Y1181791D03*
X1206987D03*
X1210728Y1189271D03*
X1218208Y1185531D03*
Y1178051D03*
X1214468Y1189271D03*
X1221948Y1178051D03*
Y1185531D03*
X1206987Y1174310D03*
Y1189271D03*
X1214468Y1185531D03*
Y1181791D03*
Y1178051D03*
Y1174310D03*
X1210728D03*
X1218208Y1189271D03*
Y1174310D03*
X1221948Y1181791D03*
Y1174310D03*
X1218208Y1181791D03*
X1221948Y1189271D03*
X1208858Y1194881D03*
X1212598D03*
X1218208Y1193011D03*
X1214468D03*
X1221948D03*
X1212598Y1202362D03*
X1220078Y1198621D03*
X1216338D03*
X1208858Y1202362D03*
X1212598Y1198621D03*
X1208858D03*
X1216338Y1202362D03*
X1220078D03*
Y1206102D03*
X1216338D03*
X1220078Y1221062D03*
X1216338D03*
X1212598D03*
Y1217322D03*
X1216338Y1213582D03*
X1220078D03*
X1212598Y1209842D03*
X1208858Y1221062D03*
Y1217322D03*
Y1209842D03*
X1220078Y1217322D03*
Y1209842D03*
X1212598Y1206102D03*
X1216338Y1217322D03*
X1212598Y1213582D03*
X1208858Y1206102D03*
Y1213582D03*
X1216338Y1209842D03*
Y1224803D03*
Y1228543D03*
X1212598Y1232283D03*
Y1236023D03*
X1220078Y1232283D03*
Y1236023D03*
X1208858Y1224803D03*
Y1228543D03*
X1220078Y1224803D03*
X1212598Y1228543D03*
X1208858Y1232283D03*
X1216338Y1236023D03*
Y1232283D03*
X1212598Y1224803D03*
X1220078Y1228543D03*
X1208858Y1236023D03*
X1212598Y1250984D03*
Y1254724D03*
X1216338Y1247243D03*
Y1243503D03*
X1220078Y1250984D03*
Y1254724D03*
X1212598Y1239763D03*
X1216338D03*
X1220078D03*
X1208858Y1247243D03*
Y1243503D03*
Y1239763D03*
X1212598Y1243503D03*
X1220078Y1247243D03*
Y1243503D03*
X1212598Y1247243D03*
X1208858Y1254724D03*
Y1250984D03*
X1216338Y1254724D03*
Y1250984D03*
Y1258465D03*
X1208858D03*
X1227559Y1075196D03*
X1235039D03*
X1231298Y1071455D03*
X1223818D03*
X1231297Y1075196D03*
X1223817D03*
Y1082677D03*
X1223818Y1086417D03*
X1223817Y1090157D03*
X1235039Y1078936D03*
X1227559D03*
X1231298Y1082677D03*
X1235039Y1086417D03*
X1231299D03*
X1227557Y1090157D03*
X1231298D03*
X1235039D03*
X1231297Y1078936D03*
X1235039Y1082676D03*
X1227557Y1086417D03*
X1223817Y1078936D03*
X1227557Y1082677D03*
X1223818Y1101377D03*
X1227558Y1093897D03*
Y1097637D03*
X1231298Y1101377D03*
X1235039Y1093897D03*
Y1097637D03*
X1223818Y1105117D03*
X1231299D03*
X1235039D03*
X1227558Y1101377D03*
X1231298Y1093897D03*
X1235039Y1101377D03*
X1227558Y1105117D03*
X1223817Y1093897D03*
Y1097637D03*
X1231298D03*
X1223817Y1108858D03*
X1223818Y1116338D03*
Y1112598D03*
Y1123818D03*
Y1120078D03*
X1227558Y1108858D03*
X1231298D03*
X1227558Y1116338D03*
X1231298D03*
X1235039Y1112598D03*
X1227558Y1123818D03*
X1231298D03*
X1235039Y1120078D03*
X1227558Y1112598D03*
X1235039Y1123818D03*
X1231298Y1120078D03*
Y1112598D03*
X1235039Y1108858D03*
Y1116338D03*
X1227558Y1120078D03*
X1236909Y1140649D03*
X1233169D03*
X1229428Y1136909D03*
X1233169D03*
X1223818Y1127558D03*
Y1131299D03*
X1235039Y1127558D03*
X1231298Y1131299D03*
X1227557D03*
X1223818Y1135039D03*
X1235039D03*
X1231298D03*
X1227558Y1127558D03*
X1235039Y1131299D03*
X1231298Y1127558D03*
X1227558Y1135039D03*
X1236909Y1136909D03*
X1225688Y1140649D03*
X1229428D03*
X1236909Y1148129D03*
Y1155610D03*
X1233169Y1144389D03*
X1225688D03*
Y1151869D03*
X1229428Y1144389D03*
X1233169Y1155610D03*
X1229428Y1151869D03*
X1233169D03*
Y1148129D03*
X1236909Y1151870D03*
X1225688Y1148129D03*
X1229428D03*
X1225688Y1155610D03*
X1236909Y1144389D03*
X1229428Y1155610D03*
X1236909Y1170570D03*
Y1166830D03*
X1225688D03*
X1229428Y1159350D03*
X1233169D03*
X1225688D03*
X1229428Y1166830D03*
X1233169Y1170570D03*
Y1166830D03*
X1229428Y1170570D03*
X1225688D03*
X1236909Y1159350D03*
Y1178051D03*
Y1185531D03*
X1229428Y1181791D03*
Y1189271D03*
X1233169D03*
Y1185531D03*
Y1181791D03*
Y1178051D03*
X1229428Y1174310D03*
X1233169D03*
X1225688D03*
Y1181791D03*
Y1189271D03*
X1236909Y1181791D03*
X1225688Y1185531D03*
X1236909Y1189271D03*
X1229428Y1178051D03*
Y1185531D03*
X1236909Y1174310D03*
X1225688Y1178051D03*
X1233169Y1193011D03*
X1223818Y1194881D03*
X1229428Y1196751D03*
X1233169D03*
X1236909Y1193011D03*
X1223818Y1202362D03*
Y1198621D03*
X1235039Y1202362D03*
X1231298Y1198621D03*
X1227558D03*
X1231298Y1202362D03*
X1235039Y1198621D03*
X1227558Y1202362D03*
X1225688Y1193011D03*
X1229428D03*
X1223818Y1206102D03*
Y1221062D03*
Y1217322D03*
Y1213582D03*
Y1209842D03*
X1231298Y1206102D03*
X1227558D03*
X1235039Y1217322D03*
X1231298Y1221062D03*
X1227558D03*
X1235039Y1209842D03*
X1231298Y1213582D03*
X1227558D03*
X1235039D03*
X1231298Y1209842D03*
X1227558D03*
X1235039Y1221062D03*
X1231298Y1217322D03*
X1235039Y1206102D03*
X1227558Y1217322D03*
X1223818Y1224803D03*
Y1228543D03*
X1235039Y1224803D03*
X1231298D03*
Y1228543D03*
X1227558Y1236023D03*
Y1232283D03*
X1235039D03*
Y1236023D03*
X1225688Y1222932D03*
X1231298Y1232283D03*
X1227558Y1228543D03*
Y1224803D03*
X1223818Y1236023D03*
X1231298D03*
X1235039Y1228543D03*
X1223818Y1232283D03*
Y1247243D03*
Y1243503D03*
Y1239763D03*
X1227558Y1250984D03*
Y1254724D03*
X1235039Y1250984D03*
X1231298Y1247243D03*
Y1243503D03*
X1235039D03*
X1227558Y1239763D03*
X1231298D03*
X1235039Y1254724D03*
X1227558Y1247243D03*
X1231298Y1254724D03*
X1223818D03*
Y1250984D03*
X1235039Y1239763D03*
X1227558Y1243503D03*
X1231298Y1250984D03*
X1235039Y1247243D03*
X1231298Y1258465D03*
X1223818D03*
X1235966Y1348187D03*
X1228086D03*
X1235966Y1360099D03*
X1228086D03*
X1235966Y1372385D03*
Y1384297D03*
X1228086Y1372385D03*
Y1384297D03*
X1238779Y1086417D03*
Y1078936D03*
X1242520Y1090158D03*
Y1082677D03*
X1238779Y1090157D03*
Y1082676D03*
Y1093897D03*
Y1097637D03*
Y1105117D03*
X1242520Y1101378D03*
X1238779Y1101377D03*
Y1112598D03*
Y1120078D03*
X1242520Y1123819D03*
Y1116339D03*
Y1108859D03*
X1238779Y1108858D03*
Y1116338D03*
Y1123818D03*
X1243149Y1136909D03*
X1240649Y1140649D03*
X1238779Y1127558D03*
Y1135039D03*
X1242520Y1131300D03*
X1238779Y1131299D03*
X1240649Y1136909D03*
Y1148129D03*
Y1155610D03*
Y1151870D03*
Y1144389D03*
Y1166830D03*
Y1170570D03*
Y1159350D03*
Y1178051D03*
Y1185531D03*
Y1174310D03*
Y1181791D03*
Y1189271D03*
X1240589Y1193011D03*
X1238779Y1202362D03*
X1242520Y1198621D03*
X1238779D03*
Y1217322D03*
Y1209842D03*
X1242520Y1221062D03*
Y1213582D03*
Y1206102D03*
X1238779Y1221062D03*
Y1206102D03*
Y1213582D03*
Y1224803D03*
Y1232283D03*
Y1236023D03*
X1242520Y1228543D03*
X1238779D03*
Y1250984D03*
Y1243503D03*
X1242520Y1247243D03*
Y1239762D03*
X1238779Y1247243D03*
Y1239763D03*
X1252566Y1348187D03*
X1240326D03*
X1248206D03*
X1252566Y1360099D03*
X1240326D03*
X1248206D03*
X1252566Y1372385D03*
Y1384297D03*
X1240326D03*
Y1372385D03*
X1248206D03*
Y1384297D03*
X1252566Y1396583D03*
X1240326D03*
X1248206D03*
X1252566Y1408495D03*
X1240326D03*
X1248206D03*
X1264806Y1348187D03*
X1260446D03*
X1264806Y1360099D03*
X1260446D03*
X1264806Y1372385D03*
Y1384297D03*
X1260446Y1372385D03*
Y1384297D03*
X1264806Y1396583D03*
X1260446D03*
X1264806Y1408495D03*
X1260446D03*
X1284926Y1348187D03*
X1277046D03*
X1272686D03*
X1284926Y1360099D03*
X1277046D03*
X1272686D03*
X1284926Y1372385D03*
Y1384297D03*
X1277046Y1372385D03*
Y1384297D03*
X1272686D03*
Y1372385D03*
X1284926Y1396583D03*
X1277046D03*
X1272686D03*
X1284926Y1408495D03*
X1277046D03*
X1272686D03*
X1301526Y1348187D03*
X1289286D03*
X1297166D03*
X1301526Y1360099D03*
X1289286D03*
X1297166D03*
X1301526Y1372385D03*
Y1384297D03*
X1289286D03*
Y1372385D03*
X1297166Y1384297D03*
Y1372385D03*
X1301526Y1396583D03*
X1289286D03*
X1297166D03*
X1301526Y1408495D03*
X1289286D03*
X1297166D03*
X1315330Y831445D03*
X1318480D03*
Y844044D03*
Y834595D03*
Y837744D03*
X1315330Y834595D03*
Y837744D03*
X1318480Y840894D03*
X1315330D03*
Y844044D03*
X1318480Y847193D03*
X1315330D03*
X1318480Y850343D03*
X1315330D03*
X1318480Y853492D03*
X1315330D03*
X1318480Y856642D03*
X1315330D03*
X1318480Y859792D03*
X1315330D03*
Y862941D03*
X1318480D03*
Y866091D03*
X1315330Y878689D03*
X1318480D03*
X1315330Y866091D03*
Y869240D03*
X1318480D03*
X1315330Y872390D03*
X1318480D03*
X1315330Y875540D03*
X1318480D03*
Y881839D03*
Y891288D03*
X1315330Y894437D03*
X1318480D03*
X1315330Y881839D03*
Y884988D03*
X1318480D03*
X1315330Y888138D03*
X1318480D03*
X1315330Y891288D03*
Y897587D03*
X1318480D03*
X1313766Y1348187D03*
X1309406D03*
X1313766Y1360099D03*
X1309406D03*
X1313766Y1372385D03*
Y1384297D03*
X1309406Y1372385D03*
Y1384297D03*
X1313766Y1396583D03*
X1309406D03*
X1313766Y1408495D03*
X1309406D03*
X1324779Y831445D03*
X1321629D03*
X1334228D03*
X1331078D03*
X1327929D03*
X1334228Y837744D03*
X1321629Y844044D03*
X1334228Y840894D03*
Y847193D03*
X1324779Y834595D03*
X1327929Y840894D03*
X1324779Y837744D03*
X1321629Y834595D03*
X1331078Y847193D03*
Y844044D03*
X1334228Y834595D03*
Y844044D03*
X1331078Y840894D03*
Y834595D03*
Y837744D03*
X1327929D03*
Y834595D03*
Y844044D03*
X1324779Y840894D03*
X1321629Y837744D03*
Y840894D03*
X1327929Y847193D03*
X1324779Y844044D03*
Y847193D03*
X1321629D03*
X1324779Y862941D03*
X1321629D03*
X1334228Y850343D03*
X1331078D03*
X1327929D03*
X1324779D03*
X1321629D03*
X1334228Y853492D03*
X1331078D03*
X1334228Y856642D03*
X1327929Y853492D03*
X1324779D03*
X1321629D03*
X1331078Y856642D03*
X1327929D03*
X1334228Y859792D03*
X1331078D03*
X1327929D03*
X1324779Y856642D03*
X1334228Y862941D03*
X1321629Y856642D03*
X1324779Y859792D03*
X1321629D03*
X1327929Y862941D03*
X1331078D03*
X1321629Y875540D03*
X1324779D03*
Y878689D03*
X1321629D03*
X1331078Y875540D03*
X1327929Y878689D03*
X1334228Y875540D03*
X1331078Y878689D03*
X1334228D03*
X1324779Y866091D03*
X1321629D03*
X1327929D03*
X1331078D03*
X1321629Y869240D03*
X1324779D03*
X1327929D03*
X1334228Y866091D03*
X1331078Y869240D03*
X1334228D03*
X1321629Y872390D03*
X1324779D03*
X1327929D03*
Y875540D03*
X1331078Y872390D03*
X1334228D03*
X1327929Y884988D03*
X1334228Y894437D03*
X1321629Y881839D03*
X1334228Y891288D03*
Y881839D03*
X1331078Y884988D03*
X1334228Y888138D03*
X1331078Y891288D03*
Y894437D03*
X1334228Y884988D03*
X1331078Y888138D03*
X1327929Y894437D03*
Y891288D03*
Y888138D03*
X1324779Y894437D03*
X1321629D03*
X1324779Y891288D03*
X1321629D03*
X1324779Y881839D03*
X1321629Y884988D03*
X1327929Y881839D03*
X1324779Y884988D03*
X1331078Y881839D03*
X1324779Y888138D03*
X1321629D03*
X1334228Y897587D03*
X1331078D03*
X1327929D03*
X1324779D03*
X1321629D03*
X1333886Y1348187D03*
X1326006D03*
X1321646D03*
X1333886Y1360099D03*
X1326006D03*
X1321646D03*
X1333886Y1372385D03*
Y1384297D03*
X1326006Y1372385D03*
Y1384297D03*
X1321646D03*
Y1372385D03*
X1333886Y1396583D03*
X1326006D03*
X1321646D03*
X1333886Y1408495D03*
X1326006D03*
X1321646D03*
X1339196Y441086D03*
Y433999D03*
Y437543D03*
X1336396Y441086D03*
Y433999D03*
Y437543D03*
X1339196Y444629D03*
X1336396D03*
X1349976Y831445D03*
X1346826D03*
X1343677D03*
X1340527D03*
X1337377D03*
X1349976Y840894D03*
X1346826D03*
X1349976Y834595D03*
Y844044D03*
Y847193D03*
Y837744D03*
X1346826D03*
Y844044D03*
Y834595D03*
Y847193D03*
X1343677Y834595D03*
Y837744D03*
X1340527D03*
X1343677Y840894D03*
Y844044D03*
Y847193D03*
X1340527Y834595D03*
Y840894D03*
X1337377Y837744D03*
Y834595D03*
Y840894D03*
X1340527Y844044D03*
Y847193D03*
X1337377D03*
Y844044D03*
Y853492D03*
X1349976Y856642D03*
X1346826D03*
X1343677D03*
X1340527D03*
Y859792D03*
X1343677Y862941D03*
X1340527D03*
X1337377D03*
Y856642D03*
Y859792D03*
X1349976Y853492D03*
X1346826D03*
X1343677D03*
X1340527D03*
X1343677Y859792D03*
X1349976Y862941D03*
X1346826D03*
X1349976Y859792D03*
X1346826D03*
X1337377Y850343D03*
X1349976D03*
X1346826D03*
X1343677D03*
X1340527D03*
X1343677Y866091D03*
X1340527D03*
Y869240D03*
X1349976Y872390D03*
X1346826D03*
X1343677D03*
X1340527D03*
X1343677Y875540D03*
X1337377D03*
Y869240D03*
Y872390D03*
Y866091D03*
X1349976Y875540D03*
X1346826D03*
X1340527D03*
X1343677Y878689D03*
X1349976Y866091D03*
X1346826D03*
X1349976Y869240D03*
X1346826D03*
X1343677D03*
X1349976Y878689D03*
X1346826D03*
X1340527D03*
X1337377D03*
X1346826Y891288D03*
X1349976D03*
X1343677D03*
Y888138D03*
X1340527Y884988D03*
X1337377D03*
X1349976Y881839D03*
Y894437D03*
Y884988D03*
Y888138D03*
X1346826D03*
Y884988D03*
Y894437D03*
Y881839D03*
X1343677Y894437D03*
Y884988D03*
Y881839D03*
X1340527D03*
Y894437D03*
Y888138D03*
Y891288D03*
X1337377Y894437D03*
Y888138D03*
Y891288D03*
Y881839D03*
X1349976Y897587D03*
X1346826D03*
X1343677D03*
X1340527D03*
X1337377D03*
X1350486Y1348187D03*
X1338246D03*
X1346126D03*
X1350486Y1360099D03*
X1338246D03*
X1346126D03*
X1350486Y1372385D03*
Y1384297D03*
X1338246D03*
Y1372385D03*
X1346126Y1384297D03*
Y1372385D03*
X1350486Y1396583D03*
X1338246D03*
X1346126D03*
X1350486Y1408495D03*
X1338246D03*
X1346126D03*
X1365724Y831445D03*
X1362574D03*
X1359425D03*
X1356275D03*
X1353125D03*
X1365724Y847193D03*
X1362574Y837744D03*
Y840894D03*
X1365724Y844044D03*
X1362574Y847193D03*
X1365724Y840894D03*
X1362574Y844044D03*
X1365724Y837744D03*
Y834595D03*
X1359425Y847193D03*
Y844044D03*
X1362574Y834595D03*
X1359425Y840894D03*
Y837744D03*
Y834595D03*
X1356275Y840894D03*
Y837744D03*
Y834595D03*
Y844044D03*
Y847193D03*
X1353125Y840894D03*
Y837744D03*
Y834595D03*
Y847193D03*
Y844044D03*
X1365724Y850343D03*
X1362574Y853492D03*
X1365724D03*
X1362574Y856642D03*
X1365724D03*
Y859792D03*
X1362574D03*
Y862941D03*
X1365724D03*
X1359425Y853492D03*
X1356275Y856642D03*
X1353125D03*
X1356275Y859792D03*
Y862941D03*
X1353125D03*
X1356275Y853492D03*
X1353125D03*
X1359425Y856642D03*
Y859792D03*
Y862941D03*
X1353125Y859792D03*
X1362574Y850343D03*
X1359425D03*
X1356275D03*
X1353125D03*
X1365724Y878689D03*
X1362574D03*
Y866091D03*
X1365724D03*
X1362574Y869240D03*
X1365724D03*
Y872390D03*
X1362574D03*
Y875540D03*
X1365724D03*
X1356275Y866091D03*
X1353125D03*
X1356275Y869240D03*
Y872390D03*
X1353125D03*
X1359425Y875540D03*
X1353125D03*
X1359425Y866091D03*
Y869240D03*
Y872390D03*
X1356275Y875540D03*
X1353125Y878689D03*
Y869240D03*
X1359425Y878689D03*
X1356275D03*
X1365724Y881839D03*
X1362574Y894437D03*
Y891288D03*
X1365724Y884988D03*
X1362574Y881839D03*
X1359425Y884988D03*
X1356275D03*
X1359425Y881839D03*
X1365724Y888138D03*
X1362574Y884988D03*
Y888138D03*
X1365724Y891288D03*
Y894437D03*
X1359425Y888138D03*
Y891288D03*
Y894437D03*
X1356275Y881839D03*
Y888138D03*
Y891288D03*
Y894437D03*
X1353125Y888138D03*
Y891288D03*
Y894437D03*
Y881839D03*
Y884988D03*
X1365724Y897587D03*
X1362574D03*
X1359425D03*
X1356275D03*
X1353125D03*
X1358366Y1348187D03*
Y1360099D03*
Y1372385D03*
Y1384297D03*
Y1396583D03*
Y1408495D03*
X1381472Y831445D03*
X1378322D03*
X1375173D03*
X1372023D03*
X1368873D03*
X1375173Y837744D03*
X1372023Y840894D03*
X1375173D03*
X1368873Y844044D03*
X1372023D03*
X1378322Y837744D03*
X1381472Y834595D03*
X1368873Y847193D03*
X1372023D03*
X1378322Y840894D03*
X1381472Y837744D03*
X1375173Y847193D03*
X1381472Y840894D03*
Y844044D03*
X1378322Y847193D03*
X1381472D03*
X1378322Y844044D03*
X1375173D03*
X1378322Y834595D03*
X1368873Y840894D03*
X1372023Y837744D03*
X1375173Y834595D03*
X1372023D03*
X1368873Y837744D03*
Y834595D03*
Y850343D03*
X1372023D03*
X1375173D03*
X1368873Y853492D03*
X1372023D03*
X1375173D03*
X1368873Y856642D03*
X1372023D03*
X1378322Y850343D03*
X1381472D03*
X1375173Y856642D03*
X1381472D03*
X1378322Y853492D03*
X1381472D03*
X1372023Y859792D03*
X1375173D03*
X1378322Y856642D03*
X1381472Y859792D03*
X1368873D03*
X1372023Y862941D03*
X1375173D03*
X1378322D03*
X1381472D03*
X1378322Y859792D03*
X1368873Y862941D03*
X1375173Y875540D03*
X1378322D03*
X1381472D03*
X1368873Y878689D03*
X1372023D03*
X1375173D03*
X1378322D03*
X1381472D03*
Y866091D03*
X1378322D03*
X1381472Y869240D03*
X1375173Y866091D03*
X1372023D03*
X1368873Y869240D03*
X1372023D03*
X1375173D03*
Y872390D03*
X1381472D03*
X1378322D03*
X1372023D03*
X1368873D03*
Y875540D03*
X1372023D03*
X1368873Y866091D03*
X1378322Y869240D03*
X1372023Y881839D03*
X1368873D03*
X1381472D03*
X1375173Y884988D03*
X1372023D03*
X1378322D03*
X1381472D03*
X1375173Y888138D03*
X1372023D03*
X1378322D03*
X1381472D03*
Y891288D03*
X1378322D03*
X1368873Y884988D03*
X1378322Y881839D03*
X1375173D03*
X1381472Y894437D03*
X1375173Y891288D03*
X1372023D03*
X1378322Y894437D03*
X1375173D03*
X1368873Y888138D03*
Y891288D03*
X1372023Y894437D03*
X1368873D03*
X1381472Y897587D03*
X1378322D03*
X1375173D03*
X1372023D03*
X1368873D03*
X1415924Y620661D03*
Y617861D03*
X1423010Y620661D03*
X1419467Y617861D03*
X1423010D03*
X1426554Y620661D03*
Y617861D03*
X1419467Y620661D03*
X1459130Y1348187D03*
Y1360099D03*
Y1384297D03*
Y1372385D03*
X1479250Y1348187D03*
X1471370D03*
X1467010D03*
X1479250Y1360099D03*
X1471370D03*
X1467010D03*
X1479250Y1384297D03*
Y1372385D03*
X1471370D03*
Y1384297D03*
X1467010D03*
Y1372385D03*
X1479250Y1396583D03*
X1471370D03*
X1479250Y1408495D03*
X1471370D03*
X1495850Y1348187D03*
X1483610D03*
X1491490D03*
X1495850Y1360099D03*
X1483610D03*
X1491490D03*
X1483610Y1384297D03*
Y1372385D03*
X1491490Y1384297D03*
Y1372385D03*
X1495850Y1384297D03*
Y1372385D03*
Y1396583D03*
X1483610D03*
X1491490D03*
X1495850Y1408495D03*
X1483610D03*
X1491490D03*
X1514468Y1084547D03*
Y1092027D03*
Y1088287D03*
Y1095767D03*
Y1103247D03*
Y1099507D03*
Y1106988D03*
Y1110728D03*
Y1118208D03*
Y1121948D03*
Y1114468D03*
Y1125688D03*
Y1133169D03*
Y1140649D03*
Y1129429D03*
Y1136909D03*
Y1144389D03*
Y1151870D03*
Y1148129D03*
Y1155610D03*
X1511968Y1170570D03*
X1514468Y1159350D03*
Y1166829D03*
X1514467Y1170570D03*
X1511968Y1178050D03*
X1514468Y1174309D03*
Y1181790D03*
X1514467Y1178051D03*
X1512597Y1198622D03*
Y1191142D03*
Y1221063D03*
Y1213583D03*
Y1206103D03*
Y1228542D03*
X1512596Y1239762D03*
Y1247242D03*
X1508090Y1348187D03*
X1503730D03*
X1508090Y1360099D03*
X1503730D03*
X1508090Y1384297D03*
Y1372385D03*
X1503730D03*
Y1384297D03*
X1508090Y1396583D03*
X1503730D03*
X1508090Y1408495D03*
X1503730D03*
X1525689Y1073326D03*
X1521949D03*
X1529429D03*
X1521948Y1077066D03*
X1525689D03*
X1518208D03*
Y1080806D03*
X1529429Y1080807D03*
X1521949D03*
X1529429Y1084547D03*
X1521949D03*
X1518208D03*
X1529429Y1088287D03*
X1525689D03*
X1521949D03*
X1525689Y1092027D03*
X1518208D03*
X1529429Y1077066D03*
X1525689Y1084547D03*
X1529429Y1092027D03*
X1521949D03*
X1518208Y1088287D03*
X1525689Y1080807D03*
X1521949Y1103247D03*
X1518208D03*
X1529429Y1106988D03*
X1525689D03*
X1521949D03*
X1525689Y1095767D03*
X1518208D03*
X1529429Y1099507D03*
X1521949D03*
X1529429Y1103247D03*
X1518208Y1099507D03*
X1525689D03*
X1529429Y1095767D03*
X1525689Y1103247D03*
X1518208Y1106988D03*
X1521949Y1095767D03*
X1529429Y1110728D03*
X1518208D03*
X1529429Y1114468D03*
X1525689D03*
X1521949D03*
X1529429Y1118208D03*
X1518208D03*
X1529429Y1121948D03*
X1525689D03*
X1521949D03*
Y1110728D03*
X1518208Y1114468D03*
X1525689Y1110728D03*
X1518208Y1121948D03*
X1521949Y1118208D03*
X1525689D03*
X1529429Y1125688D03*
X1518208D03*
X1529429Y1129429D03*
X1525689D03*
X1521949D03*
X1518208Y1133169D03*
X1521949Y1136909D03*
X1529429Y1140649D03*
X1525689D03*
X1521949D03*
X1518208D03*
X1525689Y1125688D03*
X1518208Y1129429D03*
X1521949Y1125688D03*
X1518208Y1136909D03*
X1521949Y1133169D03*
Y1144389D03*
X1518208D03*
X1529429Y1151869D03*
X1525689D03*
X1521949Y1148129D03*
Y1151870D03*
X1518208D03*
X1529429Y1155610D03*
X1525689D03*
X1521949D03*
X1518208Y1148129D03*
Y1155610D03*
X1521949Y1159350D03*
X1518208D03*
X1529429Y1166830D03*
X1525689D03*
X1521948D03*
X1525689Y1170570D03*
X1521948D03*
X1518209Y1166830D03*
X1518207Y1170570D03*
X1521948Y1174310D03*
X1518207D03*
X1521948Y1178051D03*
X1525689Y1174310D03*
X1529429D03*
X1527559Y1179921D03*
X1523819D03*
X1518207Y1181791D03*
X1516338Y1187401D03*
X1520078D03*
X1527559Y1183661D03*
X1523819D03*
X1520078D03*
X1516338D03*
X1523819Y1187401D03*
X1527559D03*
Y1176180D03*
X1518207Y1178051D03*
X1516338Y1194881D03*
Y1202362D03*
X1527559Y1191141D03*
X1523819D03*
X1527559Y1198621D03*
X1523819D03*
X1520078Y1194881D03*
Y1202362D03*
X1516338Y1198621D03*
X1523819Y1194881D03*
X1520078Y1198621D03*
X1523819Y1202362D03*
X1516338Y1191141D03*
X1527559Y1202362D03*
Y1194881D03*
X1520078Y1191141D03*
X1516338Y1209842D03*
Y1217322D03*
X1523819Y1206102D03*
X1527559D03*
Y1213582D03*
X1523819D03*
X1520078Y1209842D03*
Y1217322D03*
X1523819Y1221062D03*
X1527559D03*
X1520078D03*
X1516338Y1213582D03*
Y1206102D03*
X1520078D03*
X1527559Y1217322D03*
X1523819Y1209842D03*
X1516338Y1221062D03*
X1527559Y1209842D03*
X1523819Y1217322D03*
X1520078Y1213582D03*
X1527559Y1228543D03*
X1516338D03*
Y1232283D03*
Y1236023D03*
Y1224803D03*
X1527559Y1236023D03*
Y1232283D03*
X1523819Y1228543D03*
Y1224803D03*
X1520078Y1236023D03*
Y1232283D03*
Y1224803D03*
X1523819Y1232283D03*
X1520078Y1228543D03*
X1523819Y1236023D03*
X1527559Y1224803D03*
X1516338Y1239763D03*
Y1243503D03*
Y1250984D03*
X1527559D03*
Y1254724D03*
X1523819Y1247243D03*
Y1239763D03*
Y1243503D03*
X1527559Y1239763D03*
X1520078Y1250984D03*
Y1254724D03*
Y1243503D03*
Y1239763D03*
Y1247243D03*
X1516338D03*
X1527559Y1243503D03*
Y1247243D03*
X1523819Y1250984D03*
Y1254724D03*
Y1258465D03*
X1528210Y1348187D03*
X1520330D03*
X1515970D03*
X1528210Y1360099D03*
X1520330D03*
X1515970D03*
X1528210Y1372385D03*
Y1384297D03*
X1520330Y1372385D03*
Y1384297D03*
X1515970D03*
Y1372385D03*
X1528210Y1396583D03*
X1520330D03*
X1515970D03*
X1528210Y1408495D03*
X1520330D03*
X1515970D03*
X1533169Y1073326D03*
X1540649D03*
X1546258Y1071455D03*
X1546259Y1075196D03*
X1536909Y1073326D03*
X1540649Y1088287D03*
X1533169Y1077066D03*
X1536909Y1080807D03*
Y1084547D03*
Y1088287D03*
X1533169D03*
Y1092027D03*
X1540649Y1077066D03*
Y1092027D03*
X1546259Y1082677D03*
Y1086417D03*
Y1090157D03*
Y1078936D03*
X1533169Y1080807D03*
Y1084547D03*
X1540649Y1080807D03*
X1536909Y1077066D03*
X1540649Y1084547D03*
X1536909Y1092027D03*
X1544389Y1099507D03*
X1533169Y1095767D03*
X1536909Y1099507D03*
Y1103247D03*
X1540649Y1106988D03*
X1536909D03*
X1533169D03*
X1544389D03*
X1540649Y1095767D03*
Y1099507D03*
X1546259Y1101377D03*
Y1105117D03*
Y1097637D03*
Y1093897D03*
X1536909Y1095767D03*
X1533169Y1099507D03*
X1540649Y1103247D03*
X1533169D03*
X1544389Y1118208D03*
X1540649D03*
Y1121948D03*
X1544389Y1110728D03*
X1540649D03*
X1536909Y1114468D03*
X1533169D03*
X1536909Y1118208D03*
X1533169D03*
Y1121948D03*
X1544389Y1114468D03*
X1536909Y1110728D03*
X1533169D03*
X1540649Y1114468D03*
X1544389Y1140649D03*
X1540649D03*
X1536909D03*
X1533169D03*
Y1125688D03*
X1544389Y1129428D03*
X1540649D03*
X1536909Y1129429D03*
X1533169D03*
X1544389Y1136909D03*
X1533169Y1133169D03*
X1540649Y1136909D03*
X1544389Y1144389D03*
X1540649D03*
X1533169D03*
Y1148129D03*
Y1151870D03*
Y1155610D03*
X1544389Y1148129D03*
Y1155610D03*
Y1151870D03*
X1536909Y1148129D03*
X1540649Y1151870D03*
Y1148129D03*
X1536909Y1144389D03*
Y1155610D03*
X1533169Y1159350D03*
X1536909Y1166830D03*
Y1170570D03*
X1544389Y1159350D03*
Y1166830D03*
Y1170570D03*
X1540649Y1159350D03*
Y1170570D03*
X1535039Y1187401D03*
X1536909Y1174310D03*
X1533169D03*
Y1178051D03*
X1544389Y1174310D03*
Y1178051D03*
Y1181791D03*
X1540649D03*
X1538779Y1179921D03*
X1535039Y1176180D03*
X1531299Y1179921D03*
Y1187401D03*
X1546259D03*
X1542519D03*
Y1183661D03*
X1538779D03*
X1535039D03*
X1531299D03*
X1538779Y1187401D03*
X1540649Y1174310D03*
Y1178050D03*
X1531299Y1176180D03*
X1542519Y1191141D03*
X1538779Y1202362D03*
X1535039Y1194881D03*
X1542519Y1198621D03*
X1535039Y1191141D03*
X1531299D03*
X1535039Y1198621D03*
X1531299D03*
Y1194881D03*
Y1202362D03*
X1538779Y1198621D03*
Y1191141D03*
X1542519Y1194881D03*
X1546259D03*
X1542519Y1202362D03*
X1546259D03*
Y1198621D03*
Y1191141D03*
X1535039Y1202362D03*
X1538779Y1194881D03*
X1542519Y1213582D03*
Y1206102D03*
X1546259Y1213582D03*
X1535039Y1209842D03*
X1531299Y1206102D03*
X1535039D03*
X1531299Y1217322D03*
X1535039Y1213582D03*
X1531299Y1209842D03*
Y1213582D03*
X1538779Y1206102D03*
Y1213582D03*
X1542519Y1209842D03*
X1546259D03*
X1531299Y1221062D03*
X1535039D03*
X1546259Y1217322D03*
Y1221062D03*
X1538779D03*
X1542519D03*
Y1217322D03*
X1535039D03*
X1546259Y1206102D03*
X1538779Y1209842D03*
Y1217322D03*
X1546259Y1232283D03*
X1535039Y1224803D03*
X1538779Y1236023D03*
X1531299Y1232283D03*
X1542519Y1228543D03*
X1535039D03*
X1546259Y1236023D03*
X1531299Y1224803D03*
Y1228543D03*
X1535039Y1232283D03*
Y1236023D03*
X1542519Y1232283D03*
Y1236023D03*
X1538779Y1228543D03*
Y1224803D03*
X1546259D03*
Y1228543D03*
X1542519Y1224803D03*
X1531299Y1236023D03*
X1538779Y1232283D03*
X1531299Y1247243D03*
X1535039Y1250984D03*
Y1254724D03*
Y1239763D03*
X1531299D03*
Y1243503D03*
X1538779Y1247243D03*
X1542519Y1254724D03*
X1538779Y1239763D03*
Y1243503D03*
X1542519Y1250984D03*
Y1239763D03*
X1546259D03*
Y1243503D03*
Y1247243D03*
Y1250984D03*
X1542519Y1243503D03*
X1546259Y1254724D03*
X1542519Y1247243D03*
X1538779Y1250984D03*
Y1254724D03*
X1535039Y1243503D03*
X1531299Y1250984D03*
X1535039Y1247243D03*
X1531299Y1254724D03*
X1546260Y1258465D03*
X1538779D03*
X1531299D03*
X1544810Y1348187D03*
X1532570D03*
X1540450D03*
X1544810Y1360099D03*
X1532570D03*
X1540450D03*
X1544810Y1384297D03*
Y1372385D03*
X1532570Y1384297D03*
Y1372385D03*
X1540450Y1384297D03*
Y1372385D03*
X1544810Y1396583D03*
X1532570D03*
X1540450D03*
X1544810Y1408495D03*
X1532570D03*
X1540450D03*
X1557480Y1075196D03*
X1550000D03*
X1561219Y1071455D03*
X1553739D03*
X1553740Y1075196D03*
X1561220D03*
Y1086417D03*
Y1090157D03*
Y1082677D03*
X1557480Y1078936D03*
Y1090157D03*
X1553740Y1082677D03*
Y1086417D03*
Y1090157D03*
X1550000Y1078936D03*
Y1090157D03*
X1557480Y1082677D03*
X1553740Y1078936D03*
X1561220D03*
X1550000Y1086417D03*
Y1082677D03*
X1557480Y1086417D03*
Y1101376D03*
X1561220Y1093897D03*
X1557480Y1105117D03*
X1561220Y1097637D03*
Y1105117D03*
X1553740D03*
X1561220Y1101377D03*
X1557480Y1097637D03*
Y1093897D03*
X1553740Y1101377D03*
X1550000Y1093897D03*
Y1097637D03*
Y1101376D03*
Y1105117D03*
X1553740Y1093897D03*
Y1097637D03*
X1551870Y1114468D03*
X1548130D03*
X1563090Y1118208D03*
X1559350D03*
X1555610D03*
X1551870D03*
X1548130D03*
X1563090Y1121948D03*
X1559350D03*
X1555610D03*
X1551870D03*
X1548130D03*
Y1110728D03*
X1561220Y1108858D03*
X1557480D03*
X1553740D03*
X1550000D03*
X1551870Y1110728D03*
X1559350Y1114468D03*
X1555610D03*
X1563090D03*
X1548130Y1140649D03*
X1563090Y1125688D03*
X1559350D03*
X1555610D03*
X1551870D03*
X1548130D03*
X1559350Y1129429D03*
X1555610D03*
X1551870D03*
X1548130D03*
X1559350Y1133169D03*
X1555610D03*
X1551870D03*
X1548130D03*
X1559350Y1136909D03*
X1551870D03*
X1548130D03*
X1559350Y1140649D03*
X1555610D03*
X1551870D03*
X1563090D03*
Y1136909D03*
X1555610D03*
X1563090Y1129429D03*
Y1133169D03*
X1551870Y1155610D03*
Y1151870D03*
X1559350Y1144389D03*
X1551870D03*
Y1148129D03*
X1559350Y1151870D03*
X1563090Y1155610D03*
Y1148129D03*
Y1144389D03*
Y1151869D03*
X1555610Y1144389D03*
X1548130Y1151870D03*
Y1148129D03*
Y1144389D03*
X1559350Y1155610D03*
X1555610Y1151870D03*
X1559350Y1148129D03*
Y1170570D03*
X1551870Y1166830D03*
X1559350Y1159350D03*
X1551870D03*
X1548130Y1170570D03*
X1551870D03*
X1563090Y1166830D03*
Y1159350D03*
Y1170570D03*
X1548130Y1166830D03*
Y1159350D03*
X1555610Y1170570D03*
X1559350Y1166830D03*
X1555610Y1159350D03*
X1551870Y1189271D03*
X1559350Y1185531D03*
X1551870D03*
Y1178051D03*
Y1174310D03*
X1559350Y1178051D03*
X1551870Y1181791D03*
X1563090D03*
Y1174310D03*
X1550000Y1187401D03*
X1548130Y1185531D03*
Y1174310D03*
Y1178051D03*
Y1181791D03*
X1563090Y1185531D03*
Y1178051D03*
X1555610Y1185531D03*
X1559350Y1174310D03*
Y1181791D03*
X1555610Y1178051D03*
X1551870Y1193011D03*
X1559350D03*
Y1196751D03*
Y1200491D03*
X1555610D03*
Y1204232D03*
X1559350D03*
X1563090D03*
Y1196751D03*
Y1200491D03*
X1555610Y1193011D03*
Y1196751D03*
X1550000Y1191141D03*
Y1194881D03*
Y1198621D03*
Y1202362D03*
X1563090Y1193011D03*
X1555610Y1211712D03*
X1559350D03*
X1563090D03*
Y1207972D03*
X1559350D03*
X1555610D03*
X1563090Y1219192D03*
X1550000Y1221062D03*
X1553740D03*
X1557480D03*
X1561220D03*
X1550000Y1206102D03*
Y1209842D03*
Y1213582D03*
Y1217322D03*
X1553740D03*
X1555610Y1215452D03*
X1563090D03*
X1559350D03*
X1553740Y1232283D03*
X1550000Y1228543D03*
X1553740Y1236023D03*
X1550000Y1224803D03*
X1557480Y1228543D03*
X1561220Y1236023D03*
X1550000Y1232283D03*
Y1236023D03*
X1561220Y1224803D03*
Y1228543D03*
X1557480Y1232283D03*
Y1236023D03*
X1553740Y1228543D03*
Y1224803D03*
X1561220Y1232283D03*
X1557480Y1224803D03*
X1550000Y1250984D03*
Y1254724D03*
Y1239763D03*
X1557480Y1250984D03*
Y1254724D03*
X1561220Y1247243D03*
X1557480Y1239763D03*
X1561220D03*
Y1243503D03*
X1553740Y1247243D03*
Y1239763D03*
Y1243503D03*
X1561220Y1250984D03*
Y1254724D03*
X1550000Y1243503D03*
X1557480Y1247243D03*
X1550000D03*
X1557480Y1243503D03*
X1553740Y1250984D03*
Y1254724D03*
X1561220Y1258465D03*
X1553740D03*
X1557050Y1348187D03*
X1552690D03*
Y1360099D03*
X1557050D03*
Y1384297D03*
Y1372385D03*
X1552690D03*
Y1384297D03*
X1557050Y1396583D03*
X1552690D03*
X1557050Y1408495D03*
X1552690D03*
X1572441Y1075196D03*
X1564960D03*
X1576180Y1071455D03*
X1568699D03*
X1576181Y1075196D03*
X1568700D03*
X1564960Y1090157D03*
Y1078936D03*
X1572441Y1090157D03*
Y1078936D03*
X1576181Y1082677D03*
Y1086417D03*
Y1090157D03*
X1568700Y1082677D03*
Y1086417D03*
Y1090157D03*
Y1078936D03*
X1572441Y1086417D03*
X1564960Y1082677D03*
Y1086417D03*
X1572441Y1082677D03*
X1576181Y1078936D03*
X1564960Y1105117D03*
X1576181Y1097637D03*
X1568700D03*
X1576181Y1105117D03*
X1568700D03*
X1564960Y1093897D03*
Y1097637D03*
X1572441Y1093897D03*
Y1097637D03*
X1576181Y1101377D03*
X1568700D03*
X1576181Y1093897D03*
X1568700D03*
X1572441Y1101376D03*
Y1105117D03*
X1564960Y1101376D03*
X1566830Y1121948D03*
X1578051Y1118208D03*
X1574311D03*
Y1121948D03*
X1578051D03*
X1570571Y1118208D03*
X1566830D03*
X1570571Y1121948D03*
X1576181Y1108858D03*
X1572441D03*
X1568700D03*
X1564960D03*
X1574311Y1114468D03*
X1570571D03*
X1578051D03*
X1566830D03*
Y1133169D03*
Y1129429D03*
X1570571Y1140649D03*
X1574311D03*
X1578051D03*
X1570571Y1125688D03*
X1574311D03*
X1578051D03*
X1566830D03*
X1578051Y1133169D03*
X1574311D03*
X1570571D03*
X1566830Y1136909D03*
X1578051D03*
X1574311D03*
X1570571D03*
X1574311Y1129429D03*
X1570571D03*
X1578051D03*
X1566830Y1140649D03*
X1574311Y1148129D03*
X1570571D03*
X1578051D03*
X1570571Y1155610D03*
X1566830Y1151869D03*
X1578051Y1155610D03*
X1566830Y1144389D03*
X1578051D03*
X1574311D03*
X1570571D03*
X1578051Y1151870D03*
X1574311D03*
X1570571D03*
X1574311Y1155610D03*
X1566830Y1148129D03*
Y1155610D03*
Y1159350D03*
X1578051Y1166830D03*
X1574311Y1159350D03*
X1570571Y1166830D03*
X1566830Y1170570D03*
X1574311D03*
X1578051D03*
X1574311Y1166830D03*
X1570571Y1170570D03*
X1566830Y1166830D03*
X1578051Y1159350D03*
X1570571D03*
X1578051Y1181791D03*
X1574311D03*
X1570571D03*
X1578051Y1189271D03*
X1574311D03*
X1570571D03*
X1566830D03*
Y1178051D03*
X1570571Y1174310D03*
X1566830Y1185531D03*
X1578051Y1174310D03*
X1574311Y1185531D03*
X1570571D03*
X1578051D03*
Y1178051D03*
X1574311D03*
X1570571D03*
X1574311Y1174310D03*
X1566830Y1181791D03*
Y1174310D03*
X1574311Y1204232D03*
X1578051D03*
Y1196751D03*
X1574311D03*
X1570571D03*
X1566830Y1200491D03*
Y1196751D03*
Y1193011D03*
Y1204232D03*
X1570571D03*
Y1193011D03*
X1574311D03*
X1578051D03*
X1570571Y1200491D03*
X1578051D03*
X1574311D03*
X1566830Y1207972D03*
Y1211712D03*
X1578051Y1207972D03*
X1574311D03*
X1570571D03*
X1564960Y1221062D03*
X1568700D03*
X1572441D03*
X1576181D03*
X1578051Y1215452D03*
X1566830D03*
X1570571Y1211712D03*
X1566830Y1219192D03*
X1574311Y1215452D03*
X1570571D03*
X1578051Y1211712D03*
X1574311D03*
X1572441Y1228543D03*
X1568700Y1236023D03*
X1564960Y1224803D03*
X1576181Y1236023D03*
X1564960Y1232283D03*
Y1236023D03*
X1576181Y1224803D03*
Y1228543D03*
X1572441Y1232283D03*
Y1236023D03*
X1568700Y1228543D03*
Y1224803D03*
X1572441D03*
X1564960Y1228543D03*
X1576181Y1232283D03*
X1568700D03*
X1564960Y1250984D03*
Y1254724D03*
Y1239763D03*
X1572441Y1250984D03*
Y1254724D03*
X1576181Y1247243D03*
Y1243503D03*
X1572441Y1239763D03*
X1576181D03*
X1568700Y1247243D03*
Y1243503D03*
Y1239763D03*
Y1254724D03*
X1572441Y1247243D03*
X1576181Y1254724D03*
X1564960Y1243503D03*
Y1247243D03*
X1576181Y1250984D03*
X1572441Y1243503D03*
X1568700Y1250984D03*
X1576181Y1258465D03*
X1568701D03*
X1564930Y1348187D03*
X1569290D03*
X1577170D03*
X1569290Y1360099D03*
X1577170D03*
X1564930D03*
X1577170Y1372385D03*
Y1384297D03*
X1569290Y1372385D03*
Y1384297D03*
X1564930D03*
Y1372385D03*
X1577170Y1396583D03*
X1569290D03*
X1564930D03*
X1577170Y1408495D03*
X1569290D03*
X1564930D03*
X1579921Y1075196D03*
X1587401D03*
X1594882D03*
X1591140Y1071455D03*
X1583660D03*
X1583661Y1075196D03*
X1591141D03*
X1579921Y1090157D03*
X1583661D03*
Y1086417D03*
Y1082677D03*
X1579921Y1078936D03*
X1587401Y1090157D03*
Y1078936D03*
X1591141Y1082677D03*
Y1086417D03*
Y1090157D03*
X1594882D03*
Y1078936D03*
Y1082677D03*
X1579921D03*
X1583661Y1078936D03*
X1594882Y1086417D03*
X1587401Y1082677D03*
X1579921Y1086417D03*
X1587401D03*
X1591141Y1078936D03*
X1594881Y1105117D03*
X1591141Y1097637D03*
X1583661Y1093897D03*
X1594881Y1101376D03*
X1583661Y1097637D03*
Y1105117D03*
X1591141D03*
X1579921Y1093897D03*
Y1097637D03*
X1583661Y1101377D03*
X1587401Y1097637D03*
Y1093897D03*
X1594882D03*
Y1097637D03*
X1591141Y1101377D03*
X1587401Y1105117D03*
X1579921Y1101376D03*
X1591141Y1093897D03*
X1587401Y1101376D03*
X1579921Y1105117D03*
X1581791Y1121948D03*
X1585531Y1118208D03*
X1589271D03*
X1593011D03*
X1589271Y1121948D03*
X1593011D03*
X1585531D03*
X1581791Y1118208D03*
X1585531Y1114468D03*
X1594882Y1108858D03*
X1591141D03*
X1587401D03*
X1583661D03*
X1579921D03*
X1587401Y1112598D03*
X1593012Y1114468D03*
X1589271D03*
X1581791D03*
Y1133169D03*
Y1140649D03*
X1585531D03*
X1589271D03*
X1593011D03*
X1589271Y1125688D03*
X1585531D03*
X1581791D03*
X1593011D03*
Y1133169D03*
X1589271D03*
X1585531D03*
X1593011Y1136909D03*
X1589271D03*
X1585531D03*
X1581791D03*
X1589271Y1129429D03*
X1585531D03*
X1581791D03*
X1593011D03*
Y1148129D03*
X1589271D03*
X1585531D03*
X1581791D03*
X1593011Y1155610D03*
X1585531D03*
Y1144389D03*
X1581791D03*
X1593011D03*
X1589271D03*
X1593012Y1151870D03*
X1589271D03*
X1585531D03*
X1581791D03*
Y1155610D03*
X1589271D03*
Y1170570D03*
X1593012Y1166830D03*
X1585531D03*
X1581791Y1159350D03*
X1589271D03*
X1581791Y1170570D03*
X1593011D03*
X1585531D03*
X1589271Y1166830D03*
X1581791D03*
X1585531Y1159350D03*
X1593011D03*
Y1181791D03*
X1589271D03*
X1585531D03*
X1581791D03*
X1593011Y1189271D03*
X1589271D03*
X1585531D03*
X1581791D03*
X1585531Y1174310D03*
X1593011D03*
X1589271Y1185531D03*
X1585531D03*
X1581791D03*
X1593011D03*
X1581791Y1178051D03*
X1593011D03*
X1589271D03*
X1585531D03*
X1589271Y1174310D03*
X1581791D03*
X1593011Y1204232D03*
Y1196751D03*
X1589271D03*
X1585531D03*
X1581791D03*
Y1204232D03*
X1585531D03*
X1589271D03*
X1585531Y1193011D03*
X1589271D03*
X1593011D03*
X1581791D03*
X1589271Y1200491D03*
X1585531D03*
X1581791D03*
X1593011D03*
Y1219192D03*
X1591141Y1217322D03*
X1593011Y1207972D03*
X1589271D03*
X1585531D03*
X1589271Y1211712D03*
X1581791Y1207972D03*
Y1211712D03*
X1591141Y1221062D03*
X1587401D03*
X1579921D03*
X1583661D03*
X1594882D03*
X1593012Y1211712D03*
Y1215452D03*
X1581791D03*
X1589271D03*
X1585531D03*
Y1211712D03*
X1594882Y1224803D03*
X1591141Y1232283D03*
X1583661Y1236023D03*
X1579921Y1228543D03*
X1583661Y1232283D03*
X1594882Y1228543D03*
X1583661Y1224803D03*
Y1228543D03*
X1579921Y1232283D03*
Y1236023D03*
X1594882Y1232283D03*
Y1236023D03*
X1591141Y1228543D03*
Y1224803D03*
X1587401Y1232283D03*
Y1236023D03*
X1579921Y1224803D03*
X1587401Y1228543D03*
Y1224803D03*
X1591141Y1236023D03*
X1583661Y1243503D03*
Y1247243D03*
X1579921Y1254724D03*
Y1250984D03*
Y1239763D03*
X1583661D03*
X1587401Y1250984D03*
Y1254724D03*
X1591141Y1247243D03*
Y1243503D03*
X1594882Y1250984D03*
Y1254724D03*
Y1239763D03*
X1591141D03*
X1587401D03*
X1583661Y1254724D03*
X1579921Y1247243D03*
X1591141Y1254724D03*
X1587401Y1247243D03*
Y1243503D03*
X1594882D03*
X1579921D03*
X1594882Y1247243D03*
X1583661Y1250984D03*
X1591141D03*
X1591142Y1258465D03*
X1583661D03*
X1589410Y1348187D03*
X1581530D03*
X1589410Y1360099D03*
X1581530D03*
Y1384297D03*
Y1372385D03*
X1589410Y1384297D03*
Y1372385D03*
X1581530Y1396583D03*
X1589410D03*
X1581530Y1408495D03*
X1589410D03*
X1609842Y1075196D03*
X1602362D03*
X1606101Y1071454D03*
X1598621Y1071455D03*
X1606101Y1075195D03*
X1598622Y1075196D03*
Y1082677D03*
Y1086417D03*
Y1090157D03*
X1606102Y1082677D03*
Y1086417D03*
X1609842Y1090157D03*
X1606102D03*
X1609842Y1078936D03*
X1602362Y1090157D03*
Y1078936D03*
X1609841Y1086416D03*
X1606101Y1078935D03*
X1609841Y1082676D03*
X1602362Y1082677D03*
Y1086417D03*
X1598622Y1078936D03*
X1606101Y1093897D03*
X1602362Y1101376D03*
X1598622Y1097637D03*
Y1105117D03*
X1606102D03*
X1598622Y1101377D03*
X1606102D03*
X1609842Y1093897D03*
Y1097637D03*
X1602362Y1093897D03*
Y1097637D03*
X1598622Y1093897D03*
X1602362Y1105117D03*
X1609842Y1101376D03*
Y1105117D03*
X1606101Y1097637D03*
X1596752Y1121948D03*
X1600492Y1118208D03*
Y1114468D03*
X1611712Y1121948D03*
X1607972D03*
X1596752Y1118208D03*
X1600492Y1121948D03*
X1609842Y1108858D03*
X1606102D03*
X1602362D03*
X1598622D03*
X1596752Y1114468D03*
X1607972D03*
X1611712Y1118208D03*
X1607972D03*
X1611712Y1114468D03*
X1607972Y1125688D03*
X1611712D03*
X1607972Y1133464D03*
X1611712Y1133169D03*
X1600590Y1132677D03*
X1596752Y1133169D03*
Y1140649D03*
X1600492D03*
Y1125688D03*
X1596752D03*
X1607972Y1140649D03*
X1611712D03*
X1600492Y1136909D03*
X1596752D03*
X1611712D03*
X1607972D03*
X1611712Y1129429D03*
X1607972D03*
X1600492D03*
X1596752D03*
X1600492Y1148129D03*
X1596752D03*
X1607972D03*
X1611712D03*
X1600492Y1155610D03*
X1611712D03*
X1600492Y1144389D03*
X1596752D03*
X1611712Y1151869D03*
X1607972D03*
X1611712Y1144389D03*
X1607972D03*
X1600492Y1151870D03*
X1596752D03*
Y1155610D03*
X1607972D03*
X1596752Y1170570D03*
Y1159350D03*
X1611712Y1166830D03*
X1607972Y1170570D03*
X1600492Y1166830D03*
X1607972Y1159350D03*
Y1166830D03*
X1611712Y1170570D03*
X1600492D03*
X1596752Y1166830D03*
X1611712Y1159350D03*
X1600492D03*
Y1181791D03*
X1611712D03*
X1607972D03*
Y1189271D03*
X1611712D03*
X1596752Y1181791D03*
X1600492Y1189271D03*
X1596752D03*
X1600492Y1174310D03*
X1611712D03*
X1600492Y1185531D03*
X1596752D03*
X1600492Y1178051D03*
X1596752D03*
X1611712Y1185531D03*
X1607972D03*
X1611712Y1178051D03*
X1607972D03*
Y1174310D03*
X1596752D03*
X1611712Y1204232D03*
X1607972D03*
Y1196751D03*
X1611712D03*
X1600492D03*
X1596752D03*
Y1204232D03*
X1600492D03*
X1607972Y1193011D03*
X1611712D03*
X1600492D03*
X1596752D03*
X1600492Y1200491D03*
X1596752D03*
X1611712D03*
X1607972D03*
X1606102Y1221062D03*
X1596752Y1207972D03*
X1607972D03*
X1611712D03*
Y1211712D03*
X1596752Y1219192D03*
X1600492Y1207972D03*
X1598622Y1221062D03*
X1609842D03*
X1602362D03*
X1600492Y1211712D03*
Y1215452D03*
X1596752Y1211712D03*
X1611712Y1215452D03*
X1607972D03*
Y1211712D03*
X1609842Y1217322D03*
X1598622Y1236023D03*
X1606102D03*
X1609842Y1228543D03*
X1606102Y1232283D03*
X1602362Y1224803D03*
X1609842D03*
X1598622Y1228543D03*
Y1224803D03*
X1609842Y1232283D03*
Y1236023D03*
X1606102Y1228543D03*
Y1224803D03*
X1602362Y1232283D03*
Y1236023D03*
Y1228543D03*
X1598622Y1232283D03*
Y1239763D03*
Y1243503D03*
Y1247243D03*
X1609842Y1254724D03*
Y1250984D03*
X1606102Y1247243D03*
Y1243503D03*
Y1239763D03*
X1609842D03*
X1602362D03*
Y1250984D03*
Y1254724D03*
X1598622D03*
Y1250984D03*
X1609842Y1247243D03*
X1606102Y1250984D03*
Y1254724D03*
X1609842Y1243503D03*
X1602362Y1247243D03*
Y1243503D03*
X1606102Y1258465D03*
X1598623D03*
X1609158Y1348187D03*
Y1360099D03*
Y1384297D03*
Y1372385D03*
X1624803Y1075196D03*
X1617322D03*
X1621062Y1071455D03*
X1613581D03*
Y1075196D03*
X1621062D03*
X1617322Y1090157D03*
Y1078936D03*
X1613582Y1090157D03*
Y1086417D03*
Y1082677D03*
X1624803Y1078936D03*
X1621063Y1082677D03*
Y1086417D03*
Y1090157D03*
X1624803D03*
X1613581Y1078936D03*
X1624802Y1082676D03*
X1617321Y1082677D03*
X1621062Y1078936D03*
X1617321Y1086417D03*
X1624802Y1086416D03*
X1621062Y1093897D03*
X1617322Y1105117D03*
Y1093897D03*
Y1097637D03*
X1624803Y1093897D03*
Y1097637D03*
X1621063Y1101377D03*
Y1105117D03*
X1613582D03*
Y1101377D03*
X1617322Y1101376D03*
X1613581Y1093897D03*
Y1097637D03*
X1624803Y1101376D03*
Y1105117D03*
X1621062Y1097637D03*
X1626673Y1121948D03*
X1622933D03*
X1619193D03*
X1615452D03*
X1624803Y1108858D03*
X1621063D03*
X1617322D03*
X1613582D03*
X1615452Y1118208D03*
X1619193D03*
X1615452Y1114468D03*
X1619193D03*
X1622933D03*
X1626673D03*
Y1118208D03*
X1622933D03*
X1615452Y1133169D03*
X1619193D03*
X1622933D03*
X1626673D03*
X1615452Y1140649D03*
X1619193D03*
X1622933D03*
X1626673D03*
X1615452Y1125688D03*
X1619193D03*
X1622933D03*
X1626673D03*
Y1136909D03*
X1622933D03*
X1615452D03*
X1619193D03*
X1626673Y1129429D03*
X1622933D03*
X1619193D03*
X1615452D03*
Y1148129D03*
X1619193D03*
X1622933D03*
X1626673D03*
X1619193Y1155610D03*
X1626673D03*
X1615452Y1151869D03*
X1619193D03*
X1626673D03*
X1622933D03*
Y1144389D03*
X1615452D03*
X1619193D03*
X1626673D03*
X1622933Y1155610D03*
X1615452D03*
Y1170570D03*
X1622933D03*
X1626673Y1166830D03*
X1615452Y1159350D03*
X1619193Y1166830D03*
X1622933Y1159350D03*
X1615452Y1166830D03*
X1619193Y1170570D03*
X1626673Y1159350D03*
X1619193D03*
X1622933Y1166830D03*
X1626673Y1170570D03*
X1615452Y1181791D03*
X1619193D03*
X1622933D03*
X1626673D03*
X1615452Y1189271D03*
X1619193D03*
X1622933D03*
X1626673D03*
Y1174310D03*
X1619193D03*
Y1185531D03*
X1626673D03*
X1622933D03*
Y1178051D03*
X1615452D03*
X1619193D03*
X1626673D03*
X1615452Y1185531D03*
X1622933Y1174310D03*
X1615452D03*
X1619193Y1204232D03*
X1615452D03*
X1626673D03*
X1622933D03*
X1615452Y1196751D03*
X1619193D03*
X1622933D03*
X1626673D03*
X1622933Y1193011D03*
X1626673D03*
X1615452D03*
X1619193D03*
X1622933Y1200491D03*
X1619193D03*
X1615452D03*
X1626673D03*
X1617322Y1221062D03*
X1619193Y1207972D03*
X1622933D03*
X1626673Y1211712D03*
Y1207972D03*
X1615452Y1211712D03*
Y1207972D03*
X1621063Y1221062D03*
X1613582D03*
X1624803D03*
X1622933Y1215452D03*
X1619192Y1215451D03*
X1626673Y1215452D03*
X1615452D03*
X1613582Y1217322D03*
X1619192Y1211711D03*
X1622933D03*
X1617322Y1228543D03*
X1624803Y1224803D03*
X1617322D03*
X1621063Y1236023D03*
X1613582D03*
X1621063Y1232283D03*
X1613582Y1228543D03*
Y1224803D03*
X1621063Y1228543D03*
Y1224803D03*
X1624803Y1232283D03*
Y1236023D03*
X1617322Y1232283D03*
Y1236023D03*
X1624803Y1228543D03*
X1613582Y1232283D03*
Y1239763D03*
Y1243503D03*
Y1247243D03*
X1621063Y1239763D03*
Y1243503D03*
Y1247243D03*
X1624803Y1239763D03*
Y1250984D03*
Y1254724D03*
X1617322Y1239763D03*
Y1250984D03*
Y1254724D03*
X1624803Y1247243D03*
Y1243503D03*
X1621063Y1254724D03*
X1613582Y1250984D03*
X1617322Y1243503D03*
Y1247243D03*
X1613582Y1254724D03*
X1621063Y1250984D03*
Y1258465D03*
X1613582D03*
X1617038Y1348187D03*
X1621398D03*
X1617038Y1360099D03*
X1621398D03*
X1617038Y1384297D03*
Y1372385D03*
X1621398D03*
Y1384297D03*
Y1396583D03*
Y1408495D03*
X1639763Y1075196D03*
X1632283D03*
X1643503Y1071455D03*
X1636022D03*
X1628542D03*
X1636022Y1075196D03*
X1643503D03*
X1628542D03*
X1636023Y1090157D03*
X1643504Y1082677D03*
X1636023D03*
Y1086417D03*
X1643504Y1090157D03*
Y1086417D03*
X1639763Y1090157D03*
Y1078936D03*
X1632283D03*
X1628543Y1082677D03*
Y1086417D03*
Y1090157D03*
X1632283D03*
X1632282Y1082677D03*
X1643503Y1078936D03*
X1628542D03*
X1639762Y1086416D03*
X1632282Y1086417D03*
X1636022Y1078936D03*
X1639762Y1082676D03*
X1639763Y1101376D03*
X1628542Y1093897D03*
X1636022D03*
X1632283D03*
X1636023Y1101377D03*
X1643504D03*
X1628543D03*
X1632283Y1097637D03*
X1639763Y1093897D03*
Y1097637D03*
X1628543Y1105117D03*
X1636023D03*
X1643504D03*
X1639763D03*
X1632283D03*
Y1101376D03*
X1636022Y1097637D03*
X1643503D03*
Y1093897D03*
X1628542Y1097637D03*
X1641633Y1118208D03*
X1637893Y1121948D03*
X1634153D03*
X1630413D03*
X1641633D03*
X1643504Y1108858D03*
X1639763D03*
X1636023D03*
X1632283D03*
X1628543D03*
X1637893Y1118208D03*
Y1114468D03*
X1634153D03*
X1630413D03*
X1641633D03*
X1634153Y1118208D03*
X1630413D03*
X1641633Y1136909D03*
X1630413Y1133169D03*
X1634153D03*
X1637893D03*
X1641633D03*
X1634153Y1140649D03*
X1637893D03*
X1641633Y1125688D03*
Y1129429D03*
X1630413Y1125688D03*
X1634153D03*
X1637893D03*
X1641633Y1140649D03*
X1630413D03*
Y1136909D03*
X1637893D03*
X1634153D03*
X1630413Y1129429D03*
X1637893D03*
X1634153D03*
X1630413Y1148129D03*
X1634153D03*
X1637893D03*
X1641633Y1144389D03*
Y1148129D03*
Y1151869D03*
X1634153Y1155610D03*
X1641633D03*
X1630413Y1151869D03*
X1637893D03*
X1634153D03*
Y1144389D03*
X1630413D03*
X1637893D03*
Y1155610D03*
X1630413D03*
X1634153Y1166830D03*
X1630413Y1159350D03*
Y1170570D03*
X1637893D03*
X1641633D03*
X1634153D03*
X1641633Y1166830D03*
X1637893D03*
Y1159350D03*
X1641633D03*
X1634153D03*
X1630413Y1166830D03*
X1634153Y1189271D03*
X1637893D03*
X1641633Y1178051D03*
X1634153Y1174310D03*
X1641633Y1185531D03*
X1630413Y1181791D03*
X1634153D03*
X1637893D03*
X1641633Y1189271D03*
X1630413D03*
X1641633Y1174310D03*
Y1181791D03*
X1630413Y1185531D03*
X1634153D03*
X1630413Y1178051D03*
X1634153D03*
X1637893Y1185531D03*
Y1178051D03*
Y1174310D03*
X1630413D03*
X1641653Y1196732D03*
X1641633Y1204232D03*
X1630413D03*
X1634153D03*
X1637893D03*
X1641633Y1200491D03*
X1630413Y1196751D03*
X1634153D03*
X1637893D03*
X1641633Y1193011D03*
X1634153D03*
X1637893D03*
X1630413D03*
Y1200491D03*
X1637893D03*
X1634153D03*
X1641633Y1211712D03*
X1634153Y1207972D03*
X1630413D03*
X1634153Y1211712D03*
X1637893Y1207972D03*
Y1211712D03*
X1630413D03*
X1641633Y1207972D03*
X1628543Y1221062D03*
X1632283D03*
X1636023D03*
X1639763D03*
X1643504D03*
X1630413Y1215452D03*
X1637893D03*
X1634153D03*
X1641634D03*
X1632283Y1228543D03*
X1628543Y1236023D03*
Y1232283D03*
X1639763Y1224803D03*
X1636023Y1236023D03*
X1628543Y1228543D03*
Y1224803D03*
X1632283Y1232283D03*
Y1236023D03*
X1636023Y1228543D03*
Y1224803D03*
X1639763Y1232283D03*
Y1236023D03*
X1643504Y1228543D03*
Y1224803D03*
Y1232283D03*
X1632283Y1224803D03*
X1643504Y1236023D03*
X1636023Y1232283D03*
X1639763Y1228543D03*
X1632283Y1254724D03*
X1628543Y1247243D03*
Y1243503D03*
X1632283Y1239763D03*
Y1250984D03*
X1628543Y1239763D03*
X1636023Y1247243D03*
X1639763Y1250984D03*
Y1254724D03*
X1643504Y1247243D03*
X1636023Y1239763D03*
X1643504D03*
X1639763D03*
X1636023Y1243503D03*
X1643504D03*
X1632283D03*
X1636023Y1254724D03*
X1639763Y1243503D03*
X1636023Y1250984D03*
X1632283Y1247243D03*
X1643504Y1250984D03*
X1628543D03*
X1639763Y1247243D03*
X1628543Y1254724D03*
X1643504D03*
Y1258465D03*
X1636023D03*
X1628543D03*
X1629278Y1348187D03*
X1641518D03*
X1633638D03*
X1629278Y1360099D03*
X1641518D03*
X1633638D03*
X1629278Y1384297D03*
Y1372385D03*
X1641518Y1384297D03*
Y1372385D03*
X1633638Y1384297D03*
Y1372385D03*
X1629278Y1396583D03*
X1641518D03*
X1633638D03*
Y1408495D03*
X1629278D03*
X1641518D03*
X1647244Y1075196D03*
X1654724D03*
X1658463Y1071455D03*
X1650983D03*
Y1075196D03*
X1658463D03*
X1654724Y1078936D03*
Y1090157D03*
X1658464D03*
Y1086417D03*
Y1082677D03*
X1650984D03*
Y1086417D03*
Y1090157D03*
X1647244D03*
Y1078936D03*
X1654723Y1086416D03*
Y1082676D03*
X1650983Y1078936D03*
X1647242Y1082677D03*
Y1086417D03*
X1658463Y1078936D03*
Y1097637D03*
X1647244Y1101376D03*
Y1097637D03*
Y1093897D03*
X1654724Y1097637D03*
X1658464Y1101377D03*
X1654724Y1093897D03*
X1650984Y1101377D03*
X1658464Y1105117D03*
X1650984D03*
X1658463Y1093897D03*
X1654724Y1105117D03*
X1650983Y1093897D03*
X1647244Y1105117D03*
X1654724Y1101376D03*
X1650983Y1097637D03*
X1645374Y1118208D03*
X1649114D03*
Y1121948D03*
X1645374D03*
X1658464Y1108858D03*
X1654724D03*
X1650984D03*
X1647244D03*
X1656594Y1118208D03*
X1652854D03*
Y1114468D03*
X1645374D03*
X1649114D03*
X1656594D03*
X1649114Y1133169D03*
Y1140649D03*
X1652854Y1136909D03*
X1649114Y1125688D03*
X1645374D03*
X1649114Y1129429D03*
Y1136909D03*
X1652854Y1140649D03*
X1645374Y1129429D03*
Y1136909D03*
Y1140649D03*
X1656594Y1133169D03*
Y1140649D03*
Y1136909D03*
X1660334Y1140649D03*
X1645374Y1155610D03*
Y1151869D03*
Y1148129D03*
X1652854D03*
X1649114Y1144389D03*
X1652854Y1155610D03*
X1649114Y1148129D03*
X1652854Y1151869D03*
X1656594D03*
X1660334D03*
Y1155610D03*
Y1144389D03*
X1649114Y1151870D03*
Y1155610D03*
X1656594D03*
X1645374Y1144389D03*
X1660334Y1148129D03*
X1652854Y1144389D03*
X1656594Y1148129D03*
Y1144389D03*
X1645374Y1166830D03*
X1652854Y1159350D03*
X1660334Y1166830D03*
Y1170570D03*
X1645374Y1159350D03*
X1660334D03*
X1645374Y1170570D03*
X1652854D03*
Y1166830D03*
X1649114Y1159350D03*
Y1170570D03*
Y1166830D03*
X1656594Y1170570D03*
Y1166830D03*
Y1159350D03*
X1652854Y1185531D03*
X1656594Y1181791D03*
X1652854Y1178051D03*
Y1174310D03*
X1649114Y1181791D03*
X1656594Y1185531D03*
X1660334Y1174310D03*
Y1178051D03*
Y1185531D03*
X1645374Y1181791D03*
Y1174310D03*
X1649114Y1178051D03*
Y1189271D03*
X1652854D03*
X1649114Y1185531D03*
X1656594Y1189271D03*
X1649114Y1174310D03*
X1656594D03*
X1652854Y1181791D03*
X1660334Y1189271D03*
X1645374Y1185531D03*
Y1189271D03*
X1660334Y1181791D03*
X1656594Y1178051D03*
X1645374D03*
Y1204232D03*
X1656594Y1193011D03*
X1652854Y1204232D03*
X1660334D03*
Y1200491D03*
Y1193011D03*
X1652854Y1196751D03*
Y1193011D03*
X1649114D03*
X1645374Y1196751D03*
X1660334D03*
X1645374Y1200491D03*
Y1193011D03*
X1656594Y1196751D03*
Y1204232D03*
X1652854Y1200491D03*
X1649114Y1204232D03*
Y1196751D03*
Y1200491D03*
X1656594D03*
X1649114Y1211712D03*
X1645374Y1207972D03*
X1660334D03*
Y1215452D03*
Y1211712D03*
X1654724Y1221062D03*
X1658464D03*
X1650984D03*
X1647244D03*
X1645374Y1215452D03*
X1649114D03*
X1652854D03*
X1656594Y1211712D03*
X1645374D03*
X1656594Y1215452D03*
Y1207972D03*
X1649114D03*
X1652854D03*
Y1211712D03*
X1654724Y1228543D03*
X1647244D03*
X1658464Y1232283D03*
X1647244D03*
Y1236023D03*
X1654724Y1232283D03*
X1658464Y1228543D03*
X1654724Y1236023D03*
X1658464Y1224803D03*
X1650984Y1228543D03*
Y1224803D03*
X1654724D03*
X1658464Y1236023D03*
X1650984D03*
X1647244Y1224803D03*
X1650984Y1232283D03*
X1647244Y1254724D03*
Y1250984D03*
Y1239763D03*
X1654724Y1250984D03*
Y1254724D03*
X1658464Y1247243D03*
X1654724Y1239763D03*
X1658464D03*
Y1243503D03*
X1650984Y1247243D03*
Y1239763D03*
Y1243503D03*
X1654724D03*
X1650984Y1250984D03*
X1647244Y1247243D03*
X1654724D03*
X1647244Y1243503D03*
X1650984Y1254724D03*
X1658464D03*
Y1250984D03*
Y1258465D03*
X1650984D03*
X1645878Y1348187D03*
X1653758D03*
X1658118D03*
X1645878Y1360099D03*
X1653758D03*
X1658118D03*
X1645878Y1384297D03*
Y1372385D03*
X1653758D03*
Y1384297D03*
X1658118D03*
Y1372385D03*
X1645878Y1396583D03*
X1653758D03*
X1658118D03*
X1645878Y1408495D03*
X1653758D03*
X1658118D03*
X1662204Y1075196D03*
X1669685D03*
X1673425Y1071455D03*
X1665944D03*
X1673424Y1075196D03*
X1665944D03*
X1662204Y1078936D03*
X1662203Y1090157D03*
X1669686Y1078936D03*
X1673424Y1082677D03*
X1673425Y1086417D03*
X1669684Y1090157D03*
X1673424D03*
X1665944Y1082677D03*
X1665945Y1086417D03*
X1665944Y1090157D03*
X1662203Y1086417D03*
Y1082677D03*
X1669684Y1086416D03*
X1665944Y1078936D03*
X1673424D03*
X1669684Y1082676D03*
X1665944Y1093897D03*
X1662204Y1105117D03*
X1669685D03*
X1673424Y1097637D03*
X1669685Y1101376D03*
X1662204Y1093897D03*
Y1097637D03*
X1669685Y1093897D03*
Y1097637D03*
X1673425Y1101377D03*
X1665944D03*
X1673425Y1105117D03*
X1665945D03*
X1673424Y1093897D03*
X1665944Y1097637D03*
X1662204Y1101376D03*
X1673425Y1112598D03*
X1665944Y1123818D03*
X1669685Y1108858D03*
X1673425D03*
Y1116338D03*
X1669685Y1112598D03*
Y1120078D03*
X1673425Y1123818D03*
X1665944Y1112598D03*
Y1120078D03*
X1665945Y1108858D03*
X1662204Y1123818D03*
Y1120078D03*
Y1116338D03*
Y1108858D03*
X1673425Y1120078D03*
X1669685Y1123818D03*
X1665944Y1116338D03*
X1669685D03*
X1665944Y1131299D03*
X1675295Y1140649D03*
X1671555D03*
Y1136909D03*
X1669685Y1127558D03*
X1673425Y1131299D03*
X1665945Y1127558D03*
X1669685Y1135039D03*
X1665945D03*
X1662204D03*
Y1131299D03*
Y1127558D03*
Y1138779D03*
X1669685Y1131299D03*
X1673425Y1127559D03*
Y1135039D03*
X1664075Y1140649D03*
X1667815Y1151869D03*
X1664074D03*
X1675295Y1155610D03*
Y1148129D03*
X1671555Y1155610D03*
Y1151869D03*
Y1148129D03*
Y1144389D03*
X1664074D03*
X1667815D03*
Y1155610D03*
X1664075Y1148129D03*
Y1155610D03*
X1675295Y1144389D03*
Y1151869D03*
X1664074Y1159350D03*
X1667815D03*
X1671555D03*
X1667815Y1166830D03*
X1664074D03*
X1675295Y1170570D03*
X1671555D03*
Y1166830D03*
X1675295D03*
Y1159350D03*
X1664075Y1170570D03*
X1667815D03*
X1664074Y1189271D03*
Y1174310D03*
X1671555Y1185531D03*
Y1181791D03*
Y1178051D03*
Y1174310D03*
X1667815D03*
Y1181791D03*
X1664074D03*
X1667815Y1189271D03*
X1675295Y1185531D03*
Y1178051D03*
X1671555Y1189271D03*
X1675295D03*
Y1174310D03*
Y1181791D03*
X1665945Y1194881D03*
X1669685D03*
X1664074Y1204232D03*
X1675295Y1193011D03*
X1671555D03*
X1665945Y1202362D03*
X1669685D03*
X1673425Y1198621D03*
Y1202362D03*
X1665945Y1198621D03*
X1669685D03*
X1673425Y1221062D03*
X1669685D03*
Y1217322D03*
X1673425Y1213582D03*
X1669685Y1209842D03*
X1665945Y1221062D03*
Y1217322D03*
Y1209842D03*
X1673425Y1206102D03*
X1662204Y1221062D03*
X1665945Y1206102D03*
X1669685Y1213582D03*
X1673425Y1209842D03*
X1669685Y1206102D03*
X1665945Y1213582D03*
X1673425Y1217322D03*
X1662204Y1232283D03*
Y1236023D03*
X1673425Y1224803D03*
Y1228543D03*
X1669685Y1232283D03*
Y1236023D03*
X1665945Y1224803D03*
Y1228543D03*
X1673425Y1236023D03*
X1662204Y1228543D03*
X1669685D03*
X1673425Y1232283D03*
X1665945D03*
Y1236023D03*
X1662204Y1224803D03*
X1669685D03*
X1665945Y1247243D03*
Y1243503D03*
Y1239763D03*
X1662204Y1250984D03*
Y1254724D03*
Y1239763D03*
X1669685Y1250984D03*
Y1254724D03*
X1673425Y1247243D03*
Y1243503D03*
X1669685Y1239763D03*
X1673425D03*
Y1250984D03*
X1662204Y1247243D03*
X1665945Y1254724D03*
X1673425D03*
X1662204Y1243503D03*
X1665945Y1250984D03*
X1669685Y1247243D03*
Y1243503D03*
X1673425Y1258465D03*
X1665945D03*
X1665998Y1348187D03*
X1670358D03*
X1665998Y1360099D03*
X1670358D03*
X1665998Y1384297D03*
Y1372385D03*
X1670358D03*
Y1384297D03*
X1665998Y1396583D03*
X1670358D03*
X1665998Y1408495D03*
X1670358D03*
X1677166Y1075196D03*
X1684646D03*
X1692126D03*
X1688385Y1071455D03*
X1680905D03*
X1680904Y1075196D03*
X1688384D03*
X1677166Y1078936D03*
X1680904Y1082677D03*
X1680905Y1086417D03*
X1677164Y1090157D03*
X1680904D03*
X1692126Y1078936D03*
X1684646D03*
X1688385Y1082677D03*
X1692126Y1086417D03*
X1688386D03*
X1684644Y1090157D03*
X1688385D03*
X1692126D03*
Y1082676D03*
X1684644Y1082677D03*
Y1086417D03*
X1680904Y1078936D03*
X1688384D03*
X1677164Y1086417D03*
Y1082677D03*
X1692126Y1101377D03*
X1684645D03*
X1677165Y1105117D03*
Y1093897D03*
Y1097637D03*
X1680905Y1101377D03*
X1684645Y1093897D03*
Y1097637D03*
X1688385Y1101377D03*
X1692126Y1093897D03*
Y1097637D03*
X1680905Y1105117D03*
X1688386D03*
X1692126D03*
X1680904Y1097637D03*
X1677165Y1101376D03*
X1688385Y1097637D03*
X1684645Y1105117D03*
X1680904Y1093897D03*
X1688385D03*
X1677165Y1120078D03*
Y1112598D03*
X1677164Y1108857D03*
X1680904Y1108858D03*
X1680905Y1116338D03*
X1677165D03*
X1680905Y1112598D03*
Y1123818D03*
X1677165D03*
X1680905Y1120078D03*
X1684645Y1108858D03*
X1688385D03*
X1684645Y1116338D03*
X1688385D03*
X1692126Y1112598D03*
X1684645Y1123818D03*
X1688385D03*
X1692126Y1120078D03*
Y1116338D03*
Y1108858D03*
X1684645Y1120078D03*
X1688385D03*
X1684645Y1112598D03*
X1692126Y1123818D03*
X1688385Y1112598D03*
X1690256Y1140649D03*
X1686515Y1136909D03*
X1690256D03*
X1682775D03*
X1679035Y1140649D03*
X1680905Y1127558D03*
Y1131299D03*
X1677165D03*
X1692126Y1127558D03*
X1688385Y1131299D03*
X1684644D03*
X1680905Y1135039D03*
X1692126D03*
X1677165D03*
Y1127559D03*
X1684645Y1135039D03*
Y1127558D03*
X1692126Y1131299D03*
X1688385Y1127558D03*
Y1135039D03*
X1686515Y1140649D03*
X1682775D03*
X1690256Y1144389D03*
X1682775D03*
X1679035Y1148129D03*
X1682775Y1151869D03*
X1679035Y1155610D03*
X1686515Y1144389D03*
X1690256Y1155610D03*
X1686515Y1151869D03*
X1690256D03*
Y1148129D03*
X1679035Y1151869D03*
Y1144389D03*
X1682775Y1148129D03*
X1686515Y1155610D03*
Y1148129D03*
X1682775Y1155610D03*
Y1166830D03*
X1679035Y1170570D03*
X1686515Y1159350D03*
X1690256D03*
X1682775D03*
X1679035D03*
X1686515Y1166830D03*
X1690256Y1170570D03*
Y1166830D03*
X1679035D03*
X1686515Y1170570D03*
X1682775D03*
X1690256Y1178051D03*
X1686515Y1174310D03*
X1690256D03*
X1682775D03*
X1679035Y1178051D03*
X1682775Y1181791D03*
X1679035Y1185531D03*
X1682775Y1189271D03*
X1686515Y1181791D03*
Y1189271D03*
X1690256D03*
Y1185531D03*
Y1181791D03*
X1679035D03*
Y1189271D03*
Y1174310D03*
X1686515Y1185531D03*
X1682775Y1178051D03*
X1686515D03*
X1682775Y1185531D03*
X1680905Y1194881D03*
X1690256Y1193011D03*
X1679035D03*
X1692126Y1202362D03*
X1688385Y1198621D03*
X1684645D03*
X1680905Y1202362D03*
Y1198621D03*
X1677165D03*
X1684645Y1202362D03*
X1692126Y1198621D03*
X1688385Y1202362D03*
X1677165D03*
X1686515Y1193011D03*
X1682775D03*
X1692126Y1217322D03*
X1688385Y1221062D03*
X1684645D03*
X1692126Y1209842D03*
X1688385Y1213582D03*
X1684645D03*
X1680905Y1221062D03*
Y1217322D03*
X1677165Y1221062D03*
Y1213582D03*
X1680905D03*
Y1209842D03*
X1688385Y1206102D03*
X1684645D03*
X1680905D03*
X1677165D03*
X1692126Y1213582D03*
X1684645Y1217322D03*
Y1209842D03*
X1692126Y1206102D03*
X1677165Y1209842D03*
X1692126Y1221062D03*
X1688385Y1209842D03*
X1677165Y1217322D03*
X1688385D03*
X1692126Y1224803D03*
X1688385D03*
Y1228543D03*
X1684645Y1236023D03*
Y1232283D03*
X1692126D03*
Y1236023D03*
X1680905Y1224803D03*
Y1228543D03*
X1677165Y1232283D03*
Y1236023D03*
X1682775Y1222932D03*
X1677165Y1228543D03*
X1680905Y1236023D03*
Y1232283D03*
X1692126Y1228543D03*
X1684645Y1224803D03*
Y1228543D03*
X1677165Y1224803D03*
X1688385Y1232283D03*
Y1236023D03*
X1684645Y1250984D03*
Y1254724D03*
X1692126Y1250984D03*
X1688385Y1247243D03*
Y1243503D03*
X1692126D03*
X1684645Y1239763D03*
X1688385D03*
X1692126Y1254724D03*
X1677165Y1250984D03*
Y1254724D03*
X1680905Y1247243D03*
Y1243503D03*
X1677165Y1239763D03*
X1680905D03*
X1684645Y1243503D03*
X1677165D03*
X1692126Y1247243D03*
X1684645D03*
X1677165D03*
X1688385Y1254724D03*
Y1250984D03*
X1692126Y1239763D03*
X1680905Y1254724D03*
Y1250984D03*
X1688385Y1258465D03*
X1680905D03*
X1678238Y1348187D03*
X1690478D03*
X1682598D03*
X1678238Y1360099D03*
X1690478D03*
X1682598D03*
X1678238Y1372385D03*
Y1384297D03*
X1690478D03*
Y1372385D03*
X1682598Y1384297D03*
Y1372385D03*
X1678238Y1396583D03*
X1690478D03*
X1682598D03*
X1678238Y1408495D03*
X1690478D03*
X1682598D03*
X1695866Y1090157D03*
Y1086417D03*
Y1078936D03*
X1699607Y1090158D03*
Y1082677D03*
X1695866Y1082676D03*
Y1093897D03*
Y1097637D03*
Y1105117D03*
X1699607Y1101378D03*
X1695866Y1101377D03*
Y1112598D03*
Y1120078D03*
X1699607Y1123819D03*
Y1116339D03*
Y1108859D03*
X1695866Y1123818D03*
Y1116338D03*
Y1108858D03*
X1700236Y1136909D03*
X1697736Y1140649D03*
X1693996D03*
X1695866Y1127558D03*
Y1135039D03*
X1699607Y1131300D03*
X1695866Y1131299D03*
X1693996Y1136909D03*
X1697736D03*
Y1148129D03*
X1693996D03*
X1697736Y1155610D03*
X1693996D03*
Y1151870D03*
X1697736D03*
X1693996Y1144389D03*
X1697736D03*
X1693996Y1170570D03*
Y1166830D03*
X1697736D03*
Y1170570D03*
Y1159350D03*
X1693996D03*
X1697736Y1178051D03*
X1693996D03*
X1697736Y1185531D03*
X1693996D03*
X1697736Y1174310D03*
X1693996Y1189271D03*
X1697736D03*
Y1181791D03*
X1693996D03*
Y1174310D03*
Y1193011D03*
X1697676D03*
X1695866Y1202362D03*
X1699607Y1198621D03*
X1695866D03*
Y1217322D03*
Y1209842D03*
X1699607Y1221062D03*
Y1213582D03*
Y1206102D03*
X1695866Y1221062D03*
Y1213582D03*
Y1206102D03*
Y1232283D03*
Y1236023D03*
Y1224803D03*
X1699607Y1228543D03*
X1695866D03*
Y1250984D03*
Y1243503D03*
X1699607Y1247243D03*
Y1239762D03*
X1695866Y1239763D03*
Y1247243D03*
X1694838Y1348187D03*
X1702718D03*
X1707078D03*
X1702718Y1360099D03*
X1707078D03*
X1694838D03*
Y1384297D03*
Y1372385D03*
X1702718D03*
Y1384297D03*
X1707078D03*
Y1372385D03*
X1694838Y1396583D03*
X1702718D03*
X1707078D03*
X1694838Y1408495D03*
X1702718D03*
X1707078D03*
X1714958Y1348187D03*
X1719318D03*
X1714958Y1360099D03*
X1719318D03*
X1714958Y1384297D03*
Y1372385D03*
X1719318D03*
Y1384297D03*
X1714958Y1396583D03*
X1719318D03*
X1714958Y1408495D03*
X1719318D03*
X1727198Y1348187D03*
X1739438D03*
X1731558D03*
X1727198Y1360099D03*
X1739438D03*
X1731558D03*
X1739438Y1372385D03*
X1731558Y1384297D03*
Y1372385D03*
X1727198D03*
Y1384297D03*
X1739438D03*
X1727198Y1396583D03*
X1739438D03*
X1731558D03*
X1727198Y1408495D03*
X1739438D03*
X1731558D03*
X1796283Y441086D03*
Y433999D03*
Y437543D03*
X1793483Y441086D03*
Y433999D03*
Y437543D03*
X1796283Y444629D03*
X1793483D03*
G54D92*
X78447Y273540D03*
X180809D03*
X283171D03*
X385533D03*
X535534D03*
X637896D03*
X740258D03*
X842620D03*
X992620D03*
X1094982D03*
X1197344D03*
X1299706D03*
X1449707D03*
X1552069D03*
X1654431D03*
X1756793D03*
G54D194*
X795791Y1446386D03*
Y1448158D03*
Y1457016D03*
Y1458788D03*
Y1453473D03*
Y1449930D03*
Y1455244D03*
Y1451701D03*
X821283Y1446386D03*
Y1448158D03*
Y1458788D03*
Y1451701D03*
Y1457016D03*
Y1453473D03*
Y1455244D03*
Y1449930D03*
G54D167*
X466046Y1010216D03*
Y1022815D03*
Y1013366D03*
Y1011791D03*
Y1016516D03*
Y1018090D03*
Y1024390D03*
Y1014941D03*
Y1021240D03*
Y1019665D03*
X484944Y1010216D03*
Y1021240D03*
Y1019665D03*
Y1018090D03*
Y1011791D03*
Y1014941D03*
Y1022815D03*
Y1016516D03*
Y1024390D03*
Y1013366D03*
X1380220Y1010216D03*
Y1022815D03*
Y1013366D03*
Y1011791D03*
Y1016516D03*
Y1018090D03*
Y1024390D03*
Y1014941D03*
Y1021240D03*
Y1019665D03*
X1399118Y1010216D03*
Y1021240D03*
Y1019665D03*
Y1018090D03*
Y1011791D03*
Y1014941D03*
Y1022815D03*
Y1016516D03*
Y1024390D03*
Y1013366D03*
G54D74*
X45755Y1204259D03*
Y1202684D03*
Y1201110D03*
Y1210558D03*
Y1208984D03*
Y1207409D03*
Y1205834D03*
X410938Y872074D03*
Y873648D03*
Y875223D03*
Y876798D03*
Y878373D03*
Y879948D03*
Y881522D03*
X438087Y636111D03*
Y634536D03*
Y632961D03*
Y631386D03*
Y629811D03*
Y628237D03*
Y637685D03*
X889445Y1219561D03*
Y1217987D03*
Y1216412D03*
Y1214837D03*
Y1213262D03*
Y1211687D03*
Y1210113D03*
X953422Y1219561D03*
Y1217987D03*
Y1216412D03*
Y1214837D03*
Y1213262D03*
Y1211687D03*
Y1210113D03*
X1797402Y1220047D03*
Y1218473D03*
Y1216898D03*
Y1215323D03*
Y1213748D03*
Y1212173D03*
Y1210599D03*
G54D276*
G01X11781Y1529312D02*
X10309Y1527848D01*
X9170D01*
X7983Y1529035D01*
G01X22756Y1528531D02*
X21916D01*
X21474Y1528089D01*
X17944D01*
X16840Y1528092D01*
X13001D01*
X11781Y1529312D01*
G01X7983Y1525635D02*
X9162Y1526814D01*
X9166D01*
X9170Y1526818D01*
X10304D01*
X11768Y1525348D01*
G01X22756Y1526562D02*
X21904D01*
X21407Y1527059D01*
X17942D01*
X16838Y1527062D01*
X13482D01*
X11768Y1525348D01*
G01X41988Y111772D02*
X40095D01*
X39447Y112420D01*
X36853D01*
X35688Y111255D01*
G01X41988Y114134D02*
Y114135D01*
X40102D01*
X39467Y113500D01*
X36843D01*
X35688Y114655D01*
G01X41988Y121221D02*
X40088D01*
X39447Y120580D01*
X29550D01*
X28388Y121742D01*
G01X41988Y125945D02*
X40095D01*
X39470Y126570D01*
X36830D01*
X35688Y125428D01*
G01X41988Y133032D02*
X40108D01*
X39467Y133673D01*
X29546D01*
X28388Y132515D01*
G01X41988Y118859D02*
X40108D01*
X39467Y119500D01*
X29546D01*
X28388Y118342D01*
G01X41988Y128307D02*
X40101D01*
X39444Y127650D01*
X36866D01*
X35688Y128828D01*
G01X41988Y135394D02*
X40088D01*
X39447Y134753D01*
X29550D01*
X28388Y135915D01*
G01X30543Y1479284D02*
Y1458657D01*
X76300Y1412900D01*
X204077D01*
X207380Y1409597D01*
X226635D01*
X231007Y1413969D01*
X372381D01*
X394483Y1436071D01*
X408144D01*
X417409Y1445336D01*
Y1464788D01*
X408653Y1473544D01*
Y1478409D01*
X415956Y1485712D01*
Y1490119D01*
X418839Y1493002D01*
Y1494877D01*
G01X411487Y1494974D02*
Y1493450D01*
X414926Y1490011D01*
Y1486139D01*
X413453Y1484666D01*
X412859D01*
X411734Y1483541D01*
Y1482947D01*
X410610Y1481823D01*
X410016D01*
X408891Y1480698D01*
Y1480104D01*
X407623Y1478836D01*
Y1473117D01*
X416379Y1464361D01*
Y1462771D01*
X415959Y1462351D01*
Y1460761D01*
X416379Y1460341D01*
Y1458751D01*
X415959Y1458331D01*
Y1456741D01*
X416379Y1456321D01*
Y1454731D01*
X415959Y1454311D01*
Y1452721D01*
X416379Y1452301D01*
Y1445763D01*
X407717Y1437101D01*
X394056D01*
X371954Y1414999D01*
X230580D01*
X226258Y1410677D01*
X207828D01*
X204525Y1413980D01*
X76748D01*
X31623Y1459105D01*
Y1463463D01*
G01D02*
Y1481331D01*
X33990Y1483698D01*
X34584D01*
X35709Y1484823D01*
Y1485417D01*
X36833Y1486541D01*
X37427D01*
X38552Y1487666D01*
Y1488260D01*
X39676Y1489384D01*
X40270D01*
X41395Y1490509D01*
Y1491103D01*
X42519Y1492227D01*
Y1502990D01*
X43032Y1503503D01*
Y1504318D01*
G01X30543Y1479284D02*
Y1481779D01*
X41454Y1492690D01*
Y1492689D01*
X41489Y1492654D01*
Y1502989D01*
X41063Y1503415D01*
Y1504318D01*
G01X82638Y1417010D02*
X79894D01*
X37010Y1459894D01*
Y1463660D01*
X35825Y1464845D01*
G01X39225D02*
X38090Y1463710D01*
Y1460342D01*
X64242Y1434190D01*
G01X57402Y1506877D02*
X58225D01*
X58662Y1507314D01*
X61333D01*
X61813Y1506834D01*
Y1498744D01*
X60370Y1497301D01*
X50307D01*
X47655Y1494649D01*
Y1488009D01*
X50138Y1485526D01*
X52773Y1485536D01*
X54351Y1483958D01*
G01X57402Y1508846D02*
X58178D01*
X58680Y1508344D01*
X61760D01*
X62843Y1507261D01*
Y1498317D01*
X60797Y1496271D01*
X50734D01*
X48685Y1494222D01*
Y1488436D01*
X50563Y1486558D01*
X53009Y1486568D01*
X54339Y1487897D01*
G01X68999Y114723D02*
X67776Y113500D01*
X62699D01*
X62065Y114134D01*
X60098D01*
G01X68999Y111123D02*
X67702Y112420D01*
X62727D01*
X62079Y111772D01*
X60098D01*
G01X66856Y104249D02*
X65685Y105420D01*
X62762D01*
X62027Y104685D01*
X60098D01*
G01X66856Y107649D02*
X65707Y106500D01*
X62628D01*
X62081Y107047D01*
X60098D01*
G01X79401Y132409D02*
X78140Y133670D01*
X62732D01*
X62094Y133032D01*
X60098D01*
G01X68999Y128896D02*
X67703Y127600D01*
X62772D01*
X62065Y128307D01*
X60098D01*
G01X68999Y125296D02*
X67775Y126520D01*
X62654D01*
X62079Y125945D01*
X60098D01*
G01X79401Y121835D02*
X78166Y120600D01*
X62690D01*
X62069Y121221D01*
X60098D01*
G01X79401Y118235D02*
X78116Y119520D01*
X62740D01*
X62079Y118859D01*
X60098D01*
G01X79401Y136009D02*
X78142Y134750D01*
X62722D01*
X62078Y135394D01*
X60098D01*
G01X64242Y1434190D02*
X80342Y1418090D01*
X206511D01*
X209372Y1415229D01*
X224076D01*
X228147Y1419300D01*
X370395D01*
X371717Y1420622D01*
Y1421258D01*
X372842Y1422383D01*
X373478D01*
X374602Y1423507D01*
Y1424143D01*
X375727Y1425268D01*
X376363D01*
X377487Y1426392D01*
Y1427028D01*
X378612Y1428153D01*
X379248D01*
X380372Y1429277D01*
Y1429913D01*
X381497Y1431038D01*
X382133D01*
X390017Y1438922D01*
Y1439558D01*
X391142Y1440683D01*
X391778D01*
X392902Y1441807D01*
Y1442443D01*
X394027Y1443568D01*
X394663D01*
X399098Y1448003D01*
Y1458175D01*
X398648Y1458625D01*
Y1460215D01*
X399098Y1460665D01*
Y1462255D01*
X398648Y1462705D01*
Y1464295D01*
X399098Y1464745D01*
Y1469218D01*
X402622Y1472742D01*
Y1501804D01*
X396881Y1507545D01*
Y1509170D01*
X393620Y1512431D01*
Y1513298D01*
G01X71404Y1452463D02*
Y1479376D01*
X65323Y1485457D01*
X55850D01*
X54351Y1483958D01*
G01X68664Y1483644D02*
X65771Y1486537D01*
X55699D01*
X54339Y1487897D01*
G01X56248Y1750941D02*
Y1754871D01*
X56778Y1755401D01*
X66896D01*
X68588Y1757093D01*
Y1760833D01*
X69648Y1761893D01*
X74068D01*
X75128Y1760833D01*
Y1750601D01*
X76820Y1748909D01*
X82136D01*
X83828Y1750601D01*
Y1760833D01*
X84888Y1761893D01*
X89308D01*
X90368Y1760833D01*
Y1750601D01*
X92060Y1748909D01*
X97376D01*
X99068Y1750601D01*
Y1760833D01*
X100128Y1761893D01*
X104548D01*
X105608Y1760833D01*
Y1750601D01*
X107300Y1748909D01*
X112616D01*
X114308Y1750601D01*
Y1760833D01*
X115368Y1761893D01*
X119788D01*
X120848Y1760833D01*
Y1750601D01*
X122540Y1748909D01*
X127856D01*
X129548Y1750601D01*
Y1760833D01*
X130608Y1761893D01*
X135028D01*
X136088Y1760833D01*
Y1750601D01*
X137780Y1748909D01*
X143096D01*
X144788Y1750601D01*
Y1760833D01*
X145848Y1761893D01*
X150268D01*
X151328Y1760833D01*
Y1750601D01*
X153020Y1748909D01*
X158336D01*
X160028Y1750601D01*
Y1760833D01*
X161088Y1761893D01*
X165508D01*
X166568Y1760833D01*
Y1750601D01*
X168260Y1748909D01*
X173576D01*
X175268Y1750601D01*
Y1760833D01*
X176328Y1761893D01*
X180748D01*
X181808Y1760833D01*
Y1750601D01*
X183500Y1748909D01*
X188816D01*
X190508Y1750601D01*
Y1760833D01*
X191568Y1761893D01*
X195988D01*
X197048Y1760833D01*
Y1750601D01*
X198740Y1748909D01*
X204056D01*
X205748Y1750601D01*
Y1760833D01*
X206808Y1761893D01*
X211228D01*
X212288Y1760833D01*
Y1750601D01*
X213980Y1748909D01*
X219296D01*
X220988Y1750601D01*
Y1760833D01*
X222048Y1761893D01*
X226468D01*
X227528Y1760833D01*
Y1750601D01*
X229220Y1748909D01*
X234536D01*
X236228Y1750601D01*
Y1760833D01*
X237288Y1761893D01*
X241708D01*
X242768Y1760833D01*
Y1750601D01*
X244460Y1748909D01*
X249776D01*
X251468Y1750601D01*
Y1760833D01*
X252528Y1761893D01*
X256948D01*
X258008Y1760833D01*
Y1750601D01*
X259700Y1748909D01*
X265016D01*
X266708Y1750601D01*
Y1760833D01*
X267768Y1761893D01*
X272188D01*
X273248Y1760833D01*
Y1750601D01*
X274940Y1748909D01*
X280256D01*
X281948Y1750601D01*
Y1760833D01*
X283008Y1761893D01*
X287428D01*
X288488Y1760833D01*
Y1750601D01*
X290180Y1748909D01*
X295496D01*
X297188Y1750601D01*
Y1754341D01*
X298248Y1755401D01*
X307918D01*
X308448Y1754871D01*
Y1750941D01*
G01X56248Y1760941D02*
Y1757011D01*
X56778Y1756481D01*
X66448D01*
X67508Y1757541D01*
Y1761281D01*
X69200Y1762973D01*
X74516D01*
X76208Y1761281D01*
Y1751049D01*
X77268Y1749989D01*
X81688D01*
X82748Y1751049D01*
Y1761281D01*
X84440Y1762973D01*
X89756D01*
X91448Y1761281D01*
Y1751049D01*
X92508Y1749989D01*
X96928D01*
X97988Y1751049D01*
Y1761281D01*
X99680Y1762973D01*
X104996D01*
X106688Y1761281D01*
Y1751049D01*
X107748Y1749989D01*
X112168D01*
X113228Y1751049D01*
Y1761281D01*
X114920Y1762973D01*
X120236D01*
X121928Y1761281D01*
Y1751049D01*
X122988Y1749989D01*
X127408D01*
X128468Y1751049D01*
Y1761281D01*
X130160Y1762973D01*
X135476D01*
X137168Y1761281D01*
Y1751049D01*
X138228Y1749989D01*
X142648D01*
X143708Y1751049D01*
Y1761281D01*
X145400Y1762973D01*
X150716D01*
X152408Y1761281D01*
Y1751049D01*
X153468Y1749989D01*
X157888D01*
X158948Y1751049D01*
Y1761281D01*
X160640Y1762973D01*
X165956D01*
X167648Y1761281D01*
Y1751049D01*
X168708Y1749989D01*
X173128D01*
X174188Y1751049D01*
Y1761281D01*
X175880Y1762973D01*
X181196D01*
X182888Y1761281D01*
Y1751049D01*
X183948Y1749989D01*
X188368D01*
X189428Y1751049D01*
Y1761281D01*
X191120Y1762973D01*
X196436D01*
X198128Y1761281D01*
Y1751049D01*
X199188Y1749989D01*
X203608D01*
X204668Y1751049D01*
Y1761281D01*
X206360Y1762973D01*
X211676D01*
X213368Y1761281D01*
Y1751049D01*
X214428Y1749989D01*
X218848D01*
X219908Y1751049D01*
Y1761281D01*
X221600Y1762973D01*
X226916D01*
X228608Y1761281D01*
Y1751049D01*
X229668Y1749989D01*
X234088D01*
X235148Y1751049D01*
Y1761281D01*
X236840Y1762973D01*
X242156D01*
X243848Y1761281D01*
Y1751049D01*
X244908Y1749989D01*
X249328D01*
X250388Y1751049D01*
Y1761281D01*
X252080Y1762973D01*
X257396D01*
X259088Y1761281D01*
Y1751049D01*
X260148Y1749989D01*
X264568D01*
X265628Y1751049D01*
Y1761281D01*
X267320Y1762973D01*
X272636D01*
X274328Y1761281D01*
Y1751049D01*
X275388Y1749989D01*
X279808D01*
X280868Y1751049D01*
Y1761281D01*
X282560Y1762973D01*
X287876D01*
X289568Y1761281D01*
Y1751049D01*
X290628Y1749989D01*
X295048D01*
X296108Y1751049D01*
Y1754789D01*
X297800Y1756481D01*
X307918D01*
X308448Y1757011D01*
Y1760941D01*
G01X76005Y114623D02*
X74882Y113500D01*
X72322D01*
X71099Y114723D01*
G01X76005Y111223D02*
X74808Y112420D01*
X72396D01*
X71099Y111123D01*
G01X86407Y132509D02*
X85246Y133670D01*
X82762D01*
X81501Y132409D01*
G01X86407Y118335D02*
X85242Y119500D01*
X82766D01*
X81501Y118235D01*
G01X86407Y121735D02*
X85252Y120580D01*
X82756D01*
X81501Y121835D01*
G01X76005Y125396D02*
X74881Y126520D01*
X72323D01*
X71099Y125296D01*
G01X76005Y128796D02*
X74809Y127600D01*
X72395D01*
X71099Y128896D01*
G01X86407Y135909D02*
X85248Y134750D01*
X82760D01*
X81501Y136009D01*
G01X76012Y1353093D02*
X77272Y1351833D01*
Y1349347D01*
X76112Y1348187D01*
G01X79612Y1353093D02*
X78352Y1351833D01*
Y1349347D01*
X79512Y1348187D01*
G01X76112Y1360099D02*
X77272Y1358939D01*
Y1356453D01*
X76012Y1355193D01*
G01X79512Y1360099D02*
X78352Y1358939D01*
Y1356453D01*
X79612Y1355193D01*
G01Y1377291D02*
X78352Y1376031D01*
Y1373545D01*
X79512Y1372385D01*
G01X76012Y1377291D02*
X77272Y1376031D01*
Y1373545D01*
X76112Y1372385D01*
G01Y1384297D02*
X77272Y1383137D01*
Y1380651D01*
X76012Y1379391D01*
G01X79512Y1384297D02*
X78352Y1383137D01*
Y1380651D01*
X79612Y1379391D01*
G01X400903Y1513406D02*
Y1512162D01*
X397911Y1509170D01*
Y1507972D01*
X403652Y1502231D01*
Y1472315D01*
X400178Y1468841D01*
Y1447555D01*
X370843Y1418220D01*
X228595D01*
X224524Y1414149D01*
X208924D01*
X206063Y1417010D01*
X82638D01*
G01X71404Y1452463D02*
Y1434767D01*
X83471Y1422700D01*
X206601D01*
X210751Y1418550D01*
X216849D01*
X218305Y1420006D01*
Y1421604D01*
X221543Y1424842D01*
Y1425811D01*
G01X214191Y1425908D02*
Y1424608D01*
X217225Y1421574D01*
Y1420454D01*
X216401Y1419630D01*
X211199D01*
X207049Y1423780D01*
X83919D01*
X72484Y1435215D01*
Y1456705D01*
X73024Y1457245D01*
Y1458835D01*
X72484Y1459375D01*
Y1460965D01*
X72934Y1461415D01*
Y1463005D01*
X72484Y1463455D01*
Y1465045D01*
X72904Y1465465D01*
Y1467055D01*
X72484Y1467475D01*
Y1469065D01*
X72904Y1469485D01*
Y1471075D01*
X72484Y1471495D01*
Y1473085D01*
X72904Y1473505D01*
Y1475095D01*
X72484Y1475515D01*
Y1479824D01*
X68664Y1483644D01*
G01X88252Y1353093D02*
X89512Y1351833D01*
Y1349347D01*
X88352Y1348187D01*
G01X91852Y1353093D02*
X90592Y1351833D01*
Y1349347D01*
X91752Y1348187D01*
G01X100492Y1353093D02*
X101752Y1351833D01*
Y1349347D01*
X100592Y1348187D01*
G01X91752Y1360099D02*
X90592Y1358939D01*
Y1356453D01*
X91852Y1355193D01*
G01X88352Y1360099D02*
X89512Y1358939D01*
Y1356453D01*
X88252Y1355193D01*
G01X100592Y1360099D02*
X101752Y1358939D01*
Y1356453D01*
X100492Y1355193D01*
G01X100592Y1384297D02*
X101752Y1383137D01*
Y1380651D01*
X100492Y1379391D01*
G01Y1377291D02*
X101752Y1376031D01*
Y1373545D01*
X100592Y1372385D01*
G01X91852Y1377291D02*
X90592Y1376031D01*
Y1373545D01*
X91752Y1372385D01*
G01X88252Y1377291D02*
X89512Y1376031D01*
Y1373545D01*
X88352Y1372385D01*
G01Y1384297D02*
X89512Y1383137D01*
Y1380651D01*
X88252Y1379391D01*
G01X91752Y1384297D02*
X90592Y1383137D01*
Y1380651D01*
X91852Y1379391D01*
G01Y1401489D02*
X90592Y1400229D01*
Y1397743D01*
X91752Y1396583D01*
G01X88252Y1401489D02*
X89512Y1400229D01*
Y1397743D01*
X88352Y1396583D01*
G01X100492Y1401489D02*
X101752Y1400229D01*
Y1397743D01*
X100592Y1396583D01*
G01X91752Y1408495D02*
X90592Y1407335D01*
Y1404849D01*
X91852Y1403589D01*
G01X88352Y1408495D02*
X89512Y1407335D01*
Y1404849D01*
X88252Y1403589D01*
G01X100592Y1408495D02*
X101752Y1407335D01*
Y1404849D01*
X100492Y1403589D01*
G01X116332Y1353093D02*
X115072Y1351833D01*
Y1349347D01*
X116232Y1348187D01*
G01X112732Y1353093D02*
X113992Y1351833D01*
Y1349347D01*
X112832Y1348187D01*
G01X104092Y1353093D02*
X102832Y1351833D01*
Y1349347D01*
X103992Y1348187D01*
G01X112832Y1360099D02*
X113992Y1358939D01*
Y1356453D01*
X112732Y1355193D01*
G01X116232Y1360099D02*
X115072Y1358939D01*
Y1356453D01*
X116332Y1355193D01*
G01X103992Y1360099D02*
X102832Y1358939D01*
Y1356453D01*
X104092Y1355193D01*
G01Y1377291D02*
X102832Y1376031D01*
Y1373545D01*
X103992Y1372385D01*
G01Y1384297D02*
X102832Y1383137D01*
Y1380651D01*
X104092Y1379391D01*
G01X112832Y1384297D02*
X113992Y1383137D01*
Y1380651D01*
X112732Y1379391D01*
G01X116332Y1377291D02*
X115072Y1376031D01*
Y1373545D01*
X116232Y1372385D01*
G01Y1384297D02*
X115072Y1383137D01*
Y1380651D01*
X116332Y1379391D01*
G01X112732Y1377291D02*
X113992Y1376031D01*
Y1373545D01*
X112832Y1372385D01*
G01X116332Y1401489D02*
X115072Y1400229D01*
Y1397743D01*
X116232Y1396583D01*
G01X112732Y1401489D02*
X113992Y1400229D01*
Y1397743D01*
X112832Y1396583D01*
G01X104092Y1401489D02*
X102832Y1400229D01*
Y1397743D01*
X103992Y1396583D01*
G01X112832Y1408495D02*
X113992Y1407335D01*
Y1404849D01*
X112732Y1403589D01*
G01X116232Y1408495D02*
X115072Y1407335D01*
Y1404849D01*
X116332Y1403589D01*
G01X103992Y1408495D02*
X102832Y1407335D01*
Y1404849D01*
X104092Y1403589D01*
G01X144350Y133032D02*
X142470D01*
X141829Y133673D01*
X131908D01*
X130750Y132515D01*
G01X144350Y121221D02*
X142450D01*
X141809Y120580D01*
X131912D01*
X130750Y121742D01*
G01X144350Y118859D02*
X142470D01*
X141829Y119500D01*
X131908D01*
X130750Y118342D01*
G01X144350Y135394D02*
X142450D01*
X141809Y134753D01*
X131912D01*
X130750Y135915D01*
G01X124972Y1353093D02*
X126232Y1351833D01*
Y1349347D01*
X125072Y1348187D01*
G01X128572Y1353093D02*
X127312Y1351833D01*
Y1349347D01*
X128472Y1348187D01*
G01Y1360099D02*
X127312Y1358939D01*
Y1356453D01*
X128572Y1355193D01*
G01X125072Y1360099D02*
X126232Y1358939D01*
Y1356453D01*
X124972Y1355193D01*
G01X125072Y1384297D02*
X126232Y1383137D01*
Y1380651D01*
X124972Y1379391D01*
G01X128472Y1384297D02*
X127312Y1383137D01*
Y1380651D01*
X128572Y1379391D01*
G01X124972Y1377291D02*
X126232Y1376031D01*
Y1373545D01*
X125072Y1372385D01*
G01X128572Y1377291D02*
X127312Y1376031D01*
Y1373545D01*
X128472Y1372385D01*
G01X124972Y1401489D02*
X126232Y1400229D01*
Y1397743D01*
X125072Y1396583D01*
G01X128572Y1401489D02*
X127312Y1400229D01*
Y1397743D01*
X128472Y1396583D01*
G01X125072Y1408495D02*
X126232Y1407335D01*
Y1404849D01*
X124972Y1403589D01*
G01X128472Y1408495D02*
X127312Y1407335D01*
Y1404849D01*
X128572Y1403589D01*
G01X144350Y111772D02*
X142457D01*
X141809Y112420D01*
X139215D01*
X138050Y111255D01*
G01X144350Y114134D02*
Y114135D01*
X142464D01*
X141829Y113500D01*
X139205D01*
X138050Y114655D01*
G01X144350Y128307D02*
X142463D01*
X141806Y127650D01*
X139228D01*
X138050Y128828D01*
G01X144350Y125945D02*
X142457D01*
X141832Y126570D01*
X139192D01*
X138050Y125428D01*
G01X148692Y391001D02*
X149852Y392161D01*
X152338D01*
X153598Y390901D01*
G01Y394501D02*
X152338Y393241D01*
X149852D01*
X148692Y394401D01*
G01X153598Y405074D02*
X152338Y406334D01*
X149852D01*
X148692Y405174D01*
G01X145596Y401613D02*
X144336Y400353D01*
X141850D01*
X140690Y401513D01*
G01X145596Y398013D02*
X144336Y399273D01*
X141850D01*
X140690Y398113D01*
G01X153598Y408674D02*
X152338Y407414D01*
X149852D01*
X148692Y408574D01*
G01X181269Y400965D02*
X179348D01*
X178706Y400323D01*
X148986D01*
X147696Y401613D01*
G01X181269Y398602D02*
X179347D01*
X178706Y399243D01*
X148926D01*
X147696Y398013D01*
G01X143196Y412187D02*
X141936Y413447D01*
X139450D01*
X138290Y412287D01*
G01X153598Y419247D02*
X152338Y420507D01*
X149852D01*
X148692Y419347D01*
G01X153598Y422847D02*
X152338Y421587D01*
X149852D01*
X148692Y422747D01*
G01X143196Y415787D02*
X141936Y414527D01*
X139450D01*
X138290Y415687D01*
G01X145296Y415787D02*
X146586Y414497D01*
X178707D01*
X179348Y415138D01*
X181269D01*
G01X145296Y412187D02*
X146526Y413417D01*
X178707D01*
X179348Y412776D01*
X181269D01*
G01X153598Y433421D02*
X152338Y434681D01*
X149852D01*
X148692Y433521D01*
G01X143196Y426360D02*
X141936Y427620D01*
X139450D01*
X138290Y426460D01*
G01X143196Y429960D02*
X141936Y428700D01*
X139450D01*
X138290Y429860D01*
G01X153598Y437021D02*
X152338Y435761D01*
X149852D01*
X148692Y436921D01*
G01X143196Y440533D02*
X141936Y441793D01*
X139450D01*
X138290Y440633D01*
G01X145296Y429960D02*
X146586Y428670D01*
X178707D01*
X179348Y429311D01*
X181269D01*
G01X145296Y426360D02*
X146526Y427590D01*
X178707D01*
X179348Y426949D01*
X181269D01*
G01X145296Y440533D02*
X146526Y441763D01*
X178707D01*
X179348Y441122D01*
X181269D01*
G01X143196Y444133D02*
X141936Y442873D01*
X139450D01*
X138290Y444033D01*
G01X145296Y444133D02*
X146586Y442843D01*
X178707D01*
X179348Y443484D01*
X181269D01*
G01X143196Y469287D02*
X141936Y470547D01*
X139450D01*
X138290Y469387D01*
G01X143196Y472887D02*
X141936Y471627D01*
X139450D01*
X138290Y472787D01*
G01X181269Y472264D02*
X179348D01*
X178707Y471623D01*
X146560D01*
X145296Y472887D01*
G01X181269Y469902D02*
X179348D01*
X178707Y470543D01*
X146552D01*
X145296Y469287D01*
G01X153598Y476399D02*
X152338Y477659D01*
X149852D01*
X148692Y476499D01*
G01X143196Y483460D02*
X141936Y484720D01*
X139450D01*
X138290Y483560D01*
G01X143196Y487060D02*
X141936Y485800D01*
X139450D01*
X138290Y486960D01*
G01X153598Y479999D02*
X152338Y478739D01*
X149852D01*
X148692Y479899D01*
G01X181269Y486437D02*
X179348D01*
X178707Y485796D01*
X146560D01*
X145296Y487060D01*
G01X181269Y484075D02*
X179348D01*
X178707Y484716D01*
X146552D01*
X145296Y483460D01*
G01X153598Y490573D02*
X152338Y491833D01*
X149852D01*
X148692Y490673D01*
G01X153598Y494173D02*
X152338Y492913D01*
X149852D01*
X148692Y494073D01*
G01X153598Y520533D02*
X152338Y521793D01*
X149852D01*
X148692Y520633D01*
G01X143196Y517021D02*
X141936Y515761D01*
X139450D01*
X138290Y516921D01*
G01X143196Y513421D02*
X141936Y514681D01*
X139450D01*
X138290Y513521D01*
G01X181269Y516398D02*
X179348D01*
X178707Y515757D01*
X146560D01*
X145296Y517021D01*
G01X181269Y514036D02*
X179348D01*
X178707Y514677D01*
X146552D01*
X145296Y513421D01*
G01X153598Y524133D02*
X152338Y522873D01*
X149852D01*
X148692Y524033D01*
G01X143196Y531194D02*
X141936Y529934D01*
X139450D01*
X138290Y531094D01*
G01X153598Y538306D02*
X152338Y537046D01*
X149852D01*
X148692Y538206D01*
G01X153598Y534706D02*
X152338Y535966D01*
X149852D01*
X148692Y534806D01*
G01X143196Y527594D02*
X141936Y528854D01*
X139450D01*
X138290Y527694D01*
G01X181269Y530571D02*
X179348D01*
X178707Y529930D01*
X146560D01*
X145296Y531194D01*
G01X181269Y528209D02*
X179348D01*
X178707Y528850D01*
X146552D01*
X145296Y527594D01*
G01X148818Y1138779D02*
X146948Y1136909D01*
G01X145078Y1138779D02*
X143208Y1136909D01*
G01X140812Y1353093D02*
X139552Y1351833D01*
Y1349347D01*
X140712Y1348187D01*
G01X137212Y1353093D02*
X138472Y1351833D01*
Y1349347D01*
X137312Y1348187D01*
G01Y1360099D02*
X138472Y1358939D01*
Y1356453D01*
X137212Y1355193D01*
G01X140712Y1360099D02*
X139552Y1358939D01*
Y1356453D01*
X140812Y1355193D01*
G01Y1377291D02*
X139552Y1376031D01*
Y1373545D01*
X140712Y1372385D01*
G01Y1384297D02*
X139552Y1383137D01*
Y1380651D01*
X140812Y1379391D01*
G01X137312Y1384297D02*
X138472Y1383137D01*
Y1380651D01*
X137212Y1379391D01*
G01Y1377291D02*
X138472Y1376031D01*
Y1373545D01*
X137312Y1372385D01*
G01X140812Y1401489D02*
X139552Y1400229D01*
Y1397743D01*
X140712Y1396583D01*
G01X137212Y1401489D02*
X138472Y1400229D01*
Y1397743D01*
X137312Y1396583D01*
G01X140712Y1408495D02*
X139552Y1407335D01*
Y1404849D01*
X140812Y1403589D01*
G01X137312Y1408495D02*
X138472Y1407335D01*
Y1404849D01*
X137212Y1403589D01*
G01X171361Y111123D02*
X170064Y112420D01*
X165089D01*
X164441Y111772D01*
X162460D01*
G01X171361Y114723D02*
X170138Y113500D01*
X165061D01*
X164427Y114134D01*
X162460D01*
G01X169218Y107649D02*
X168069Y106500D01*
X164990D01*
X164443Y107047D01*
X162460D01*
G01X169218Y104249D02*
X168047Y105420D01*
X165124D01*
X164389Y104685D01*
X162460D01*
G01X171361Y125296D02*
X170137Y126520D01*
X165016D01*
X164441Y125945D01*
X162460D01*
G01X181763Y118235D02*
X180478Y119520D01*
X165102D01*
X164441Y118859D01*
X162460D01*
G01X181763Y121835D02*
X180528Y120600D01*
X165052D01*
X164431Y121221D01*
X162460D01*
G01X171361Y128896D02*
X170065Y127600D01*
X165134D01*
X164427Y128307D01*
X162460D01*
G01X181763Y132409D02*
X180502Y133670D01*
X165094D01*
X164456Y133032D01*
X162460D01*
G01X181763Y136009D02*
X180504Y134750D01*
X165084D01*
X164440Y135394D01*
X162460D01*
G01X181269Y391516D02*
X179348D01*
X178707Y392157D01*
X156954D01*
X155698Y390901D01*
G01Y405074D02*
X156954Y406330D01*
X178707D01*
X179348Y405689D01*
X181269D01*
G01X155698Y408674D02*
X156962Y407410D01*
X178707D01*
X179348Y408051D01*
X181269D01*
G01Y393878D02*
X179348D01*
X178707Y393237D01*
X156962D01*
X155698Y394501D01*
G01Y419247D02*
X156954Y420503D01*
X178707D01*
X179348Y419862D01*
X181269D01*
G01X155698Y422847D02*
X156962Y421583D01*
X178707D01*
X179348Y422224D01*
X181269D01*
G01X155698Y433421D02*
X156954Y434677D01*
X178707D01*
X179348Y434036D01*
X181269D01*
G01X155698Y437021D02*
X156962Y435757D01*
X178707D01*
X179348Y436398D01*
X181269D01*
G01Y479350D02*
X179348D01*
X178707Y478709D01*
X156988D01*
X155698Y479999D01*
G01X181269Y476988D02*
X179348D01*
X178707Y477629D01*
X156928D01*
X155698Y476399D01*
G01X181269Y493524D02*
X179348D01*
X178707Y492883D01*
X156988D01*
X155698Y494173D01*
G01X181269Y491162D02*
X179348D01*
X178707Y491803D01*
X156928D01*
X155698Y490573D01*
G01X181269Y523484D02*
X179348D01*
X178707Y522843D01*
X156988D01*
X155698Y524133D01*
G01X181269Y521122D02*
X179348D01*
X178707Y521763D01*
X156928D01*
X155698Y520533D01*
G01Y534706D02*
X156928Y535936D01*
X178706D01*
X179347Y535295D01*
X181269D01*
G01X155698Y538306D02*
X156988Y537016D01*
X178706D01*
X179348Y537658D01*
X181269D01*
G01X152559Y1135039D02*
X150689Y1133169D01*
G01X163779Y1135039D02*
X161909Y1133169D01*
G01X156299Y1135039D02*
X154429Y1133169D01*
G01X165292Y1353093D02*
X164032Y1351833D01*
Y1349347D01*
X165192Y1348187D01*
G01X161692Y1353093D02*
X162952Y1351833D01*
Y1349347D01*
X161792Y1348187D01*
G01X153052Y1353093D02*
X151792Y1351833D01*
Y1349347D01*
X152952Y1348187D01*
G01X149452Y1353093D02*
X150712Y1351833D01*
Y1349347D01*
X149552Y1348187D01*
G01X165192Y1360099D02*
X164032Y1358939D01*
Y1356453D01*
X165292Y1355193D01*
G01X161792Y1360099D02*
X162952Y1358939D01*
Y1356453D01*
X161692Y1355193D01*
G01X149552Y1360099D02*
X150712Y1358939D01*
Y1356453D01*
X149452Y1355193D01*
G01X152952Y1360099D02*
X151792Y1358939D01*
Y1356453D01*
X153052Y1355193D01*
G01X152952Y1384297D02*
X151792Y1383137D01*
Y1380651D01*
X153052Y1379391D01*
G01X149552Y1384297D02*
X150712Y1383137D01*
Y1380651D01*
X149452Y1379391D01*
G01Y1377291D02*
X150712Y1376031D01*
Y1373545D01*
X149552Y1372385D01*
G01X153052Y1377291D02*
X151792Y1376031D01*
Y1373545D01*
X152952Y1372385D01*
G01X161792Y1384297D02*
X162952Y1383137D01*
Y1380651D01*
X161692Y1379391D01*
G01X165292Y1377291D02*
X164032Y1376031D01*
Y1373545D01*
X165192Y1372385D01*
G01Y1384297D02*
X164032Y1383137D01*
Y1380651D01*
X165292Y1379391D01*
G01X161692Y1377291D02*
X162952Y1376031D01*
Y1373545D01*
X161792Y1372385D01*
G01X165292Y1401489D02*
X164032Y1400229D01*
Y1397743D01*
X165192Y1396583D01*
G01X161692Y1401489D02*
X162952Y1400229D01*
Y1397743D01*
X161792Y1396583D01*
G01X153052Y1401489D02*
X151792Y1400229D01*
Y1397743D01*
X152952Y1396583D01*
G01X149452Y1401489D02*
X150712Y1400229D01*
Y1397743D01*
X149552Y1396583D01*
G01X165192Y1408495D02*
X164032Y1407335D01*
Y1404849D01*
X165292Y1403589D01*
G01X161792Y1408495D02*
X162952Y1407335D01*
Y1404849D01*
X161692Y1403589D01*
G01X149552Y1408495D02*
X150712Y1407335D01*
Y1404849D01*
X149452Y1403589D01*
G01X152952Y1408495D02*
X151792Y1407335D01*
Y1404849D01*
X153052Y1403589D01*
G01X178367Y111223D02*
X177170Y112420D01*
X174758D01*
X173461Y111123D01*
G01X178367Y114623D02*
X177244Y113500D01*
X174684D01*
X173461Y114723D01*
G01X178367Y128796D02*
X177171Y127600D01*
X174757D01*
X173461Y128896D01*
G01X178367Y125396D02*
X177243Y126520D01*
X174685D01*
X173461Y125296D01*
G01X174923Y545263D02*
X176083Y544103D01*
X178899D01*
X179540Y544744D01*
X181269D01*
G01X174923Y541863D02*
X176083Y543023D01*
X178899D01*
X179540Y542382D01*
X181269D01*
G01X167519Y1135039D02*
X165649Y1133169D01*
G01X174999Y1138779D02*
X173129Y1136909D01*
G01X171259Y1138779D02*
X169389Y1136909D01*
G01X177532Y1353093D02*
X176272Y1351833D01*
Y1349347D01*
X177432Y1348187D01*
G01X173932Y1353093D02*
X175192Y1351833D01*
Y1349347D01*
X174032Y1348187D01*
G01Y1360099D02*
X175192Y1358939D01*
Y1356453D01*
X173932Y1355193D01*
G01X177432Y1360099D02*
X176272Y1358939D01*
Y1356453D01*
X177532Y1355193D01*
G01X177432Y1384297D02*
X176272Y1383137D01*
Y1380651D01*
X177532Y1379391D01*
G01X174032Y1384297D02*
X175192Y1383137D01*
Y1380651D01*
X173932Y1379391D01*
G01Y1377291D02*
X175192Y1376031D01*
Y1373545D01*
X174032Y1372385D01*
G01X177532Y1377291D02*
X176272Y1376031D01*
Y1373545D01*
X177432Y1372385D01*
G01X177532Y1401489D02*
X176272Y1400229D01*
Y1397743D01*
X177432Y1396583D01*
G01X173932Y1401489D02*
X175192Y1400229D01*
Y1397743D01*
X174032Y1396583D01*
G01X177432Y1408495D02*
X176272Y1407335D01*
Y1404849D01*
X177532Y1403589D01*
G01X174032Y1408495D02*
X175192Y1407335D01*
Y1404849D01*
X173932Y1403589D01*
G01X188769Y118335D02*
X187604Y119500D01*
X185128D01*
X183863Y118235D01*
G01X188769Y121735D02*
X187614Y120580D01*
X185118D01*
X183863Y121835D01*
G01X188769Y132509D02*
X187608Y133670D01*
X185124D01*
X183863Y132409D01*
G01X188769Y135909D02*
X187610Y134750D01*
X185122D01*
X183863Y136009D01*
G01X189772Y1353093D02*
X188512Y1351833D01*
Y1349347D01*
X189672Y1348187D01*
G01X186172Y1353093D02*
X187432Y1351833D01*
Y1349347D01*
X186272Y1348187D01*
G01X189672Y1360099D02*
X188512Y1358939D01*
Y1356453D01*
X189772Y1355193D01*
G01X186272Y1360099D02*
X187432Y1358939D01*
Y1356453D01*
X186172Y1355193D01*
G01X186272Y1384297D02*
X187432Y1383137D01*
Y1380651D01*
X186172Y1379391D01*
G01X189672Y1384297D02*
X188512Y1383137D01*
Y1380651D01*
X189772Y1379391D01*
G01Y1377291D02*
X188512Y1376031D01*
Y1373545D01*
X189672Y1372385D01*
G01X186172Y1377291D02*
X187432Y1376031D01*
Y1373545D01*
X186272Y1372385D01*
G01X186172Y1401489D02*
X187432Y1400229D01*
Y1397743D01*
X186272Y1396583D01*
G01X189772Y1401489D02*
X188512Y1400229D01*
Y1397743D01*
X189672Y1396583D01*
G01Y1408495D02*
X188512Y1407335D01*
Y1404849D01*
X189772Y1403589D01*
G01X186272Y1408495D02*
X187432Y1407335D01*
Y1404849D01*
X186172Y1403589D01*
G01X199380Y391516D02*
X201301D01*
X201942Y392157D01*
X211818D01*
X212980Y390995D01*
G01X199380Y405689D02*
X201301D01*
X201942Y406330D01*
X211818D01*
X212980Y405168D01*
G01X199380Y393878D02*
X201301D01*
X201942Y393237D01*
X211818D01*
X211820Y393235D01*
X212980Y394395D01*
G01X199380Y400965D02*
X201301D01*
X201943Y400323D01*
X204521D01*
X205680Y401482D01*
G01X199380Y398602D02*
X201302D01*
X201943Y399243D01*
X204519D01*
X205680Y398082D01*
G01X199380Y408051D02*
X201301D01*
X201942Y407410D01*
X211818D01*
X211820Y407408D01*
X212980Y408568D01*
G01X199380Y419862D02*
X201301D01*
X201942Y420503D01*
X211818D01*
X212980Y419341D01*
G01X199380Y422224D02*
X201301D01*
X201942Y421583D01*
X211818D01*
X211820Y421581D01*
X212980Y422741D01*
G01X205680Y415655D02*
X204522Y414497D01*
X201942D01*
X201301Y415138D01*
X199380D01*
G01X205680Y412255D02*
Y412256D01*
X204519Y413417D01*
X201942D01*
X201301Y412776D01*
X199380D01*
G01Y441122D02*
X201301D01*
X201942Y441763D01*
X204519D01*
X205680Y440602D01*
G01Y429828D02*
X204522Y428670D01*
X201942D01*
X201301Y429311D01*
X199380D01*
G01Y434036D02*
X201301D01*
X201942Y434677D01*
X211818D01*
X212980Y433515D01*
G01X205680Y426428D02*
Y426429D01*
X204519Y427590D01*
X201942D01*
X201301Y426949D01*
X199380D01*
G01Y436398D02*
X201301D01*
X201942Y435757D01*
X211818D01*
X211820Y435755D01*
X212980Y436915D01*
G01X199380Y443484D02*
X201301D01*
X201942Y442843D01*
X204521D01*
X205680Y444002D01*
G01X199380Y469902D02*
X201301D01*
X201942Y470543D01*
X211818D01*
X212980Y469381D01*
G01X199380Y472264D02*
X201301D01*
X201942Y471623D01*
X211818D01*
X211820Y471621D01*
X212980Y472781D01*
G01X199380Y479350D02*
X201301D01*
X201942Y478709D01*
X204521D01*
X205680Y479868D01*
G01X199380Y484075D02*
X201301D01*
X201942Y484716D01*
X211818D01*
X212980Y483554D01*
G01X199380Y476988D02*
X201301D01*
X201942Y477629D01*
X204519D01*
X205680Y476468D01*
G01X199380Y486437D02*
X201301D01*
X201942Y485796D01*
X211818D01*
X211820Y485794D01*
X212980Y486954D01*
G01X205680Y494041D02*
X204522Y492883D01*
X201942D01*
X201301Y493524D01*
X199380D01*
G01X205680Y490641D02*
Y490642D01*
X204519Y491803D01*
X201942D01*
X201301Y491162D01*
X199380D01*
G01Y523484D02*
X201301D01*
X201942Y522843D01*
X204521D01*
X205680Y524002D01*
G01X199380Y516398D02*
X201301D01*
X201942Y515757D01*
X211818D01*
X211820Y515755D01*
X212980Y516915D01*
G01X199380Y514036D02*
X201301D01*
X201942Y514677D01*
X211818D01*
X212980Y513515D01*
G01X199380Y521122D02*
X201301D01*
X201942Y521763D01*
X204519D01*
X205680Y520602D01*
G01X199380Y535295D02*
X201302D01*
X201943Y535936D01*
X204519D01*
X205680Y534775D01*
G01X199380Y528209D02*
X201301D01*
X201942Y528850D01*
X211818D01*
X212980Y527688D01*
G01X199380Y537658D02*
X201301D01*
X201943Y537016D01*
X204521D01*
X205680Y538175D01*
G01X199380Y530571D02*
X201301D01*
X201942Y529930D01*
X211818D01*
X211820Y529928D01*
X212980Y531088D01*
G01X202012Y1353093D02*
X200752Y1351833D01*
Y1349347D01*
X201912Y1348187D01*
G01X198412Y1353093D02*
X199672Y1351833D01*
Y1349347D01*
X198512Y1348187D01*
G01Y1360099D02*
X199672Y1358939D01*
Y1356453D01*
X198412Y1355193D01*
G01X201912Y1360099D02*
X200752Y1358939D01*
Y1356453D01*
X202012Y1355193D01*
G01X198512Y1384297D02*
X199672Y1383137D01*
Y1380651D01*
X198412Y1379391D01*
G01X201912Y1384297D02*
X200752Y1383137D01*
Y1380651D01*
X202012Y1379391D01*
G01X198412Y1377291D02*
X199672Y1376031D01*
Y1373545D01*
X198512Y1372385D01*
G01X202012Y1377291D02*
X200752Y1376031D01*
Y1373545D01*
X201912Y1372385D01*
G01X202012Y1401489D02*
X200752Y1400229D01*
Y1397743D01*
X201912Y1396583D01*
G01X198412Y1401489D02*
X199672Y1400229D01*
Y1397743D01*
X198512Y1396583D01*
G01X201912Y1408495D02*
X200752Y1407335D01*
Y1404849D01*
X202012Y1403589D01*
G01X198512Y1408495D02*
X199672Y1407335D01*
Y1404849D01*
X198412Y1403589D01*
G01X217906Y1430452D02*
X216512Y1429058D01*
X214191D01*
G01X216125Y1440028D02*
X217300Y1438853D01*
Y1436521D01*
X214191Y1433412D01*
Y1432208D01*
G01X219559Y1447353D02*
X218292Y1448620D01*
X215136D01*
X213969Y1447453D01*
G01X219559Y1461953D02*
X218306Y1460700D01*
X215122D01*
X213969Y1461853D01*
G01X219559Y1458353D02*
X218292Y1459620D01*
X215136D01*
X213969Y1458453D01*
G01X219559Y1450953D02*
X218306Y1449700D01*
X215122D01*
X213969Y1450853D01*
G01X221543Y1428961D02*
X219815D01*
X217906Y1427052D01*
G01X219525Y1440028D02*
X218380Y1438883D01*
Y1436491D01*
X221543Y1433328D01*
Y1432111D01*
G01X227249Y1447453D02*
X226082Y1448620D01*
X222926D01*
X221659Y1447353D01*
G01X227249Y1450853D02*
X226096Y1449700D01*
X222912D01*
X221659Y1450953D01*
G01X227249Y1458453D02*
X226082Y1459620D01*
X222926D01*
X221659Y1458353D01*
G01X227249Y1461853D02*
X226096Y1460700D01*
X222912D01*
X221659Y1461953D01*
G01X246712Y114134D02*
Y114135D01*
X244826D01*
X244191Y113500D01*
X241567D01*
X240412Y114655D01*
G01X246712Y111772D02*
X244819D01*
X244171Y112420D01*
X241577D01*
X240412Y111255D01*
G01X246712Y133032D02*
X244832D01*
X244191Y133673D01*
X234270D01*
X233112Y132515D01*
G01X246712Y121221D02*
X244812D01*
X244171Y120580D01*
X234274D01*
X233112Y121742D01*
G01X246712Y125945D02*
X244819D01*
X244194Y126570D01*
X241554D01*
X240412Y125428D01*
G01X246712Y118859D02*
X244832D01*
X244191Y119500D01*
X234270D01*
X233112Y118342D01*
G01X246712Y128307D02*
X244825D01*
X244168Y127650D01*
X241590D01*
X240412Y128828D01*
G01X246712Y135394D02*
X244812D01*
X244171Y134753D01*
X234274D01*
X233112Y135915D01*
G01X236712Y1211712D02*
X234842Y1213582D01*
G01X236712Y1215452D02*
X234842Y1217322D01*
G01X241523Y1353093D02*
X242783Y1351833D01*
Y1349347D01*
X241623Y1348187D01*
G01X245123Y1353093D02*
X243863Y1351833D01*
Y1349347D01*
X245023Y1348187D01*
G01Y1360099D02*
X243863Y1358939D01*
Y1356453D01*
X245123Y1355193D01*
G01X241623Y1360099D02*
X242783Y1358939D01*
Y1356453D01*
X241523Y1355193D01*
G01X245123Y1377291D02*
X243863Y1376031D01*
Y1373545D01*
X245023Y1372385D01*
G01X241523Y1377291D02*
X242783Y1376031D01*
Y1373545D01*
X241623Y1372385D01*
G01Y1384297D02*
X242783Y1383137D01*
Y1380651D01*
X241523Y1379391D01*
G01X245023Y1384297D02*
X243863Y1383137D01*
Y1380651D01*
X245123Y1379391D01*
G01X270305Y489114D02*
X268384D01*
X267743Y489755D01*
X257867D01*
X257865Y489757D01*
X256705Y488597D01*
G01X270305Y474941D02*
X268384D01*
X267743Y475582D01*
X257867D01*
X257865Y475584D01*
X256705Y474424D01*
G01X270305Y477303D02*
X268384D01*
X267743Y476662D01*
X257867D01*
X256705Y477824D01*
G01X270305Y491476D02*
X268384D01*
X267743Y490835D01*
X257867D01*
X256705Y491997D01*
G01X270305Y519075D02*
X268384D01*
X267743Y519716D01*
X257867D01*
X257865Y519718D01*
X256705Y518558D01*
G01X270305Y521437D02*
X268384D01*
X267743Y520796D01*
X257867D01*
X256705Y521958D01*
G01X270305Y533248D02*
X268384D01*
X267743Y533889D01*
X257867D01*
X257865Y533891D01*
X256705Y532731D01*
G01X270305Y535610D02*
X268384D01*
X267743Y534969D01*
X257867D01*
X256705Y536131D01*
G01X270305Y571476D02*
X268384D01*
X267743Y570835D01*
X257867D01*
X256705Y571997D01*
G01X270305Y569114D02*
X268384D01*
X267743Y569755D01*
X257867D01*
X257865Y569757D01*
X256705Y568597D01*
G01X270305Y585650D02*
X268384D01*
X267743Y585009D01*
X257867D01*
X256705Y586171D01*
G01X270305Y583288D02*
X268384D01*
X267743Y583929D01*
X257867D01*
X257865Y583931D01*
X256705Y582771D01*
G01X270305Y599823D02*
X268384D01*
X267743Y599182D01*
X257867D01*
X256705Y600344D01*
G01X270305Y597461D02*
X268384D01*
X267743Y598102D01*
X257867D01*
X257865Y598104D01*
X256705Y596944D01*
G01X270305Y611634D02*
X268384D01*
X267743Y612275D01*
X257867D01*
X257865Y612277D01*
X256705Y611117D01*
G01X270305Y613996D02*
X268384D01*
X267743Y613355D01*
X257867D01*
X256705Y614517D01*
G01X253763Y1353093D02*
X255023Y1351833D01*
Y1349347D01*
X253863Y1348187D01*
G01X257363Y1353093D02*
X256103Y1351833D01*
Y1349347D01*
X257263Y1348187D01*
G01X253863Y1360099D02*
X255023Y1358939D01*
Y1356453D01*
X253763Y1355193D01*
G01X257263Y1360099D02*
X256103Y1358939D01*
Y1356453D01*
X257363Y1355193D01*
G01X253763Y1377291D02*
X255023Y1376031D01*
Y1373545D01*
X253863Y1372385D01*
G01X257363Y1377291D02*
X256103Y1376031D01*
Y1373545D01*
X257263Y1372385D01*
G01X253863Y1384297D02*
X255023Y1383137D01*
Y1380651D01*
X253763Y1379391D01*
G01X257263Y1384297D02*
X256103Y1383137D01*
Y1380651D01*
X257363Y1379391D01*
G01X253763Y1401489D02*
X255023Y1400229D01*
Y1397743D01*
X253863Y1396583D01*
G01X257363Y1401489D02*
X256103Y1400229D01*
Y1397743D01*
X257263Y1396583D01*
G01Y1408495D02*
X256103Y1407335D01*
Y1404849D01*
X257363Y1403589D01*
G01X253863Y1408495D02*
X255023Y1407335D01*
Y1404849D01*
X253763Y1403589D01*
G01X280729Y111223D02*
X279532Y112420D01*
X277120D01*
X275823Y111123D01*
G01X280729Y114623D02*
X279606Y113500D01*
X277046D01*
X275823Y114723D01*
G01X273723Y111123D02*
X272426Y112420D01*
X267451D01*
X266803Y111772D01*
X264822D01*
G01X273723Y114723D02*
X272500Y113500D01*
X267423D01*
X266789Y114134D01*
X264822D01*
G01X271580Y107649D02*
X270431Y106500D01*
X267352D01*
X266805Y107047D01*
X264822D01*
G01X271580Y104249D02*
X270409Y105420D01*
X267486D01*
X266751Y104685D01*
X264822D01*
G01X280729Y125396D02*
X279605Y126520D01*
X277047D01*
X275823Y125296D01*
G01X280729Y128796D02*
X279533Y127600D01*
X277119D01*
X275823Y128896D01*
G01X284125Y132409D02*
X282864Y133670D01*
X267456D01*
X266818Y133032D01*
X264822D01*
G01X284125Y118235D02*
X282840Y119520D01*
X267464D01*
X266803Y118859D01*
X264822D01*
G01X273723Y128896D02*
X272427Y127600D01*
X267496D01*
X266789Y128307D01*
X264822D01*
G01X273723Y125296D02*
X272499Y126520D01*
X267378D01*
X266803Y125945D01*
X264822D01*
G01X284125Y121835D02*
X282890Y120600D01*
X267414D01*
X266793Y121221D01*
X264822D01*
G01X284125Y136009D02*
X282866Y134750D01*
X267446D01*
X266802Y135394D01*
X264822D01*
G01X270305Y467854D02*
X268383D01*
X267742Y468495D01*
X265163D01*
X264005Y467337D01*
G01X270305Y470217D02*
X268384D01*
X267742Y469575D01*
X265167D01*
X264005Y470737D01*
G01Y484910D02*
X265166Y483749D01*
X267743D01*
X268384Y484390D01*
X270305D01*
G01X264005Y481510D02*
Y481511D01*
X265163Y482669D01*
X267743D01*
X268384Y482028D01*
X270305D01*
G01Y514350D02*
X268384D01*
X267743Y513709D01*
X265167D01*
X264005Y514871D01*
G01X270305Y511988D02*
X268384D01*
X267743Y512629D01*
X265163D01*
X264005Y511471D01*
G01Y525644D02*
Y525645D01*
X265163Y526803D01*
X267743D01*
X268384Y526162D01*
X270305D01*
G01X264005Y529044D02*
X265166Y527883D01*
X267743D01*
X268384Y528524D01*
X270305D01*
G01X264005Y561510D02*
Y561511D01*
X265163Y562669D01*
X267743D01*
X268384Y562028D01*
X270305D01*
G01X264005Y564910D02*
X265166Y563749D01*
X267743D01*
X268384Y564390D01*
X270305D01*
G01Y576201D02*
X268384D01*
X267743Y576842D01*
X265163D01*
X264005Y575684D01*
G01X270305Y578563D02*
X268384D01*
X267743Y577922D01*
X265167D01*
X264005Y579084D01*
G01X270305Y590374D02*
X268384D01*
X267743Y591015D01*
X265163D01*
X264005Y589857D01*
G01X270305Y592736D02*
X268384D01*
X267743Y592095D01*
X265167D01*
X264005Y593257D01*
G01X270305Y604547D02*
X268383D01*
X267742Y605188D01*
X265163D01*
X264005Y604030D01*
G01X270305Y606910D02*
X268384D01*
X267742Y606268D01*
X265167D01*
X264005Y607430D01*
G01X269603Y1353093D02*
X268343Y1351833D01*
Y1349347D01*
X269503Y1348187D01*
G01X278243Y1353093D02*
X279503Y1351833D01*
Y1349347D01*
X278343Y1348187D01*
G01X266003Y1353093D02*
X267263Y1351833D01*
Y1349347D01*
X266103Y1348187D01*
G01X278343Y1360099D02*
X279503Y1358939D01*
Y1356453D01*
X278243Y1355193D01*
G01X266103Y1360099D02*
X267263Y1358939D01*
Y1356453D01*
X266003Y1355193D01*
G01X269503Y1360099D02*
X268343Y1358939D01*
Y1356453D01*
X269603Y1355193D01*
G01Y1377291D02*
X268343Y1376031D01*
Y1373545D01*
X269503Y1372385D01*
G01X266003Y1377291D02*
X267263Y1376031D01*
Y1373545D01*
X266103Y1372385D01*
G01X278243Y1377291D02*
X279503Y1376031D01*
Y1373545D01*
X278343Y1372385D01*
G01X266103Y1384297D02*
X267263Y1383137D01*
Y1380651D01*
X266003Y1379391D01*
G01X269503Y1384297D02*
X268343Y1383137D01*
Y1380651D01*
X269603Y1379391D01*
G01X278343Y1384297D02*
X279503Y1383137D01*
Y1380651D01*
X278243Y1379391D01*
G01Y1401489D02*
X279503Y1400229D01*
Y1397743D01*
X278343Y1396583D01*
G01X269603Y1401489D02*
X268343Y1400229D01*
Y1397743D01*
X269503Y1396583D01*
G01X266003Y1401489D02*
X267263Y1400229D01*
Y1397743D01*
X266103Y1396583D01*
G01X278343Y1408495D02*
X279503Y1407335D01*
Y1404849D01*
X278243Y1403589D01*
G01X269503Y1408495D02*
X268343Y1407335D01*
Y1404849D01*
X269603Y1403589D01*
G01X266103Y1408495D02*
X267263Y1407335D01*
Y1404849D01*
X266003Y1403589D01*
G01X291131Y121735D02*
X289976Y120580D01*
X287480D01*
X286225Y121835D01*
G01X291131Y118335D02*
X289966Y119500D01*
X287490D01*
X286225Y118235D01*
G01X291131Y132509D02*
X289970Y133670D01*
X287486D01*
X286225Y132409D01*
G01X291131Y135909D02*
X289972Y134750D01*
X287484D01*
X286225Y136009D01*
G01X288416Y467854D02*
X290339D01*
X290980Y468495D01*
X312698D01*
X313987Y467206D01*
G01X288416Y470217D02*
X290338D01*
X290980Y469575D01*
X312756D01*
X313987Y470806D01*
G01X295011Y460218D02*
X293851Y461378D01*
X290842D01*
X290232Y460768D01*
X288416D01*
G01X295011Y463618D02*
X293851Y462458D01*
X290842D01*
X290170Y463130D01*
X288416D01*
G01Y474941D02*
X290338D01*
X290979Y475582D01*
X323125D01*
X324389Y474318D01*
G01X288416Y484390D02*
X290338D01*
X290979Y483749D01*
X312757D01*
X313987Y484979D01*
G01X288416Y482028D02*
X290338D01*
X290979Y482669D01*
X312697D01*
X313987Y481379D01*
G01X288416Y477303D02*
X290338D01*
X290979Y476662D01*
X323133D01*
X324389Y477918D01*
G01X288416Y489114D02*
X290338D01*
X290979Y489755D01*
X323125D01*
X324389Y488491D01*
G01X288416Y491476D02*
X290338D01*
X290979Y490835D01*
X323133D01*
X324389Y492091D01*
G01X288416Y511988D02*
X290338D01*
X290979Y512629D01*
X312697D01*
X313987Y511339D01*
G01X288416Y519075D02*
X290338D01*
X290979Y519716D01*
X323125D01*
X324389Y518452D01*
G01X288416Y521437D02*
X290338D01*
X290979Y520796D01*
X323133D01*
X324389Y522052D01*
G01X288416Y514350D02*
X290338D01*
X290979Y513709D01*
X312757D01*
X313987Y514939D01*
G01X288416Y528524D02*
X290338D01*
X290979Y527883D01*
X312757D01*
X313987Y529113D01*
G01X288416Y533248D02*
X290338D01*
X290979Y533889D01*
X323125D01*
X324389Y532625D01*
G01X288416Y535610D02*
X290338D01*
X290979Y534969D01*
X323133D01*
X324389Y536225D01*
G01X288416Y526162D02*
X290338D01*
X290979Y526803D01*
X312697D01*
X313987Y525513D01*
G01X288416Y562028D02*
X290338D01*
X290979Y562669D01*
X312697D01*
X313987Y561379D01*
G01X288416Y571476D02*
X290338D01*
X290979Y570835D01*
X323133D01*
X324389Y572091D01*
G01X288416Y564390D02*
X290338D01*
X290979Y563749D01*
X312757D01*
X313987Y564979D01*
G01X288416Y569114D02*
X290338D01*
X290979Y569755D01*
X323125D01*
X324389Y568491D01*
G01X288416Y585650D02*
X290338D01*
X290979Y585009D01*
X323133D01*
X324389Y586265D01*
G01X288416Y576201D02*
X290338D01*
X290979Y576842D01*
X312697D01*
X313987Y575552D01*
G01X288416Y578563D02*
X290338D01*
X290979Y577922D01*
X312757D01*
X313987Y579152D01*
G01X288416Y583288D02*
X290338D01*
X290979Y583929D01*
X323125D01*
X324389Y582665D01*
G01X288416Y592736D02*
X290338D01*
X290979Y592095D01*
X312757D01*
X313987Y593325D01*
G01X288416Y597461D02*
X290338D01*
X290979Y598102D01*
X323125D01*
X324389Y596838D01*
G01X288416Y599823D02*
X290338D01*
X290979Y599182D01*
X323133D01*
X324389Y600438D01*
G01X288416Y590374D02*
X290338D01*
X290979Y591015D01*
X312697D01*
X313987Y589725D01*
G01X288416Y611634D02*
X290338D01*
X290979Y612275D01*
X323125D01*
X324389Y611011D01*
G01X288416Y613996D02*
X290338D01*
X290979Y613355D01*
X323133D01*
X324389Y614611D01*
G01X288416Y606910D02*
X290338D01*
X290980Y606268D01*
X312756D01*
X313987Y607499D01*
G01X288416Y604547D02*
X290339D01*
X290980Y605188D01*
X312698D01*
X313987Y603899D01*
G01X294685Y1123818D02*
X294684D01*
G01X294685Y1116338D02*
X294684D01*
G01X294685Y1131299D02*
X294684D01*
G01X281843Y1353093D02*
X280583Y1351833D01*
Y1349347D01*
X281743Y1348187D01*
G01X294083Y1353093D02*
X292823Y1351833D01*
Y1349347D01*
X293983Y1348187D01*
G01X290483Y1353093D02*
X291743Y1351833D01*
Y1349347D01*
X290583Y1348187D01*
G01X281743Y1360099D02*
X280583Y1358939D01*
Y1356453D01*
X281843Y1355193D01*
G01X293983Y1360099D02*
X292823Y1358939D01*
Y1356453D01*
X294083Y1355193D01*
G01X290583Y1360099D02*
X291743Y1358939D01*
Y1356453D01*
X290483Y1355193D01*
G01X294083Y1377291D02*
X292823Y1376031D01*
Y1373545D01*
X293983Y1372385D01*
G01X281843Y1377291D02*
X280583Y1376031D01*
Y1373545D01*
X281743Y1372385D01*
G01X290583Y1384297D02*
X291743Y1383137D01*
Y1380651D01*
X290483Y1379391D01*
G01X293983Y1384297D02*
X292823Y1383137D01*
Y1380651D01*
X294083Y1379391D01*
G01X290483Y1377291D02*
X291743Y1376031D01*
Y1373545D01*
X290583Y1372385D01*
G01X281743Y1384297D02*
X280583Y1383137D01*
Y1380651D01*
X281843Y1379391D01*
G01X294083Y1401489D02*
X292823Y1400229D01*
Y1397743D01*
X293983Y1396583D01*
G01X290483Y1401489D02*
X291743Y1400229D01*
Y1397743D01*
X290583Y1396583D01*
G01X281843Y1401489D02*
X280583Y1400229D01*
Y1397743D01*
X281743Y1396583D01*
G01Y1408495D02*
X280583Y1407335D01*
Y1404849D01*
X281843Y1403589D01*
G01X293983Y1408495D02*
X292823Y1407335D01*
Y1404849D01*
X294083Y1403589D01*
G01X290583Y1408495D02*
X291743Y1407335D01*
Y1404849D01*
X290483Y1403589D01*
G01X302723Y1353093D02*
X303983Y1351833D01*
Y1349347D01*
X302823Y1348187D01*
G01X306323Y1353093D02*
X305063Y1351833D01*
Y1349347D01*
X306223Y1348187D01*
G01Y1360099D02*
X305063Y1358939D01*
Y1356453D01*
X306323Y1355193D01*
G01X302823Y1360099D02*
X303983Y1358939D01*
Y1356453D01*
X302723Y1355193D01*
G01X306323Y1377291D02*
X305063Y1376031D01*
Y1373545D01*
X306223Y1372385D01*
G01X302723Y1377291D02*
X303983Y1376031D01*
Y1373545D01*
X302823Y1372385D01*
G01X306223Y1384297D02*
X305063Y1383137D01*
Y1380651D01*
X306323Y1379391D01*
G01X302823Y1384297D02*
X303983Y1383137D01*
Y1380651D01*
X302723Y1379391D01*
G01Y1401489D02*
X303983Y1400229D01*
Y1397743D01*
X302823Y1396583D01*
G01X306323Y1401489D02*
X305063Y1400229D01*
Y1397743D01*
X306223Y1396583D01*
G01X302823Y1408495D02*
X303983Y1407335D01*
Y1404849D01*
X302723Y1403589D01*
G01X306223Y1408495D02*
X305063Y1407335D01*
Y1404849D01*
X306323Y1403589D01*
G01X316087Y467206D02*
X317347Y468466D01*
X319833D01*
X320993Y467306D01*
G01X316087Y470806D02*
X317347Y469546D01*
X319833D01*
X320993Y470706D01*
G01X316087Y481379D02*
X317347Y482639D01*
X319833D01*
X320993Y481479D01*
G01X316087Y484979D02*
X317347Y483719D01*
X319833D01*
X320993Y484879D01*
G01X326489Y488491D02*
X327749Y489751D01*
X330235D01*
X331395Y488591D01*
G01X326489Y477918D02*
X327749Y476658D01*
X330235D01*
X331395Y477818D01*
G01X326489Y474318D02*
X327749Y475578D01*
X330235D01*
X331395Y474418D01*
G01X326489Y492091D02*
X327749Y490831D01*
X330235D01*
X331395Y491991D01*
G01X316087Y514939D02*
X317347Y513679D01*
X319833D01*
X320993Y514839D01*
G01X326489Y518452D02*
X327749Y519712D01*
X330235D01*
X331395Y518552D01*
G01X326489Y522052D02*
X327749Y520792D01*
X330235D01*
X331395Y521952D01*
G01X316087Y511339D02*
X317347Y512599D01*
X319833D01*
X320993Y511439D01*
G01X316087Y525513D02*
X317347Y526773D01*
X319833D01*
X320993Y525613D01*
G01X326489Y536225D02*
X327749Y534965D01*
X330235D01*
X331395Y536125D01*
G01X316087Y529113D02*
X317347Y527853D01*
X319833D01*
X320993Y529013D01*
G01X326489Y532625D02*
X327749Y533885D01*
X330235D01*
X331395Y532725D01*
G01X316087Y564979D02*
X317347Y563719D01*
X319833D01*
X320993Y564879D01*
G01X326489Y568491D02*
X327749Y569751D01*
X330235D01*
X331395Y568591D01*
G01X316087Y561379D02*
X317347Y562639D01*
X319833D01*
X320993Y561479D01*
G01X326489Y572091D02*
X327749Y570831D01*
X330235D01*
X331395Y571991D01*
G01X316087Y575552D02*
X317347Y576812D01*
X319833D01*
X320993Y575652D01*
G01X326489Y586265D02*
X327749Y585005D01*
X330235D01*
X331395Y586165D01*
G01X316087Y579152D02*
X317347Y577892D01*
X319833D01*
X320993Y579052D01*
G01X326489Y582665D02*
X327749Y583925D01*
X330235D01*
X331395Y582765D01*
G01X316087Y603899D02*
X317347Y605159D01*
X319833D01*
X320993Y603999D01*
G01X326489Y600438D02*
X327749Y599178D01*
X330235D01*
X331395Y600338D01*
G01X316087Y593325D02*
X317347Y592065D01*
X319833D01*
X320993Y593225D01*
G01X316087Y589725D02*
X317347Y590985D01*
X319833D01*
X320993Y589825D01*
G01X326489Y596838D02*
X327749Y598098D01*
X330235D01*
X331395Y596938D01*
G01X316087Y607499D02*
X317347Y606239D01*
X319833D01*
X320993Y607399D01*
G01X326489Y611011D02*
X327749Y612271D01*
X330235D01*
X331395Y611111D01*
G01X326489Y614611D02*
X327749Y613351D01*
X330235D01*
X331395Y614511D01*
G01X327203Y1353093D02*
X328463Y1351833D01*
Y1349347D01*
X327303Y1348187D01*
G01X314963Y1353093D02*
X316223Y1351833D01*
Y1349347D01*
X315063Y1348187D01*
G01X318563Y1353093D02*
X317303Y1351833D01*
Y1349347D01*
X318463Y1348187D01*
G01X327303Y1360099D02*
X328463Y1358939D01*
Y1356453D01*
X327203Y1355193D01*
G01X315063Y1360099D02*
X316223Y1358939D01*
Y1356453D01*
X314963Y1355193D01*
G01X318463Y1360099D02*
X317303Y1358939D01*
Y1356453D01*
X318563Y1355193D01*
G01X314963Y1377291D02*
X316223Y1376031D01*
Y1373545D01*
X315063Y1372385D01*
G01X318463Y1384297D02*
X317303Y1383137D01*
Y1380651D01*
X318563Y1379391D01*
G01X315063Y1384297D02*
X316223Y1383137D01*
Y1380651D01*
X314963Y1379391D01*
G01X327203Y1377291D02*
X328463Y1376031D01*
Y1373545D01*
X327303Y1372385D01*
G01X318563Y1377291D02*
X317303Y1376031D01*
Y1373545D01*
X318463Y1372385D01*
G01X327303Y1384297D02*
X328463Y1383137D01*
Y1380651D01*
X327203Y1379391D01*
G01Y1401489D02*
X328463Y1400229D01*
Y1397743D01*
X327303Y1396583D01*
G01X314963Y1401489D02*
X316223Y1400229D01*
Y1397743D01*
X315063Y1396583D01*
G01X318563Y1401489D02*
X317303Y1400229D01*
Y1397743D01*
X318463Y1396583D01*
G01X327303Y1408495D02*
X328463Y1407335D01*
Y1404849D01*
X327203Y1403589D01*
G01X318463Y1408495D02*
X317303Y1407335D01*
Y1404849D01*
X318563Y1403589D01*
G01X315063Y1408495D02*
X316223Y1407335D01*
Y1404849D01*
X314963Y1403589D01*
G01X349074Y111772D02*
X347181D01*
X346533Y112420D01*
X343939D01*
X342774Y111255D01*
G01X349074Y114134D02*
Y114135D01*
X347188D01*
X346553Y113500D01*
X343929D01*
X342774Y114655D01*
G01X349074Y118859D02*
X347194D01*
X346553Y119500D01*
X336632D01*
X335474Y118342D01*
G01X349074Y133032D02*
X347194D01*
X346553Y133673D01*
X336632D01*
X335474Y132515D01*
G01X349074Y125945D02*
X347181D01*
X346556Y126570D01*
X343916D01*
X342774Y125428D01*
G01X349074Y121221D02*
X347174D01*
X346533Y120580D01*
X336636D01*
X335474Y121742D01*
G01X349074Y128307D02*
X347187D01*
X346530Y127650D01*
X343952D01*
X342774Y128828D01*
G01X349074Y135394D02*
X347174D01*
X346533Y134753D01*
X336636D01*
X335474Y135915D01*
G01X339443Y1353093D02*
X340703Y1351833D01*
Y1349347D01*
X339543Y1348187D01*
G01X343043Y1353093D02*
X341783Y1351833D01*
Y1349347D01*
X342943Y1348187D01*
G01X330803Y1353093D02*
X329543Y1351833D01*
Y1349347D01*
X330703Y1348187D01*
G01Y1360099D02*
X329543Y1358939D01*
Y1356453D01*
X330803Y1355193D01*
G01X342943Y1360099D02*
X341783Y1358939D01*
Y1356453D01*
X343043Y1355193D01*
G01X339543Y1360099D02*
X340703Y1358939D01*
Y1356453D01*
X339443Y1355193D01*
G01Y1377291D02*
X340703Y1376031D01*
Y1373545D01*
X339543Y1372385D01*
G01X343043Y1377291D02*
X341783Y1376031D01*
Y1373545D01*
X342943Y1372385D01*
G01X330803Y1377291D02*
X329543Y1376031D01*
Y1373545D01*
X330703Y1372385D01*
G01X342943Y1384297D02*
X341783Y1383137D01*
Y1380651D01*
X343043Y1379391D01*
G01X339543Y1384297D02*
X340703Y1383137D01*
Y1380651D01*
X339443Y1379391D01*
G01X330703Y1384297D02*
X329543Y1383137D01*
Y1380651D01*
X330803Y1379391D01*
G01Y1401489D02*
X329543Y1400229D01*
Y1397743D01*
X330703Y1396583D01*
G01X339443Y1401489D02*
X340703Y1400229D01*
Y1397743D01*
X339543Y1396583D01*
G01X343043Y1401489D02*
X341783Y1400229D01*
Y1397743D01*
X342943Y1396583D01*
G01X330703Y1408495D02*
X329543Y1407335D01*
Y1404849D01*
X330803Y1403589D01*
G01X342943Y1408495D02*
X341783Y1407335D01*
Y1404849D01*
X343043Y1403589D01*
G01X339543Y1408495D02*
X340703Y1407335D01*
Y1404849D01*
X339443Y1403589D01*
G01X351683Y1353093D02*
X352943Y1351833D01*
Y1349347D01*
X351783Y1348187D01*
G01X355283Y1353093D02*
X354023Y1351833D01*
Y1349347D01*
X355183Y1348187D01*
G01Y1360099D02*
X354023Y1358939D01*
Y1356453D01*
X355283Y1355193D01*
G01X351783Y1360099D02*
X352943Y1358939D01*
Y1356453D01*
X351683Y1355193D01*
G01Y1377291D02*
X352943Y1376031D01*
Y1373545D01*
X351783Y1372385D01*
G01X355283Y1377291D02*
X354023Y1376031D01*
Y1373545D01*
X355183Y1372385D01*
G01Y1384297D02*
X354023Y1383137D01*
Y1380651D01*
X355283Y1379391D01*
G01X351783Y1384297D02*
X352943Y1383137D01*
Y1380651D01*
X351683Y1379391D01*
G01Y1401489D02*
X352943Y1400229D01*
Y1397743D01*
X351783Y1396583D01*
G01X355283Y1401489D02*
X354023Y1400229D01*
Y1397743D01*
X355183Y1396583D01*
G01X351783Y1408495D02*
X352943Y1407335D01*
Y1404849D01*
X351683Y1403589D01*
G01X355183Y1408495D02*
X354023Y1407335D01*
Y1404849D01*
X355283Y1403589D01*
G01X376085Y114723D02*
X374862Y113500D01*
X369785D01*
X369151Y114134D01*
X367184D01*
G01X376085Y111123D02*
X374788Y112420D01*
X369813D01*
X369165Y111772D01*
X367184D01*
G01X373942Y104249D02*
X372771Y105420D01*
X369848D01*
X369113Y104685D01*
X367184D01*
G01X373942Y107649D02*
X372793Y106500D01*
X369714D01*
X369167Y107047D01*
X367184D01*
G01X386487Y132409D02*
X385226Y133670D01*
X369818D01*
X369180Y133032D01*
X367184D01*
G01X376085Y128896D02*
X374789Y127600D01*
X369858D01*
X369151Y128307D01*
X367184D01*
G01X386487Y118235D02*
X385202Y119520D01*
X369826D01*
X369165Y118859D01*
X367184D01*
G01X386487Y121835D02*
X385252Y120600D01*
X369776D01*
X369155Y121221D01*
X367184D01*
G01X376085Y125296D02*
X374861Y126520D01*
X369740D01*
X369165Y125945D01*
X367184D01*
G01X386487Y136009D02*
X385228Y134750D01*
X369808D01*
X369164Y135394D01*
X367184D01*
G01X363923Y1353093D02*
X365183Y1351833D01*
Y1349347D01*
X364023Y1348187D01*
G01X367523Y1353093D02*
X366263Y1351833D01*
Y1349347D01*
X367423Y1348187D01*
G01Y1360099D02*
X366263Y1358939D01*
Y1356453D01*
X367523Y1355193D01*
G01X364023Y1360099D02*
X365183Y1358939D01*
Y1356453D01*
X363923Y1355193D01*
G01Y1377291D02*
X365183Y1376031D01*
Y1373545D01*
X364023Y1372385D01*
G01X367423Y1384297D02*
X366263Y1383137D01*
Y1380651D01*
X367523Y1379391D01*
G01X364023Y1384297D02*
X365183Y1383137D01*
Y1380651D01*
X363923Y1379391D01*
G01X367523Y1377291D02*
X366263Y1376031D01*
Y1373545D01*
X367423Y1372385D01*
G01X363923Y1401489D02*
X365183Y1400229D01*
Y1397743D01*
X364023Y1396583D01*
G01X367523Y1401489D02*
X366263Y1400229D01*
Y1397743D01*
X367423Y1396583D01*
G01X364023Y1408495D02*
X365183Y1407335D01*
Y1404849D01*
X363923Y1403589D01*
G01X367423Y1408495D02*
X366263Y1407335D01*
Y1404849D01*
X367523Y1403589D01*
G01X383091Y111223D02*
X381894Y112420D01*
X379482D01*
X378185Y111123D01*
G01X383091Y114623D02*
X381968Y113500D01*
X379408D01*
X378185Y114723D01*
G01X393493Y118335D02*
X392328Y119500D01*
X389852D01*
X388587Y118235D01*
G01X383091Y125396D02*
X381967Y126520D01*
X379409D01*
X378185Y125296D01*
G01X383091Y128796D02*
X381895Y127600D01*
X379481D01*
X378185Y128896D01*
G01X393493Y132509D02*
X392332Y133670D01*
X389848D01*
X388587Y132409D01*
G01X393493Y121735D02*
X392338Y120580D01*
X389842D01*
X388587Y121835D01*
G01X393493Y135909D02*
X392334Y134750D01*
X389846D01*
X388587Y136009D01*
G01X397473Y780320D02*
Y781627D01*
X397050Y782050D01*
Y784450D01*
X393870Y787630D01*
X392171D01*
X391230Y788571D01*
Y791540D01*
X392415Y792725D01*
G01X395505Y780320D02*
Y781604D01*
X395970Y782069D01*
Y784002D01*
X393422Y786550D01*
X391723D01*
X390150Y788123D01*
Y791590D01*
X389015Y792725D01*
G01X416886Y342437D02*
X415207D01*
X414945Y342175D01*
X411248D01*
X409715Y340642D01*
X396118D01*
X396068Y340592D01*
X394883Y341777D01*
G01X416886Y340862D02*
X415202D01*
X414969Y341095D01*
X411696D01*
X410163Y339562D01*
X396068D01*
X394883Y338377D01*
G01X405498Y1524334D02*
Y1523029D01*
X407697Y1517717D01*
Y1514144D01*
X414648Y1507193D01*
Y1505826D01*
X411487Y1502665D01*
Y1501274D01*
G01X393620Y1516448D02*
X395667D01*
X397266Y1518047D01*
G01X400903Y1516556D02*
X399175D01*
X397266Y1514647D01*
G01X403059Y1534417D02*
Y1533244D01*
X402590Y1532775D01*
Y1531284D01*
X401320Y1530014D01*
X398282Y1528755D01*
X397885Y1528358D01*
Y1524424D01*
X397884Y1524423D01*
Y1524411D01*
X400903Y1521392D01*
Y1519706D01*
G01X401090Y1534417D02*
Y1533323D01*
X401510Y1532903D01*
Y1531732D01*
X400708Y1530930D01*
X397670Y1529671D01*
X396805Y1528806D01*
Y1524423D01*
X393620Y1521238D01*
Y1519598D01*
G01X414025Y1509344D02*
X408777Y1514592D01*
Y1517932D01*
X406578Y1523244D01*
Y1532908D01*
X406996Y1533326D01*
Y1534417D01*
G01X405498Y1524334D02*
Y1532853D01*
X405028Y1533323D01*
Y1534417D01*
G01X423551Y312686D02*
X424820Y311417D01*
Y308639D01*
X423651Y307470D01*
G01X419277Y312686D02*
X418000Y311409D01*
Y305647D01*
X419177Y304470D01*
G01X415677Y312686D02*
X416920Y311443D01*
Y305613D01*
X415777Y304470D01*
G01X415677Y315836D02*
X416912Y317071D01*
Y319339D01*
X420061Y322488D01*
Y324984D01*
X419839Y325206D01*
Y326886D01*
G01X419277Y315836D02*
X417992Y317121D01*
Y318891D01*
X421141Y322040D01*
Y324930D01*
X421413Y325202D01*
Y326886D01*
G01X423551Y315836D02*
X424820Y317105D01*
Y324950D01*
X424563Y325207D01*
Y326886D01*
G01X413934Y1477101D02*
X415094Y1475941D01*
Y1474221D01*
X416909Y1469837D01*
X429730Y1457016D01*
G01X951989Y899890D02*
X950529Y901350D01*
Y909829D01*
X951700Y911000D01*
Y921100D01*
X948500Y924300D01*
Y929200D01*
X946000Y931700D01*
X886100D01*
X884100Y929700D01*
X867100D01*
X863800Y933000D01*
Y938200D01*
X858500Y943500D01*
Y958100D01*
X847100Y969500D01*
Y1008400D01*
X848600Y1009900D01*
Y1013600D01*
X843900Y1018300D01*
Y1091910D01*
X835400Y1112431D01*
Y1222209D01*
X844600Y1244420D01*
Y1265846D01*
X812178Y1344122D01*
X736828Y1419472D01*
X688525Y1439480D01*
X487705D01*
X487355Y1439830D01*
X485765D01*
X485415Y1439480D01*
X483825D01*
X483475Y1439830D01*
X481885D01*
X481535Y1439480D01*
X479945D01*
X479595Y1439830D01*
X478005D01*
X477655Y1439480D01*
X476065D01*
X475715Y1439830D01*
X474125D01*
X473775Y1439480D01*
X472185D01*
X471835Y1439830D01*
X470245D01*
X469895Y1439480D01*
X468305D01*
X467955Y1439830D01*
X466365D01*
X466015Y1439480D01*
X464425D01*
X464075Y1439830D01*
X462485D01*
X462135Y1439480D01*
X460545D01*
X460195Y1439830D01*
X458605D01*
X458255Y1439480D01*
X448794D01*
X420388Y1467886D01*
G01D02*
X417825Y1470449D01*
X416174Y1474436D01*
Y1475941D01*
X417334Y1477101D01*
G01X418839Y1498027D02*
X417111D01*
X415202Y1496118D01*
G01X411487Y1498124D02*
X413808D01*
X415202Y1499518D01*
G01X414025Y1509344D02*
X415728Y1507641D01*
Y1505873D01*
X418839Y1502762D01*
Y1501177D01*
G01X417129Y1523296D02*
X415959Y1524466D01*
Y1530033D01*
X414761Y1531231D01*
X413497D01*
X412483Y1532245D01*
Y1532825D01*
X412902Y1533244D01*
Y1534417D01*
G01X417129Y1523296D02*
X416000Y1522167D01*
Y1518039D01*
X417153Y1516886D01*
G01X413776Y1523296D02*
X414879Y1524399D01*
Y1529585D01*
X414313Y1530151D01*
X413049D01*
X411403Y1531797D01*
Y1532853D01*
X410933Y1533323D01*
Y1534417D01*
G01X413776Y1523296D02*
X414920Y1522152D01*
Y1518053D01*
X413753Y1516886D01*
G01X431425Y312686D02*
X432720Y311391D01*
Y305665D01*
X431525Y304470D01*
G01X435025Y312686D02*
X433800Y311461D01*
Y305595D01*
X434925Y304470D01*
G01X427151Y312686D02*
X425900Y311435D01*
Y308621D01*
X427051Y307470D01*
G01X427151Y315836D02*
X425900Y317087D01*
Y324964D01*
X426138Y325202D01*
Y326886D01*
G01X431425Y315836D02*
X432720Y317131D01*
Y324924D01*
X432437Y325207D01*
Y326886D01*
G01X435025Y315836D02*
X433800Y317061D01*
Y324990D01*
X434012Y325202D01*
Y326886D01*
G01X452584Y324685D02*
X451349Y325920D01*
X447652D01*
X443511Y330061D01*
X442016D01*
X441794Y329839D01*
X440114D01*
G01X452584Y328285D02*
X451299Y327000D01*
X448100D01*
X443959Y331141D01*
X442070D01*
X441798Y331413D01*
X440114D01*
G01X452584Y332559D02*
X451299Y333844D01*
X446403D01*
X444008Y334836D01*
X442066D01*
X441793Y334563D01*
X440114D01*
G01X452584Y336159D02*
X451349Y334924D01*
X446618D01*
X444223Y335916D01*
X442020D01*
X441798Y336138D01*
X440114D01*
G01X452584Y340433D02*
X451317Y341700D01*
X446724D01*
X445359Y341135D01*
X442066D01*
X441793Y340862D01*
X440114D01*
G01X452584Y344033D02*
X451331Y342780D01*
X446509D01*
X445144Y342215D01*
X442020D01*
X441798Y342437D01*
X440114D01*
G01X452584Y348307D02*
X451299Y349592D01*
X448892D01*
X445159Y345859D01*
X442066D01*
X441794Y345587D01*
X440114D01*
G01X452584Y351907D02*
X451349Y350672D01*
X448444D01*
X444711Y346939D01*
X442020D01*
X441798Y347161D01*
X440114D01*
G01X435024Y361943D02*
X433789Y360708D01*
Y352016D01*
X434012Y351793D01*
Y350114D01*
G01X431424Y361943D02*
X432709Y360658D01*
Y352070D01*
X432437Y351798D01*
Y350114D01*
G01X431524Y370309D02*
X432659Y369174D01*
Y366328D01*
X431424Y365093D01*
G01X435024D02*
X433739Y366378D01*
Y369124D01*
X434924Y370309D01*
G01X440302Y1353093D02*
X441562Y1351833D01*
Y1349347D01*
X440402Y1348187D01*
G01Y1360099D02*
X441562Y1358939D01*
Y1356453D01*
X440302Y1355193D01*
G01Y1377291D02*
X441562Y1376031D01*
Y1373545D01*
X440402Y1372385D01*
G01Y1384297D02*
X441562Y1383137D01*
Y1380651D01*
X440302Y1379391D01*
G01X429730Y1457016D02*
X448346Y1438400D01*
X688310D01*
X736216Y1418556D01*
X811262Y1343510D01*
X843520Y1265631D01*
Y1244635D01*
X834320Y1222424D01*
Y1112216D01*
X842820Y1091695D01*
Y1072635D01*
X842280Y1072095D01*
Y1070505D01*
X842820Y1069965D01*
Y1068375D01*
X842280Y1067835D01*
Y1066245D01*
X842820Y1065705D01*
Y1064115D01*
X842280Y1063575D01*
Y1061985D01*
X842820Y1061445D01*
Y1017852D01*
X847520Y1013152D01*
Y1010348D01*
X846020Y1008848D01*
Y969052D01*
X857420Y957652D01*
Y943052D01*
X862720Y937752D01*
Y932552D01*
X866652Y928620D01*
X884548D01*
X886548Y930620D01*
X895205D01*
X895605Y930220D01*
X897195D01*
X897595Y930620D01*
X899185D01*
X899605Y930200D01*
X901195D01*
X901615Y930620D01*
X903205D01*
X903745Y930080D01*
X905335D01*
X905875Y930620D01*
X945552D01*
X947420Y928752D01*
Y923852D01*
X950620Y920652D01*
Y911448D01*
X949449Y910277D01*
Y901350D01*
X947989Y899890D01*
G01X455734Y328285D02*
X457019Y327000D01*
X459765D01*
X460950Y328185D01*
G01X455734Y324685D02*
X456969Y325920D01*
X459815D01*
X460950Y324785D01*
G01X455734Y332559D02*
X456995Y333820D01*
X462789D01*
X463950Y332659D01*
G01X455734Y336159D02*
X456993Y334900D01*
X462791D01*
X463950Y336059D01*
G01X455734Y344033D02*
X456967Y342800D01*
X459817D01*
X460950Y343933D01*
G01X455734Y340433D02*
X457021Y341720D01*
X459763D01*
X460950Y340533D01*
G01X455734Y351907D02*
X457041Y350600D01*
X462743D01*
X463950Y351807D01*
G01X455734Y348307D02*
X456947Y349520D01*
X462837D01*
X463950Y348407D01*
G01X452542Y1353093D02*
X453802Y1351833D01*
Y1349347D01*
X452642Y1348187D01*
G01X456142Y1353093D02*
X454882Y1351833D01*
Y1349347D01*
X456042Y1348187D01*
G01X443902Y1353093D02*
X442642Y1351833D01*
Y1349347D01*
X443802Y1348187D01*
G01X456042Y1360099D02*
X454882Y1358939D01*
Y1356453D01*
X456142Y1355193D01*
G01X452642Y1360099D02*
X453802Y1358939D01*
Y1356453D01*
X452542Y1355193D01*
G01X443802Y1360099D02*
X442642Y1358939D01*
Y1356453D01*
X443902Y1355193D01*
G01Y1377291D02*
X442642Y1376031D01*
Y1373545D01*
X443802Y1372385D01*
G01X452542Y1377291D02*
X453802Y1376031D01*
Y1373545D01*
X452642Y1372385D01*
G01X456142Y1377291D02*
X454882Y1376031D01*
Y1373545D01*
X456042Y1372385D01*
G01X452642Y1384297D02*
X453802Y1383137D01*
Y1380651D01*
X452542Y1379391D01*
G01X456042Y1384297D02*
X454882Y1383137D01*
Y1380651D01*
X456142Y1379391D01*
G01X443802Y1384297D02*
X442642Y1383137D01*
Y1380651D01*
X443902Y1379391D01*
G01X452542Y1401489D02*
X453802Y1400229D01*
Y1397743D01*
X452642Y1396583D01*
G01X456142Y1401489D02*
X454882Y1400229D01*
Y1397743D01*
X456042Y1396583D01*
G01X452642Y1408495D02*
X453802Y1407335D01*
Y1404849D01*
X452542Y1403589D01*
G01X456042Y1408495D02*
X454882Y1407335D01*
Y1404849D01*
X456142Y1403589D01*
G01X468382Y1353093D02*
X467122Y1351833D01*
Y1349347D01*
X468282Y1348187D01*
G01X464782Y1353093D02*
X466042Y1351833D01*
Y1349347D01*
X464882Y1348187D01*
G01X468282Y1360099D02*
X467122Y1358939D01*
Y1356453D01*
X468382Y1355193D01*
G01X464882Y1360099D02*
X466042Y1358939D01*
Y1356453D01*
X464782Y1355193D01*
G01Y1377291D02*
X466042Y1376031D01*
Y1373545D01*
X464882Y1372385D01*
G01X468382Y1377291D02*
X467122Y1376031D01*
Y1373545D01*
X468282Y1372385D01*
G01X464882Y1384297D02*
X466042Y1383137D01*
Y1380651D01*
X464782Y1379391D01*
G01X468282Y1384297D02*
X467122Y1383137D01*
Y1380651D01*
X468382Y1379391D01*
G01Y1401489D02*
X467122Y1400229D01*
Y1397743D01*
X468282Y1396583D01*
G01X464782Y1401489D02*
X466042Y1400229D01*
Y1397743D01*
X464882Y1396583D01*
G01Y1408495D02*
X466042Y1407335D01*
Y1404849D01*
X464782Y1403589D01*
G01X468282Y1408495D02*
X467122Y1407335D01*
Y1404849D01*
X468382Y1403589D01*
G01X499075Y118859D02*
X497195D01*
X496554Y119500D01*
X486633D01*
X485475Y118342D01*
G01X499075Y121221D02*
X497175D01*
X496534Y120580D01*
X486637D01*
X485475Y121742D01*
G01X499075Y133032D02*
X497195D01*
X496554Y133673D01*
X486633D01*
X485475Y132515D01*
G01X499075Y135394D02*
X497175D01*
X496534Y134753D01*
X486637D01*
X485475Y135915D01*
G01X486837Y701306D02*
X488051Y702520D01*
X504078D01*
X509673Y696927D01*
X511228D01*
X511697Y696458D01*
G01X486837Y704706D02*
X487943Y703600D01*
X504526D01*
X510121Y698007D01*
X511277D01*
X511697Y698427D01*
G01X489262Y1353093D02*
X490522Y1351833D01*
Y1349347D01*
X489362Y1348187D01*
G01X480622Y1353093D02*
X479362Y1351833D01*
Y1349347D01*
X480522Y1348187D01*
G01X477022Y1353093D02*
X478282Y1351833D01*
Y1349347D01*
X477122Y1348187D01*
G01X480522Y1360099D02*
X479362Y1358939D01*
Y1356453D01*
X480622Y1355193D01*
G01X477122Y1360099D02*
X478282Y1358939D01*
Y1356453D01*
X477022Y1355193D01*
G01X489362Y1360099D02*
X490522Y1358939D01*
Y1356453D01*
X489262Y1355193D01*
G01X477022Y1377291D02*
X478282Y1376031D01*
Y1373545D01*
X477122Y1372385D01*
G01X480622Y1377291D02*
X479362Y1376031D01*
Y1373545D01*
X480522Y1372385D01*
G01X489262Y1377291D02*
X490522Y1376031D01*
Y1373545D01*
X489362Y1372385D01*
G01Y1384297D02*
X490522Y1383137D01*
Y1380651D01*
X489262Y1379391D01*
G01X480522Y1384297D02*
X479362Y1383137D01*
Y1380651D01*
X480622Y1379391D01*
G01X477122Y1384297D02*
X478282Y1383137D01*
Y1380651D01*
X477022Y1379391D01*
G01X480622Y1401489D02*
X479362Y1400229D01*
Y1397743D01*
X480522Y1396583D01*
G01X477022Y1401489D02*
X478282Y1400229D01*
Y1397743D01*
X477122Y1396583D01*
G01X489262Y1401489D02*
X490522Y1400229D01*
Y1397743D01*
X489362Y1396583D01*
G01X477122Y1408495D02*
X478282Y1407335D01*
Y1404849D01*
X477022Y1403589D01*
G01X480522Y1408495D02*
X479362Y1407335D01*
Y1404849D01*
X480622Y1403589D01*
G01X489362Y1408495D02*
X490522Y1407335D01*
Y1404849D01*
X489262Y1403589D01*
G01X499075Y114134D02*
Y114135D01*
X497189D01*
X496554Y113500D01*
X493930D01*
X492775Y114655D01*
G01X499075Y111772D02*
X497182D01*
X496534Y112420D01*
X493940D01*
X492775Y111255D01*
G01X499075Y128307D02*
X497188D01*
X496531Y127650D01*
X493953D01*
X492775Y128828D01*
G01X499075Y125945D02*
X497182D01*
X496557Y126570D01*
X493917D01*
X492775Y125428D01*
G01X492862Y1353093D02*
X491602Y1351833D01*
Y1349347D01*
X492762Y1348187D01*
G01X501502Y1353093D02*
X502762Y1351833D01*
Y1349347D01*
X501602Y1348187D01*
G01X505102Y1353093D02*
X503842Y1351833D01*
Y1349347D01*
X505002Y1348187D01*
G01X501602Y1360099D02*
X502762Y1358939D01*
Y1356453D01*
X501502Y1355193D01*
G01X505002Y1360099D02*
X503842Y1358939D01*
Y1356453D01*
X505102Y1355193D01*
G01X492762Y1360099D02*
X491602Y1358939D01*
Y1356453D01*
X492862Y1355193D01*
G01X505102Y1377291D02*
X503842Y1376031D01*
Y1373545D01*
X505002Y1372385D01*
G01X492862Y1377291D02*
X491602Y1376031D01*
Y1373545D01*
X492762Y1372385D01*
G01X501502Y1377291D02*
X502762Y1376031D01*
Y1373545D01*
X501602Y1372385D01*
G01X492762Y1384297D02*
X491602Y1383137D01*
Y1380651D01*
X492862Y1379391D01*
G01X505002Y1384297D02*
X503842Y1383137D01*
Y1380651D01*
X505102Y1379391D01*
G01X501602Y1384297D02*
X502762Y1383137D01*
Y1380651D01*
X501502Y1379391D01*
G01X505102Y1401489D02*
X503842Y1400229D01*
Y1397743D01*
X505002Y1396583D01*
G01X492862Y1401489D02*
X491602Y1400229D01*
Y1397743D01*
X492762Y1396583D01*
G01X501502Y1401489D02*
X502762Y1400229D01*
Y1397743D01*
X501602Y1396583D01*
G01X505002Y1408495D02*
X503842Y1407335D01*
Y1404849D01*
X505102Y1403589D01*
G01X501602Y1408495D02*
X502762Y1407335D01*
Y1404849D01*
X501502Y1403589D01*
G01X492762Y1408495D02*
X491602Y1407335D01*
Y1404849D01*
X492862Y1403589D01*
G01X526086Y111123D02*
X524789Y112420D01*
X519814D01*
X519166Y111772D01*
X517185D01*
G01X526086Y114723D02*
X524863Y113500D01*
X519786D01*
X519152Y114134D01*
X517185D01*
G01X523943Y107649D02*
X522774Y106480D01*
X519735D01*
X519168Y107047D01*
X517185D01*
G01X523943Y104249D02*
X522792Y105400D01*
X519829D01*
X519114Y104685D01*
X517185D01*
G01X536488Y132409D02*
X535227Y133670D01*
X519819D01*
X519181Y133032D01*
X517185D01*
G01X536488Y121835D02*
X535253Y120600D01*
X519777D01*
X519156Y121221D01*
X517185D01*
G01X536488Y118235D02*
X535203Y119520D01*
X519827D01*
X519166Y118859D01*
X517185D01*
G01X526086Y125296D02*
X524862Y126520D01*
X519741D01*
X519166Y125945D01*
X517185D01*
G01X526086Y128896D02*
X524790Y127600D01*
X519859D01*
X519152Y128307D01*
X517185D01*
G01X536488Y136009D02*
X535229Y134750D01*
X519809D01*
X519165Y135394D01*
X517185D01*
G01X521540Y710238D02*
X521959Y710657D01*
Y720714D01*
X520720Y721953D01*
Y723986D01*
X519285Y725421D01*
G01X515285D02*
X513821Y723957D01*
Y722379D01*
X519102Y717098D01*
Y710707D01*
X519571Y710238D01*
G01X517603D02*
X518022Y710657D01*
Y716650D01*
X512741Y721931D01*
Y723965D01*
X511285Y725421D01*
G01X523285D02*
X521800Y723936D01*
Y722401D01*
X523039Y721162D01*
Y710707D01*
X523508Y710238D01*
G01X521131Y741071D02*
X519946Y739886D01*
Y736654D01*
X521800Y734800D01*
Y730056D01*
X523285Y728571D01*
G01X519285D02*
X520720Y730006D01*
Y734352D01*
X518866Y736206D01*
Y739936D01*
X517731Y741071D01*
G01X511724Y741035D02*
X510510Y739821D01*
Y736091D01*
X513800Y732801D01*
Y730056D01*
X515285Y728571D01*
G01X511285D02*
X512720Y730006D01*
Y732353D01*
X509430Y735643D01*
Y739929D01*
X508324Y741035D01*
G01X517342Y1353093D02*
X516082Y1351833D01*
Y1349347D01*
X517242Y1348187D01*
G01X513742Y1353093D02*
X515002Y1351833D01*
Y1349347D01*
X513842Y1348187D01*
G01Y1360099D02*
X515002Y1358939D01*
Y1356453D01*
X513742Y1355193D01*
G01X517242Y1360099D02*
X516082Y1358939D01*
Y1356453D01*
X517342Y1355193D01*
G01Y1377291D02*
X516082Y1376031D01*
Y1373545D01*
X517242Y1372385D01*
G01X513742Y1377291D02*
X515002Y1376031D01*
Y1373545D01*
X513842Y1372385D01*
G01X517242Y1384297D02*
X516082Y1383137D01*
Y1380651D01*
X517342Y1379391D01*
G01X513842Y1384297D02*
X515002Y1383137D01*
Y1380651D01*
X513742Y1379391D01*
G01X517342Y1401489D02*
X516082Y1400229D01*
Y1397743D01*
X517242Y1396583D01*
G01X513742Y1401489D02*
X515002Y1400229D01*
Y1397743D01*
X513842Y1396583D01*
G01X517242Y1408495D02*
X516082Y1407335D01*
Y1404849D01*
X517342Y1403589D01*
G01X513842Y1408495D02*
X515002Y1407335D01*
Y1404849D01*
X513742Y1403589D01*
G01X533092Y114623D02*
X531969Y113500D01*
X529409D01*
X528186Y114723D01*
G01X533092Y111223D02*
X531895Y112420D01*
X529483D01*
X528186Y111123D01*
G01X543494Y121735D02*
X542339Y120580D01*
X539843D01*
X538588Y121835D01*
G01X533092Y128796D02*
X531896Y127600D01*
X529482D01*
X528186Y128896D01*
G01X543494Y132509D02*
X542333Y133670D01*
X539849D01*
X538588Y132409D01*
G01X543494Y118335D02*
X542329Y119500D01*
X539853D01*
X538588Y118235D01*
G01X533092Y125396D02*
X531968Y126520D01*
X529410D01*
X528186Y125296D01*
G01X543494Y135909D02*
X542335Y134750D01*
X539847D01*
X538588Y136009D01*
G01X537964Y670078D02*
X536480Y668594D01*
Y662740D01*
X537664Y661556D01*
G01X533964Y670078D02*
X535400Y668642D01*
Y662692D01*
X534264Y661556D01*
G01X529964Y670078D02*
X528500Y668614D01*
Y665220D01*
X529664Y664056D01*
G01X525964Y670078D02*
X527420Y668622D01*
Y665212D01*
X526264Y664056D01*
G01X527445Y688584D02*
X527920Y688109D01*
Y683551D01*
X527400Y683031D01*
Y674664D01*
X525964Y673228D01*
G01X529414Y688584D02*
X529000Y688170D01*
Y683103D01*
X528480Y682583D01*
Y674712D01*
X529964Y673228D01*
G01X531382Y688584D02*
X531851Y688115D01*
Y681728D01*
X535400Y678179D01*
Y674664D01*
X533964Y673228D01*
G01X537964D02*
X536480Y674712D01*
Y678627D01*
X532931Y682176D01*
Y688164D01*
X533351Y688584D01*
G01Y690553D02*
X533820Y691022D01*
X533870Y690972D01*
X540500D01*
X545528Y685944D01*
X548463D01*
X549898Y684509D01*
G01X533351Y692521D02*
X533820Y692052D01*
X540948D01*
X545976Y687024D01*
X548413D01*
X549898Y688509D01*
G01Y692509D02*
X548463Y693944D01*
X547128D01*
X546163Y694909D01*
X533870D01*
X533820Y694959D01*
X533351Y694490D01*
G01X549898Y696509D02*
X548413Y695024D01*
X547576D01*
X546611Y695989D01*
X533820D01*
X533351Y696458D01*
G01X549898Y704509D02*
X548389Y703000D01*
X542257D01*
X539257Y700000D01*
X533746D01*
X533351Y700395D01*
G01Y698427D02*
X533844Y698920D01*
X539705D01*
X542705Y701920D01*
X548487D01*
X549898Y700509D01*
G01X533351Y708269D02*
X533802Y708720D01*
X536503D01*
X545727Y717944D01*
X548463D01*
X549898Y716509D01*
G01X533351Y710238D02*
X533789Y709800D01*
X536055D01*
X545279Y719024D01*
X548413D01*
X549898Y720509D01*
G01X533351Y704332D02*
X533739Y704720D01*
X539282D01*
X544506Y709944D01*
X548463D01*
X549898Y708509D01*
G01X535285Y725421D02*
X536770Y723936D01*
Y718770D01*
X529917Y711917D01*
Y710741D01*
X529414Y710238D01*
G01X539285Y725421D02*
X537850Y723986D01*
Y718322D01*
X530997Y711469D01*
Y710757D01*
X530947Y710707D01*
Y710673D01*
X531382Y710238D01*
G01X533351Y706301D02*
X533852Y705800D01*
X538834D01*
X544058Y711024D01*
X548413D01*
X549898Y712509D01*
G01X531285Y725421D02*
X529791Y723927D01*
Y718691D01*
X526976Y715876D01*
Y710707D01*
X527445Y710238D01*
G01X525477D02*
X525896Y710657D01*
Y716324D01*
X528711Y719139D01*
Y723995D01*
X527285Y725421D01*
G01X535285Y728571D02*
X536720Y730006D01*
Y735458D01*
X535585Y736593D01*
G01X539285Y728571D02*
X537800Y730056D01*
Y735408D01*
X538985Y736593D01*
G01X531285Y728571D02*
X529800Y730056D01*
Y740408D01*
X530985Y741593D01*
G01X527285Y728571D02*
X528720Y730006D01*
Y740458D01*
X527585Y741593D01*
G01X529582Y1353093D02*
X528322Y1351833D01*
Y1349347D01*
X529482Y1348187D01*
G01X525982Y1353093D02*
X527242Y1351833D01*
Y1349347D01*
X526082Y1348187D01*
G01X538222Y1353093D02*
X539482Y1351833D01*
Y1349347D01*
X538322Y1348187D01*
G01Y1360099D02*
X539482Y1358939D01*
Y1356453D01*
X538222Y1355193D01*
G01X529482Y1360099D02*
X528322Y1358939D01*
Y1356453D01*
X529582Y1355193D01*
G01X526082Y1360099D02*
X527242Y1358939D01*
Y1356453D01*
X525982Y1355193D01*
G01X529582Y1377291D02*
X528322Y1376031D01*
Y1373545D01*
X529482Y1372385D01*
G01X538322Y1384297D02*
X539482Y1383137D01*
Y1380651D01*
X538222Y1379391D01*
G01X529482Y1384297D02*
X528322Y1383137D01*
Y1380651D01*
X529582Y1379391D01*
G01X538222Y1377291D02*
X539482Y1376031D01*
Y1373545D01*
X538322Y1372385D01*
G01X525982Y1377291D02*
X527242Y1376031D01*
Y1373545D01*
X526082Y1372385D01*
G01Y1384297D02*
X527242Y1383137D01*
Y1380651D01*
X525982Y1379391D01*
G01Y1401489D02*
X527242Y1400229D01*
Y1397743D01*
X526082Y1396583D01*
G01X538222Y1401489D02*
X539482Y1400229D01*
Y1397743D01*
X538322Y1396583D01*
G01X529582Y1401489D02*
X528322Y1400229D01*
Y1397743D01*
X529482Y1396583D01*
G01Y1408495D02*
X528322Y1407335D01*
Y1404849D01*
X529582Y1403589D01*
G01X526082Y1408495D02*
X527242Y1407335D01*
Y1404849D01*
X525982Y1403589D01*
G01X538322Y1408495D02*
X539482Y1407335D01*
Y1404849D01*
X538222Y1403589D01*
G01X553048Y684509D02*
X554539Y686000D01*
X557879D01*
X559070Y684809D01*
G01X553048Y700509D02*
X554459Y701920D01*
X557959D01*
X559070Y700809D01*
G01X553048Y688509D02*
X554477Y687080D01*
X557941D01*
X559070Y688209D01*
G01X553048Y696509D02*
X554457Y695100D01*
X560461D01*
X561570Y696209D01*
G01X553048Y692509D02*
X554559Y694020D01*
X560359D01*
X561570Y692809D01*
G01X553048Y716509D02*
X554539Y718000D01*
X557879D01*
X559070Y716809D01*
G01X553048Y708509D02*
X554459Y709920D01*
X560459D01*
X561570Y708809D01*
G01X553048Y712509D02*
X554557Y711000D01*
X560361D01*
X561570Y712209D01*
G01X553048Y704509D02*
X554557Y703000D01*
X557861D01*
X559070Y704209D01*
G01X553048Y720509D02*
X554477Y719080D01*
X557941D01*
X559070Y720209D01*
G01X548452Y789327D02*
Y786860D01*
X547919Y786327D01*
Y782849D01*
X549168Y781600D01*
G01X546483Y789327D02*
Y786869D01*
X546889Y786463D01*
Y782721D01*
X545768Y781600D01*
G01X554062Y1353093D02*
X552802Y1351833D01*
Y1349347D01*
X553962Y1348187D01*
G01X541822Y1353093D02*
X540562Y1351833D01*
Y1349347D01*
X541722Y1348187D01*
G01X550462Y1353093D02*
X551722Y1351833D01*
Y1349347D01*
X550562Y1348187D01*
G01X553962Y1360099D02*
X552802Y1358939D01*
Y1356453D01*
X554062Y1355193D01*
G01X550562Y1360099D02*
X551722Y1358939D01*
Y1356453D01*
X550462Y1355193D01*
G01X541722Y1360099D02*
X540562Y1358939D01*
Y1356453D01*
X541822Y1355193D01*
G01Y1377291D02*
X540562Y1376031D01*
Y1373545D01*
X541722Y1372385D01*
G01X550462Y1377291D02*
X551722Y1376031D01*
Y1373545D01*
X550562Y1372385D01*
G01X541722Y1384297D02*
X540562Y1383137D01*
Y1380651D01*
X541822Y1379391D01*
G01X553962Y1384297D02*
X552802Y1383137D01*
Y1380651D01*
X554062Y1379391D01*
G01X550562Y1384297D02*
X551722Y1383137D01*
Y1380651D01*
X550462Y1379391D01*
G01X554062Y1377291D02*
X552802Y1376031D01*
Y1373545D01*
X553962Y1372385D01*
G01X554062Y1401489D02*
X552802Y1400229D01*
Y1397743D01*
X553962Y1396583D01*
G01X541822Y1401489D02*
X540562Y1400229D01*
Y1397743D01*
X541722Y1396583D01*
G01X550462Y1401489D02*
X551722Y1400229D01*
Y1397743D01*
X550562Y1396583D01*
G01X553962Y1408495D02*
X552802Y1407335D01*
Y1404849D01*
X554062Y1403589D01*
G01X550562Y1408495D02*
X551722Y1407335D01*
Y1404849D01*
X550462Y1403589D01*
G01X541722Y1408495D02*
X540562Y1407335D01*
Y1404849D01*
X541822Y1403589D01*
G01X562702Y1353093D02*
X563962Y1351833D01*
Y1349347D01*
X562802Y1348187D01*
G01X566302Y1353093D02*
X565042Y1351833D01*
Y1349347D01*
X566202Y1348187D01*
G01Y1360099D02*
X565042Y1358939D01*
Y1356453D01*
X566302Y1355193D01*
G01X562802Y1360099D02*
X563962Y1358939D01*
Y1356453D01*
X562702Y1355193D01*
G01X566302Y1377291D02*
X565042Y1376031D01*
Y1373545D01*
X566202Y1372385D01*
G01Y1384297D02*
X565042Y1383137D01*
Y1380651D01*
X566302Y1379391D01*
G01X562802Y1384297D02*
X563962Y1383137D01*
Y1380651D01*
X562702Y1379391D01*
G01Y1377291D02*
X563962Y1376031D01*
Y1373545D01*
X562802Y1372385D01*
G01X566302Y1401489D02*
X565042Y1400229D01*
Y1397743D01*
X566202Y1396583D01*
G01X562702Y1401489D02*
X563962Y1400229D01*
Y1397743D01*
X562802Y1396583D01*
G01X566202Y1408495D02*
X565042Y1407335D01*
Y1404849D01*
X566302Y1403589D01*
G01X562802Y1408495D02*
X563962Y1407335D01*
Y1404849D01*
X562702Y1403589D01*
G01X601437Y118859D02*
X599557D01*
X598916Y119500D01*
X588995D01*
X587837Y118342D01*
G01X601437Y121221D02*
X599537D01*
X598896Y120580D01*
X588999D01*
X587837Y121742D01*
G01X601437Y133032D02*
X599557D01*
X598916Y133673D01*
X588995D01*
X587837Y132515D01*
G01X601437Y135394D02*
X599537D01*
X598896Y134753D01*
X588999D01*
X587837Y135915D01*
G01X601437Y111772D02*
X599544D01*
X598896Y112420D01*
X596302D01*
X595137Y111255D01*
G01X601437Y114134D02*
Y114135D01*
X599551D01*
X598916Y113500D01*
X596292D01*
X595137Y114655D01*
G01X601437Y125945D02*
X599544D01*
X598919Y126570D01*
X596279D01*
X595137Y125428D01*
G01X601437Y128307D02*
X599550D01*
X598893Y127650D01*
X596315D01*
X595137Y128828D01*
G01X602682Y401613D02*
X601422Y400353D01*
X598936D01*
X597776Y401513D01*
G01X602682Y398013D02*
X601422Y399273D01*
X598936D01*
X597776Y398113D01*
G01X600282Y412187D02*
X599022Y413447D01*
X596536D01*
X595376Y412287D01*
G01X600282Y415787D02*
X599022Y414527D01*
X596536D01*
X595376Y415687D01*
G01X602382Y412187D02*
X603612Y413417D01*
X635793D01*
X636434Y412776D01*
X638355D01*
G01X602382Y415787D02*
X603672Y414497D01*
X635793D01*
X636434Y415138D01*
X638355D01*
G01X600282Y440533D02*
X599022Y441793D01*
X596536D01*
X595376Y440633D01*
G01X600282Y426360D02*
X599022Y427620D01*
X596536D01*
X595376Y426460D01*
G01X600282Y429960D02*
X599022Y428700D01*
X596536D01*
X595376Y429860D01*
G01X602382Y426360D02*
X603612Y427590D01*
X635793D01*
X636434Y426949D01*
X638355D01*
G01X602382Y429960D02*
X603672Y428670D01*
X635793D01*
X636434Y429311D01*
X638355D01*
G01X602382Y440533D02*
X603612Y441763D01*
X635793D01*
X636434Y441122D01*
X638355D01*
G01X600282Y444133D02*
X599022Y442873D01*
X596536D01*
X595376Y444033D01*
G01X602382Y444133D02*
X603672Y442843D01*
X635793D01*
X636434Y443484D01*
X638355D01*
G01X600282Y469287D02*
X599022Y470547D01*
X596536D01*
X595376Y469387D01*
G01X600282Y472887D02*
X599022Y471627D01*
X596536D01*
X595376Y472787D01*
G01X638355Y472264D02*
X636434D01*
X635793Y471623D01*
X603646D01*
X602382Y472887D01*
G01X638355Y469902D02*
X636434D01*
X635793Y470543D01*
X603638D01*
X602382Y469287D01*
G01X600282Y483460D02*
X599022Y484720D01*
X596536D01*
X595376Y483560D01*
G01X600282Y487060D02*
X599022Y485800D01*
X596536D01*
X595376Y486960D01*
G01X638355Y486437D02*
X636434D01*
X635793Y485796D01*
X603646D01*
X602382Y487060D01*
G01X638355Y484075D02*
X636434D01*
X635793Y484716D01*
X603638D01*
X602382Y483460D01*
G01X600282Y513421D02*
X599022Y514681D01*
X596536D01*
X595376Y513521D01*
G01X600282Y517021D02*
X599022Y515761D01*
X596536D01*
X595376Y516921D01*
G01X638355Y516398D02*
X636434D01*
X635793Y515757D01*
X603646D01*
X602382Y517021D01*
G01X638355Y514036D02*
X636434D01*
X635793Y514677D01*
X603638D01*
X602382Y513421D01*
G01X600282Y531194D02*
X599022Y529934D01*
X596536D01*
X595376Y531094D01*
G01X600282Y527594D02*
X599022Y528854D01*
X596536D01*
X595376Y527694D01*
G01X638355Y528209D02*
X636434D01*
X635793Y528850D01*
X603638D01*
X602382Y527594D01*
G01X638355Y530571D02*
X636434D01*
X635793Y529930D01*
X603646D01*
X602382Y531194D01*
G01X628448Y111123D02*
X627151Y112420D01*
X622176D01*
X621528Y111772D01*
X619547D01*
G01X628448Y114723D02*
X627225Y113500D01*
X622148D01*
X621514Y114134D01*
X619547D01*
G01X626305Y104249D02*
X625154Y105400D01*
X622191D01*
X621476Y104685D01*
X619547D01*
G01X626305Y107649D02*
X625136Y106480D01*
X622097D01*
X621530Y107047D01*
X619547D01*
G01X638850Y132409D02*
X637589Y133670D01*
X622181D01*
X621543Y133032D01*
X619547D01*
G01X638850Y121835D02*
X637615Y120600D01*
X622139D01*
X621518Y121221D01*
X619547D01*
G01X638850Y118235D02*
X637565Y119520D01*
X622189D01*
X621528Y118859D01*
X619547D01*
G01X628448Y128896D02*
X627152Y127600D01*
X622221D01*
X621514Y128307D01*
X619547D01*
G01X628448Y125296D02*
X627224Y126520D01*
X622103D01*
X621528Y125945D01*
X619547D01*
G01X638850Y136009D02*
X637591Y134750D01*
X622171D01*
X621527Y135394D01*
X619547D01*
G01X610684Y390901D02*
X609424Y392161D01*
X606938D01*
X605778Y391001D01*
G01X612784Y390901D02*
X614040Y392157D01*
X635793D01*
X636434Y391516D01*
X638355D01*
G01X610684Y405074D02*
X609424Y406334D01*
X606938D01*
X605778Y405174D01*
G01X610684Y394501D02*
X609424Y393241D01*
X606938D01*
X605778Y394401D01*
G01X610684Y408674D02*
X609424Y407414D01*
X606938D01*
X605778Y408574D01*
G01X612784Y408674D02*
X614048Y407410D01*
X635793D01*
X636434Y408051D01*
X638355D01*
G01X612784Y394501D02*
X614048Y393237D01*
X635793D01*
X636434Y393878D01*
X638355D01*
G01Y398602D02*
X636433D01*
X635792Y399243D01*
X606012D01*
X604782Y398013D01*
G01X638355Y400965D02*
X636434D01*
X635792Y400323D01*
X606072D01*
X604782Y401613D01*
G01X612784Y405074D02*
X614040Y406330D01*
X635793D01*
X636434Y405689D01*
X638355D01*
G01X610684Y422847D02*
X609424Y421587D01*
X606938D01*
X605778Y422747D01*
G01X610684Y419247D02*
X609424Y420507D01*
X606938D01*
X605778Y419347D01*
G01X612784Y419247D02*
X614040Y420503D01*
X635793D01*
X636434Y419862D01*
X638355D01*
G01X612784Y422847D02*
X614048Y421583D01*
X635793D01*
X636434Y422224D01*
X638355D01*
G01X610684Y433421D02*
X609424Y434681D01*
X606938D01*
X605778Y433521D01*
G01X610684Y437021D02*
X609424Y435761D01*
X606938D01*
X605778Y436921D01*
G01X612784Y437021D02*
X614048Y435757D01*
X635793D01*
X636434Y436398D01*
X638355D01*
G01X612784Y433421D02*
X614040Y434677D01*
X635793D01*
X636434Y434036D01*
X638355D01*
G01X610684Y479999D02*
X609424Y478739D01*
X606938D01*
X605778Y479899D01*
G01X610684Y476399D02*
X609424Y477659D01*
X606938D01*
X605778Y476499D01*
G01X638355Y476988D02*
X636434D01*
X635793Y477629D01*
X614014D01*
X612784Y476399D01*
G01X638355Y479350D02*
X636434D01*
X635793Y478709D01*
X614074D01*
X612784Y479999D01*
G01X610684Y490573D02*
X609424Y491833D01*
X606938D01*
X605778Y490673D01*
G01X610684Y494173D02*
X609424Y492913D01*
X606938D01*
X605778Y494073D01*
G01X638355Y493524D02*
X636434D01*
X635793Y492883D01*
X614074D01*
X612784Y494173D01*
G01X638355Y491162D02*
X636434D01*
X635793Y491803D01*
X614014D01*
X612784Y490573D01*
G01X610684Y520533D02*
X609424Y521793D01*
X606938D01*
X605778Y520633D01*
G01X610684Y524133D02*
X609424Y522873D01*
X606938D01*
X605778Y524033D01*
G01X638355Y521122D02*
X636434D01*
X635793Y521763D01*
X614014D01*
X612784Y520533D01*
G01X638355Y523484D02*
X636434D01*
X635793Y522843D01*
X614074D01*
X612784Y524133D01*
G01X610684Y534706D02*
X609424Y535966D01*
X606938D01*
X605778Y534806D01*
G01X610684Y538306D02*
X609424Y537046D01*
X606938D01*
X605778Y538206D01*
G01X638355Y535295D02*
X636433D01*
X635792Y535936D01*
X614014D01*
X612784Y534706D01*
G01X638355Y537658D02*
X636434D01*
X635792Y537016D01*
X614074D01*
X612784Y538306D01*
G01X635454Y114623D02*
X634331Y113500D01*
X631771D01*
X630548Y114723D01*
G01X635454Y111223D02*
X634257Y112420D01*
X631845D01*
X630548Y111123D01*
G01X635454Y128796D02*
X634258Y127600D01*
X631844D01*
X630548Y128896D01*
G01X635454Y125396D02*
X634330Y126520D01*
X631772D01*
X630548Y125296D01*
G01X632009Y541863D02*
X633169Y543023D01*
X635877D01*
X636518Y542382D01*
X638355D01*
G01X632009Y545263D02*
X633169Y544103D01*
X635903D01*
X636544Y544744D01*
X638355D01*
G01X629788Y1401489D02*
X628528Y1400229D01*
Y1397743D01*
X629688Y1396583D01*
G01X626188Y1401489D02*
X627448Y1400229D01*
Y1397743D01*
X626288Y1396583D01*
G01Y1408495D02*
X627448Y1407335D01*
Y1404849D01*
X626188Y1403589D01*
G01X629688Y1408495D02*
X628528Y1407335D01*
Y1404849D01*
X629788Y1403589D01*
G01X645856Y118335D02*
X644691Y119500D01*
X642215D01*
X640950Y118235D01*
G01X645856Y132509D02*
X644695Y133670D01*
X642211D01*
X640950Y132409D01*
G01X645856Y121735D02*
X644701Y120580D01*
X642205D01*
X640950Y121835D01*
G01X645856Y135909D02*
X644697Y134750D01*
X642209D01*
X640950Y136009D01*
G01X650668Y1353093D02*
X651928Y1351833D01*
Y1349347D01*
X650768Y1348187D01*
G01Y1360099D02*
X651928Y1358939D01*
Y1356453D01*
X650668Y1355193D01*
G01X650768Y1384297D02*
X651928Y1383137D01*
Y1380651D01*
X650668Y1379391D01*
G01Y1377291D02*
X651928Y1376031D01*
Y1373545D01*
X650768Y1372385D01*
G01X638428Y1377291D02*
X639688Y1376031D01*
Y1373545D01*
X638528Y1372385D01*
G01X642028Y1377291D02*
X640768Y1376031D01*
Y1373545D01*
X641928Y1372385D01*
G01X638528Y1384297D02*
X639688Y1383137D01*
Y1380651D01*
X638428Y1379391D01*
G01X641928Y1384297D02*
X640768Y1383137D01*
Y1380651D01*
X642028Y1379391D01*
G01Y1401489D02*
X640768Y1400229D01*
Y1397743D01*
X641928Y1396583D01*
G01X638428Y1401489D02*
X639688Y1400229D01*
Y1397743D01*
X638528Y1396583D01*
G01X650668Y1401489D02*
X651928Y1400229D01*
Y1397743D01*
X650768Y1396583D01*
G01X638528Y1408495D02*
X639688Y1407335D01*
Y1404849D01*
X638428Y1403589D01*
G01X641928Y1408495D02*
X640768Y1407335D01*
Y1404849D01*
X642028Y1403589D01*
G01X650768Y1408495D02*
X651928Y1407335D01*
Y1404849D01*
X650668Y1403589D01*
G01X656466Y391516D02*
X658387D01*
X659028Y392157D01*
X668904D01*
X670066Y390995D01*
G01X656466Y405689D02*
X658387D01*
X659028Y406330D01*
X668904D01*
X670066Y405168D01*
G01X656466Y398602D02*
X658388D01*
X659029Y399243D01*
X661605D01*
X662766Y398082D01*
G01X656466Y408051D02*
X658387D01*
X659028Y407410D01*
X668904D01*
X668906Y407408D01*
X670066Y408568D01*
G01X656466Y393878D02*
X658387D01*
X659028Y393237D01*
X668904D01*
X668906Y393235D01*
X670066Y394395D01*
G01X656466Y400965D02*
X658387D01*
X659029Y400323D01*
X661607D01*
X662766Y401482D01*
G01X656466Y422224D02*
X658387D01*
X659028Y421583D01*
X668904D01*
X668906Y421581D01*
X670066Y422741D01*
G01X656466Y419862D02*
X658387D01*
X659028Y420503D01*
X668904D01*
X670066Y419341D01*
G01X662766Y415655D02*
X661608Y414497D01*
X659028D01*
X658387Y415138D01*
X656466D01*
G01X662766Y412255D02*
Y412256D01*
X661605Y413417D01*
X659028D01*
X658387Y412776D01*
X656466D01*
G01Y441122D02*
X658387D01*
X659028Y441763D01*
X661605D01*
X662766Y440602D01*
G01X656466Y434036D02*
X658387D01*
X659028Y434677D01*
X668904D01*
X670066Y433515D01*
G01X662766Y426428D02*
Y426429D01*
X661605Y427590D01*
X659028D01*
X658387Y426949D01*
X656466D01*
G01X662766Y429828D02*
X661608Y428670D01*
X659028D01*
X658387Y429311D01*
X656466D01*
G01Y436398D02*
X658387D01*
X659028Y435757D01*
X668904D01*
X668906Y435755D01*
X670066Y436915D01*
G01X656466Y443484D02*
X658387D01*
X659028Y442843D01*
X661607D01*
X662766Y444002D01*
G01X656466Y469902D02*
X658387D01*
X659028Y470543D01*
X668904D01*
X670066Y469381D01*
G01X656466Y472264D02*
X658387D01*
X659028Y471623D01*
X668904D01*
X668906Y471621D01*
X670066Y472781D01*
G01X656466Y476988D02*
X658387D01*
X659028Y477629D01*
X661605D01*
X662766Y476468D01*
G01X656466Y484075D02*
X658387D01*
X659028Y484716D01*
X668904D01*
X670066Y483554D01*
G01X656466Y486437D02*
X658387D01*
X659028Y485796D01*
X668904D01*
X668906Y485794D01*
X670066Y486954D01*
G01X656466Y479350D02*
X658387D01*
X659028Y478709D01*
X661607D01*
X662766Y479868D01*
G01Y490641D02*
Y490642D01*
X661605Y491803D01*
X659028D01*
X658387Y491162D01*
X656466D01*
G01X662766Y494041D02*
X661608Y492883D01*
X659028D01*
X658387Y493524D01*
X656466D01*
G01Y516398D02*
X658387D01*
X659028Y515757D01*
X668904D01*
X668906Y515755D01*
X670066Y516915D01*
G01X656466Y521122D02*
X658387D01*
X659028Y521763D01*
X661605D01*
X662766Y520602D01*
G01X656466Y523484D02*
X658387D01*
X659028Y522843D01*
X661607D01*
X662766Y524002D01*
G01X656466Y514036D02*
X658387D01*
X659028Y514677D01*
X668904D01*
X670066Y513515D01*
G01X656466Y528209D02*
X658387D01*
X659028Y528850D01*
X668904D01*
X670066Y527688D01*
G01X656466Y535295D02*
X658388D01*
X659029Y535936D01*
X661605D01*
X662766Y534775D01*
G01X656466Y530571D02*
X658387D01*
X659028Y529930D01*
X668904D01*
X668906Y529928D01*
X670066Y531088D01*
G01X656466Y537658D02*
X658387D01*
X659029Y537016D01*
X661607D01*
X662766Y538175D01*
G01X666508Y1353093D02*
X665248Y1351833D01*
Y1349347D01*
X666408Y1348187D01*
G01X662908Y1353093D02*
X664168Y1351833D01*
Y1349347D01*
X663008Y1348187D01*
G01X654268Y1353093D02*
X653008Y1351833D01*
Y1349347D01*
X654168Y1348187D01*
G01X666408Y1360099D02*
X665248Y1358939D01*
Y1356453D01*
X666508Y1355193D01*
G01X663008Y1360099D02*
X664168Y1358939D01*
Y1356453D01*
X662908Y1355193D01*
G01X654168Y1360099D02*
X653008Y1358939D01*
Y1356453D01*
X654268Y1355193D01*
G01X654168Y1384297D02*
X653008Y1383137D01*
Y1380651D01*
X654268Y1379391D01*
G01Y1377291D02*
X653008Y1376031D01*
Y1373545D01*
X654168Y1372385D01*
G01X662908Y1377291D02*
X664168Y1376031D01*
Y1373545D01*
X663008Y1372385D01*
G01X666508Y1377291D02*
X665248Y1376031D01*
Y1373545D01*
X666408Y1372385D01*
G01X663008Y1384297D02*
X664168Y1383137D01*
Y1380651D01*
X662908Y1379391D01*
G01X666408Y1384297D02*
X665248Y1383137D01*
Y1380651D01*
X666508Y1379391D01*
G01Y1401489D02*
X665248Y1400229D01*
Y1397743D01*
X666408Y1396583D01*
G01X662908Y1401489D02*
X664168Y1400229D01*
Y1397743D01*
X663008Y1396583D01*
G01X654268Y1401489D02*
X653008Y1400229D01*
Y1397743D01*
X654168Y1396583D01*
G01X666408Y1408495D02*
X665248Y1407335D01*
Y1404849D01*
X666508Y1403589D01*
G01X663008Y1408495D02*
X664168Y1407335D01*
Y1404849D01*
X662908Y1403589D01*
G01X654168Y1408495D02*
X653008Y1407335D01*
Y1404849D01*
X654268Y1403589D01*
G01X678748Y1353093D02*
X677488Y1351833D01*
Y1349347D01*
X678648Y1348187D01*
G01X675148Y1353093D02*
X676408Y1351833D01*
Y1349347D01*
X675248Y1348187D01*
G01X678648Y1360099D02*
X677488Y1358939D01*
Y1356453D01*
X678748Y1355193D01*
G01X675248Y1360099D02*
X676408Y1358939D01*
Y1356453D01*
X675148Y1355193D01*
G01X675248Y1384297D02*
X676408Y1383137D01*
Y1380651D01*
X675148Y1379391D01*
G01X678648Y1384297D02*
X677488Y1383137D01*
Y1380651D01*
X678748Y1379391D01*
G01Y1377291D02*
X677488Y1376031D01*
Y1373545D01*
X678648Y1372385D01*
G01X675148Y1377291D02*
X676408Y1376031D01*
Y1373545D01*
X675248Y1372385D01*
G01X675148Y1401489D02*
X676408Y1400229D01*
Y1397743D01*
X675248Y1396583D01*
G01X678748Y1401489D02*
X677488Y1400229D01*
Y1397743D01*
X678648Y1396583D01*
G01Y1408495D02*
X677488Y1407335D01*
Y1404849D01*
X678748Y1403589D01*
G01X675248Y1408495D02*
X676408Y1407335D01*
Y1404849D01*
X675148Y1403589D01*
G01X703799Y114134D02*
Y114135D01*
X701913D01*
X701278Y113500D01*
X698654D01*
X697499Y114655D01*
G01X703799Y111772D02*
X701906D01*
X701258Y112420D01*
X698664D01*
X697499Y111255D01*
G01X703799Y133032D02*
X701919D01*
X701278Y133673D01*
X691357D01*
X690199Y132515D01*
G01X703799Y125945D02*
X701906D01*
X701281Y126570D01*
X698641D01*
X697499Y125428D01*
G01X703799Y128307D02*
X701912D01*
X701255Y127650D01*
X698677D01*
X697499Y128828D01*
G01X703799Y121221D02*
X701899D01*
X701258Y120580D01*
X691361D01*
X690199Y121742D01*
G01X703799Y118859D02*
X701919D01*
X701278Y119500D01*
X691357D01*
X690199Y118342D01*
G01X703799Y135394D02*
X701899D01*
X701258Y134753D01*
X691361D01*
X690199Y135915D01*
G01X693799Y1215452D02*
X691929Y1217322D01*
G01X693799Y1211712D02*
X691929Y1213582D01*
G01X690988Y1353093D02*
X689728Y1351833D01*
Y1349347D01*
X690888Y1348187D01*
G01X687388Y1353093D02*
X688648Y1351833D01*
Y1349347D01*
X687488Y1348187D01*
G01X699628Y1353093D02*
X700888Y1351833D01*
Y1349347D01*
X699728Y1348187D01*
G01X687488Y1360099D02*
X688648Y1358939D01*
Y1356453D01*
X687388Y1355193D01*
G01X690888Y1360099D02*
X689728Y1358939D01*
Y1356453D01*
X690988Y1355193D01*
G01X699728Y1360099D02*
X700888Y1358939D01*
Y1356453D01*
X699628Y1355193D01*
G01Y1377291D02*
X700888Y1376031D01*
Y1373545D01*
X699728Y1372385D01*
G01Y1384297D02*
X700888Y1383137D01*
Y1380651D01*
X699628Y1379391D01*
G01X690988Y1377291D02*
X689728Y1376031D01*
Y1373545D01*
X690888Y1372385D01*
G01X687388Y1377291D02*
X688648Y1376031D01*
Y1373545D01*
X687488Y1372385D01*
G01Y1384297D02*
X688648Y1383137D01*
Y1380651D01*
X687388Y1379391D01*
G01X690888Y1384297D02*
X689728Y1383137D01*
Y1380651D01*
X690988Y1379391D01*
G01Y1401489D02*
X689728Y1400229D01*
Y1397743D01*
X690888Y1396583D01*
G01X687388Y1401489D02*
X688648Y1400229D01*
Y1397743D01*
X687488Y1396583D01*
G01X699628Y1401489D02*
X700888Y1400229D01*
Y1397743D01*
X699728Y1396583D01*
G01X687488Y1408495D02*
X688648Y1407335D01*
Y1404849D01*
X687388Y1403589D01*
G01X690888Y1408495D02*
X689728Y1407335D01*
Y1404849D01*
X690988Y1403589D01*
G01X699728Y1408495D02*
X700888Y1407335D01*
Y1404849D01*
X699628Y1403589D01*
G01X727391Y474941D02*
X725470D01*
X724829Y475582D01*
X714953D01*
X714951Y475584D01*
X713791Y474424D01*
G01X727391Y489114D02*
X725470D01*
X724829Y489755D01*
X714953D01*
X714951Y489757D01*
X713791Y488597D01*
G01X727391Y477303D02*
X725470D01*
X724829Y476662D01*
X714953D01*
X713791Y477824D01*
G01X727391Y491476D02*
X725470D01*
X724829Y490835D01*
X714953D01*
X713791Y491997D01*
G01X727391Y519075D02*
X725470D01*
X724829Y519716D01*
X714953D01*
X714951Y519718D01*
X713791Y518558D01*
G01X727391Y521437D02*
X725470D01*
X724829Y520796D01*
X714953D01*
X713791Y521958D01*
G01X727391Y535610D02*
X725470D01*
X724829Y534969D01*
X714953D01*
X713791Y536131D01*
G01X727391Y533248D02*
X725470D01*
X724829Y533889D01*
X714953D01*
X714951Y533891D01*
X713791Y532731D01*
G01X727391Y571476D02*
X725470D01*
X724829Y570835D01*
X714953D01*
X713791Y571997D01*
G01X727391Y569114D02*
X725470D01*
X724829Y569755D01*
X714953D01*
X714951Y569757D01*
X713791Y568597D01*
G01X727391Y583288D02*
X725470D01*
X724829Y583929D01*
X714953D01*
X714951Y583931D01*
X713791Y582771D01*
G01X727391Y585650D02*
X725470D01*
X724829Y585009D01*
X714953D01*
X713791Y586171D01*
G01X727391Y597461D02*
X725470D01*
X724829Y598102D01*
X714953D01*
X714951Y598104D01*
X713791Y596944D01*
G01X727391Y599823D02*
X725470D01*
X724829Y599182D01*
X714953D01*
X713791Y600344D01*
G01X727391Y611634D02*
X725470D01*
X724829Y612275D01*
X714953D01*
X714951Y612277D01*
X713791Y611117D01*
G01X727391Y613996D02*
X725470D01*
X724829Y613355D01*
X714953D01*
X713791Y614517D01*
G01X715468Y1353093D02*
X714208Y1351833D01*
Y1349347D01*
X715368Y1348187D01*
G01X711868Y1353093D02*
X713128Y1351833D01*
Y1349347D01*
X711968Y1348187D01*
G01X703228Y1353093D02*
X701968Y1351833D01*
Y1349347D01*
X703128Y1348187D01*
G01X715368Y1360099D02*
X714208Y1358939D01*
Y1356453D01*
X715468Y1355193D01*
G01X711968Y1360099D02*
X713128Y1358939D01*
Y1356453D01*
X711868Y1355193D01*
G01X703128Y1360099D02*
X701968Y1358939D01*
Y1356453D01*
X703228Y1355193D01*
G01Y1377291D02*
X701968Y1376031D01*
Y1373545D01*
X703128Y1372385D01*
G01Y1384297D02*
X701968Y1383137D01*
Y1380651D01*
X703228Y1379391D01*
G01X715468Y1377291D02*
X714208Y1376031D01*
Y1373545D01*
X715368Y1372385D01*
G01X711868Y1377291D02*
X713128Y1376031D01*
Y1373545D01*
X711968Y1372385D01*
G01X715368Y1384297D02*
X714208Y1383137D01*
Y1380651D01*
X715468Y1379391D01*
G01X711968Y1384297D02*
X713128Y1383137D01*
Y1380651D01*
X711868Y1379391D01*
G01X715468Y1401489D02*
X714208Y1400229D01*
Y1397743D01*
X715368Y1396583D01*
G01X711868Y1401489D02*
X713128Y1400229D01*
Y1397743D01*
X711968Y1396583D01*
G01X703228Y1401489D02*
X701968Y1400229D01*
Y1397743D01*
X703128Y1396583D01*
G01X715368Y1408495D02*
X714208Y1407335D01*
Y1404849D01*
X715468Y1403589D01*
G01X711968Y1408495D02*
X713128Y1407335D01*
Y1404849D01*
X711868Y1403589D01*
G01X703128Y1408495D02*
X701968Y1407335D01*
Y1404849D01*
X703228Y1403589D01*
G01X949942Y-32782D02*
X949187D01*
X948743Y-32338D01*
X932403D01*
X931176Y-31308D01*
X928871Y-18236D01*
X927644Y-17377D01*
X923875Y-18042D01*
X923017Y-19267D01*
X927912Y-47031D01*
X926540Y-48992D01*
X921894Y-49811D01*
X919939Y-48440D01*
X914607Y-18224D01*
X913379Y-17365D01*
X909611Y-18031D01*
X908753Y-19254D01*
X913643Y-46986D01*
X912271Y-48946D01*
X907625Y-49765D01*
X905662Y-48393D01*
X900335Y-18166D01*
X899110Y-17307D01*
X895342Y-17973D01*
X894482Y-19201D01*
X899382Y-46994D01*
X898010Y-48956D01*
X893364Y-49775D01*
X891404Y-48401D01*
X886080Y-18210D01*
X884855Y-17351D01*
X881087Y-18016D01*
X880227Y-19244D01*
X885112Y-46956D01*
X883740Y-48919D01*
X879094Y-49738D01*
X877138Y-48367D01*
X871904Y-18701D01*
X870677Y-17842D01*
X866909Y-18507D01*
X866051Y-19733D01*
X870770Y-46500D01*
X869398Y-48461D01*
X864752Y-49280D01*
X862795Y-47909D01*
X857648Y-18734D01*
X856421Y-17875D01*
X852653Y-18540D01*
X851795Y-19766D01*
X856515Y-46539D01*
X855143Y-48500D01*
X850497Y-49319D01*
X848538Y-47948D01*
X843387Y-18744D01*
X842160Y-17885D01*
X838392Y-18550D01*
X837534Y-19776D01*
X842244Y-46493D01*
X840872Y-48454D01*
X836226Y-49273D01*
X834269Y-47902D01*
X829107Y-18641D01*
X827880Y-17782D01*
X824112Y-18447D01*
X823254Y-19673D01*
X828007Y-46634D01*
X826635Y-48595D01*
X821989Y-49414D01*
X820030Y-48043D01*
X814837Y-18600D01*
X813610Y-17741D01*
X809842Y-18406D01*
X808984Y-19632D01*
X813722Y-46508D01*
X812350Y-48470D01*
X807704Y-49289D01*
X805747Y-47918D01*
X800583Y-18645D01*
X799356Y-17786D01*
X795588Y-18451D01*
X794730Y-19677D01*
X799471Y-46570D01*
X798099Y-48531D01*
X793453Y-49350D01*
X791495Y-47980D01*
X786308Y-18570D01*
X785082Y-17711D01*
X781313Y-18376D01*
X780455Y-19601D01*
X785217Y-46615D01*
X783845Y-48576D01*
X779199Y-49395D01*
X777239Y-48024D01*
X772053Y-18614D01*
X770826Y-17755D01*
X767058Y-18420D01*
X766199Y-19646D01*
X770956Y-46616D01*
X769584Y-48575D01*
X764938Y-49394D01*
X762977Y-48023D01*
X757799Y-18660D01*
X756572Y-17801D01*
X752804Y-18466D01*
X751946Y-19692D01*
X756681Y-46551D01*
X755309Y-48512D01*
X750663Y-49331D01*
X748707Y-47962D01*
X746087Y-33114D01*
X745339Y-32366D01*
X726205D01*
X725761Y-32810D01*
X725006D01*
G01X949942Y-30814D02*
X949187D01*
X948743Y-31258D01*
X932797D01*
X932172Y-30733D01*
X929857Y-17608D01*
X927897Y-16235D01*
X923247Y-17056D01*
X921875Y-19014D01*
X926770Y-46778D01*
X925911Y-48005D01*
X922148Y-48669D01*
X920925Y-47812D01*
X915593Y-17596D01*
X913632Y-16223D01*
X908983Y-17045D01*
X907611Y-19000D01*
X912501Y-46733D01*
X911642Y-47959D01*
X907878Y-48623D01*
X906648Y-47764D01*
X901321Y-17538D01*
X899363Y-16165D01*
X894714Y-16987D01*
X893340Y-18948D01*
X898240Y-46741D01*
X897381Y-47969D01*
X893618Y-48633D01*
X892390Y-47773D01*
X887066Y-17582D01*
X885109Y-16209D01*
X880459Y-17030D01*
X879085Y-18991D01*
X883970Y-46703D01*
X883111Y-47933D01*
X879348Y-48596D01*
X878124Y-47739D01*
X872890Y-18073D01*
X870930Y-16700D01*
X870490Y-16777D01*
Y-16778D01*
X866280Y-17520D01*
X864909Y-19480D01*
X869628Y-46247D01*
X868769Y-47474D01*
X865005Y-48138D01*
X863781Y-47281D01*
X858634Y-18106D01*
X856674Y-16733D01*
X856234Y-16810D01*
Y-16811D01*
X852024Y-17553D01*
X850653Y-19513D01*
X855373Y-46286D01*
X854514Y-47513D01*
X850750Y-48177D01*
X849525Y-47319D01*
X844373Y-18116D01*
X842413Y-16743D01*
X841973Y-16820D01*
Y-16821D01*
X837763Y-17563D01*
X836392Y-19523D01*
X841102Y-46240D01*
X840243Y-47467D01*
X836479Y-48131D01*
X835255Y-47274D01*
X830093Y-18013D01*
X828133Y-16640D01*
X827693Y-16717D01*
Y-16718D01*
X823483Y-17460D01*
X822112Y-19420D01*
X826865Y-46381D01*
X826006Y-47608D01*
X822242Y-48272D01*
X821017Y-47414D01*
X815823Y-17972D01*
X813863Y-16599D01*
X813423Y-16676D01*
Y-16677D01*
X809213Y-17419D01*
X807842Y-19379D01*
X812580Y-46255D01*
X811721Y-47483D01*
X807957Y-48147D01*
X806733Y-47290D01*
X801569Y-18017D01*
X799609Y-16644D01*
X799169Y-16721D01*
Y-16722D01*
X794959Y-17464D01*
X793588Y-19424D01*
X798329Y-46317D01*
X797470Y-47544D01*
X793706Y-48208D01*
X792482Y-47351D01*
X787294Y-17942D01*
X785335Y-16569D01*
X780685Y-17390D01*
X779313Y-19348D01*
X784075Y-46362D01*
X783216Y-47589D01*
X779452Y-48253D01*
X778226Y-47395D01*
X773039Y-17986D01*
X771079Y-16613D01*
X766430Y-17434D01*
X765057Y-19393D01*
X769814Y-46363D01*
X768956Y-47589D01*
X765191Y-48252D01*
X763963Y-47394D01*
X758785Y-18032D01*
X756826Y-16659D01*
X752175Y-17479D01*
X750804Y-19439D01*
X755539Y-46298D01*
X754680Y-47525D01*
X750916Y-48189D01*
X749694Y-47333D01*
X747092Y-32591D01*
X745787Y-31286D01*
X726205D01*
X725761Y-30842D01*
X725006D01*
G01X737816Y114623D02*
X736693Y113500D01*
X734133D01*
X732910Y114723D01*
G01X737816Y111223D02*
X736619Y112420D01*
X734207D01*
X732910Y111123D01*
G01X730810D02*
X729513Y112420D01*
X724538D01*
X723890Y111772D01*
X721909D01*
G01X730810Y114723D02*
X729587Y113500D01*
X724510D01*
X723876Y114134D01*
X721909D01*
G01X728667Y104249D02*
X727516Y105400D01*
X724553D01*
X723838Y104685D01*
X721909D01*
G01X728667Y107649D02*
X727498Y106480D01*
X724459D01*
X723892Y107047D01*
X721909D01*
G01X737816Y128796D02*
X736620Y127600D01*
X734206D01*
X732910Y128896D01*
G01X737816Y125396D02*
X736692Y126520D01*
X734134D01*
X732910Y125296D01*
G01X741212Y121835D02*
X739977Y120600D01*
X724501D01*
X723880Y121221D01*
X721909D01*
G01X730810Y125296D02*
X729586Y126520D01*
X724465D01*
X723890Y125945D01*
X721909D01*
G01X741212Y132409D02*
X739951Y133670D01*
X724543D01*
X723905Y133032D01*
X721909D01*
G01X741212Y118235D02*
X739927Y119520D01*
X724551D01*
X723890Y118859D01*
X721909D01*
G01X730810Y128896D02*
X729514Y127600D01*
X724583D01*
X723876Y128307D01*
X721909D01*
G01X741212Y136009D02*
X739953Y134750D01*
X724533D01*
X723889Y135394D01*
X721909D01*
G01X727391Y470217D02*
X725470D01*
X724828Y469575D01*
X722253D01*
X721091Y470737D01*
G01X727391Y467854D02*
X725469D01*
X724828Y468495D01*
X722249D01*
X721091Y467337D01*
G01Y484910D02*
X722252Y483749D01*
X724829D01*
X725470Y484390D01*
X727391D01*
G01X721091Y481510D02*
Y481511D01*
X722249Y482669D01*
X724829D01*
X725470Y482028D01*
X727391D01*
G01Y514350D02*
X725470D01*
X724829Y513709D01*
X722253D01*
X721091Y514871D01*
G01X727391Y511988D02*
X725470D01*
X724829Y512629D01*
X722249D01*
X721091Y511471D01*
G01Y525644D02*
Y525645D01*
X722249Y526803D01*
X724829D01*
X725470Y526162D01*
X727391D01*
G01X721091Y529044D02*
X722252Y527883D01*
X724829D01*
X725470Y528524D01*
X727391D01*
G01X721091Y561510D02*
Y561511D01*
X722249Y562669D01*
X724829D01*
X725470Y562028D01*
X727391D01*
G01X721091Y564910D02*
X722252Y563749D01*
X724829D01*
X725470Y564390D01*
X727391D01*
G01Y578563D02*
X725470D01*
X724829Y577922D01*
X722253D01*
X721091Y579084D01*
G01X727391Y576201D02*
X725470D01*
X724829Y576842D01*
X722249D01*
X721091Y575684D01*
G01X727391Y592736D02*
X725470D01*
X724829Y592095D01*
X722253D01*
X721091Y593257D01*
G01X727391Y604547D02*
X725469D01*
X724828Y605188D01*
X722249D01*
X721091Y604030D01*
G01X727391Y590374D02*
X725470D01*
X724829Y591015D01*
X722249D01*
X721091Y589857D01*
G01X727391Y606910D02*
X725470D01*
X724828Y606268D01*
X722253D01*
X721091Y607430D01*
G01X727708Y1353093D02*
X726448Y1351833D01*
Y1349347D01*
X727608Y1348187D01*
G01X724108Y1353093D02*
X725368Y1351833D01*
Y1349347D01*
X724208Y1348187D01*
G01Y1360099D02*
X725368Y1358939D01*
Y1356453D01*
X724108Y1355193D01*
G01X727608Y1360099D02*
X726448Y1358939D01*
Y1356453D01*
X727708Y1355193D01*
G01X724108Y1377291D02*
X725368Y1376031D01*
Y1373545D01*
X724208Y1372385D01*
G01Y1384297D02*
X725368Y1383137D01*
Y1380651D01*
X724108Y1379391D01*
G01X727608Y1384297D02*
X726448Y1383137D01*
Y1380651D01*
X727708Y1379391D01*
G01Y1377291D02*
X726448Y1376031D01*
Y1373545D01*
X727608Y1372385D01*
G01X724108Y1401395D02*
X725368Y1400135D01*
Y1397649D01*
X724208Y1396489D01*
G01X727708Y1401395D02*
X726448Y1400135D01*
Y1397649D01*
X727608Y1396489D01*
G01X724208Y1408401D02*
X725368Y1407241D01*
Y1404755D01*
X724108Y1403495D01*
G01X727608Y1408401D02*
X726448Y1407241D01*
Y1404755D01*
X727708Y1403495D01*
G01X748218Y118335D02*
X747053Y119500D01*
X744577D01*
X743312Y118235D01*
G01X748218Y132509D02*
X747007Y133720D01*
X744623D01*
X743312Y132409D01*
G01X748218Y121735D02*
X747063Y120580D01*
X744567D01*
X743312Y121835D01*
G01X748218Y135909D02*
X747109Y134800D01*
X744521D01*
X743312Y136009D01*
G01X745502Y470217D02*
X747424D01*
X748066Y469575D01*
X769842D01*
X771073Y470806D01*
G01X745502Y467854D02*
X747425D01*
X748066Y468495D01*
X769784D01*
X771073Y467206D01*
G01X752097Y460218D02*
X750906Y461409D01*
X748109D01*
X747468Y460768D01*
X745502D01*
G01X752097Y463618D02*
X750968Y462489D01*
X748109D01*
X747468Y463130D01*
X745502D01*
G01Y482028D02*
X747424D01*
X748065Y482669D01*
X769783D01*
X771073Y481379D01*
G01X745502Y474941D02*
X747424D01*
X748065Y475582D01*
X780211D01*
X781475Y474318D01*
G01X745502Y477303D02*
X747424D01*
X748065Y476662D01*
X780219D01*
X781475Y477918D01*
G01X745502Y489114D02*
X747424D01*
X748065Y489755D01*
X780211D01*
X781475Y488491D01*
G01X745502Y484390D02*
X747424D01*
X748065Y483749D01*
X769843D01*
X771073Y484979D01*
G01X745502Y491476D02*
X747424D01*
X748065Y490835D01*
X780219D01*
X781475Y492091D01*
G01X745502Y514350D02*
X747424D01*
X748065Y513709D01*
X769843D01*
X771073Y514939D01*
G01X745502Y519075D02*
X747424D01*
X748065Y519716D01*
X780211D01*
X781475Y518452D01*
G01X745502Y521437D02*
X747424D01*
X748065Y520796D01*
X780219D01*
X781475Y522052D01*
G01X745502Y511988D02*
X747424D01*
X748065Y512629D01*
X769783D01*
X771073Y511339D01*
G01X745502Y528524D02*
X747424D01*
X748065Y527883D01*
X769843D01*
X771073Y529113D01*
G01X745502Y533248D02*
X747424D01*
X748065Y533889D01*
X780211D01*
X781475Y532625D01*
G01X745502Y535610D02*
X747424D01*
X748065Y534969D01*
X780219D01*
X781475Y536225D01*
G01X745502Y526162D02*
X747424D01*
X748065Y526803D01*
X769783D01*
X771073Y525513D01*
G01X745502Y571476D02*
X747424D01*
X748065Y570835D01*
X780219D01*
X781475Y572091D01*
G01X745502Y569114D02*
X747424D01*
X748065Y569755D01*
X780211D01*
X781475Y568491D01*
G01X745502Y564390D02*
X747424D01*
X748065Y563749D01*
X769843D01*
X771073Y564979D01*
G01X745502Y562028D02*
X747424D01*
X748065Y562669D01*
X769783D01*
X771073Y561379D01*
G01X745502Y576201D02*
X747424D01*
X748065Y576842D01*
X769783D01*
X771073Y575552D01*
G01X745502Y578563D02*
X747424D01*
X748065Y577922D01*
X769843D01*
X771073Y579152D01*
G01X745502Y583288D02*
X747424D01*
X748065Y583929D01*
X780211D01*
X781475Y582665D01*
G01X745502Y585650D02*
X747424D01*
X748065Y585009D01*
X780219D01*
X781475Y586265D01*
G01X745502Y599823D02*
X747424D01*
X748065Y599182D01*
X780219D01*
X781475Y600438D01*
G01X745502Y592736D02*
X747424D01*
X748065Y592095D01*
X769843D01*
X771073Y593325D01*
G01X745502Y597461D02*
X747424D01*
X748065Y598102D01*
X780211D01*
X781475Y596838D01*
G01X745502Y590374D02*
X747424D01*
X748065Y591015D01*
X769783D01*
X771073Y589725D01*
G01X745502Y613996D02*
X747424D01*
X748065Y613355D01*
X780219D01*
X781475Y614611D01*
G01X745502Y606910D02*
X747424D01*
X748066Y606268D01*
X769842D01*
X771073Y607499D01*
G01X745502Y611634D02*
X747424D01*
X748065Y612275D01*
X780211D01*
X781475Y611011D01*
G01X745502Y604547D02*
X747425D01*
X748066Y605188D01*
X769784D01*
X771073Y603899D01*
G01X739948Y1353093D02*
X738688Y1351833D01*
Y1349347D01*
X739848Y1348187D01*
G01X736348Y1353093D02*
X737608Y1351833D01*
Y1349347D01*
X736448Y1348187D01*
G01X748588Y1353093D02*
X749848Y1351833D01*
Y1349347D01*
X748688Y1348187D01*
G01X736448Y1360099D02*
X737608Y1358939D01*
Y1356453D01*
X736348Y1355193D01*
G01X739848Y1360099D02*
X738688Y1358939D01*
Y1356453D01*
X739948Y1355193D01*
G01X748688Y1360099D02*
X749848Y1358939D01*
Y1356453D01*
X748588Y1355193D01*
G01Y1377291D02*
X749848Y1376031D01*
Y1373545D01*
X748688Y1372385D01*
G01Y1384297D02*
X749848Y1383137D01*
Y1380651D01*
X748588Y1379391D01*
G01X739948Y1377291D02*
X738688Y1376031D01*
Y1373545D01*
X739848Y1372385D01*
G01X736348Y1377291D02*
X737608Y1376031D01*
Y1373545D01*
X736448Y1372385D01*
G01X739848Y1384297D02*
X738688Y1383137D01*
Y1380651D01*
X739948Y1379391D01*
G01X736448Y1384297D02*
X737608Y1383137D01*
Y1380651D01*
X736348Y1379391D01*
G01X739948Y1401395D02*
X738688Y1400135D01*
Y1397649D01*
X739848Y1396489D01*
G01X736348Y1401395D02*
X737608Y1400135D01*
Y1397649D01*
X736448Y1396489D01*
G01X739848Y1408401D02*
X738688Y1407241D01*
Y1404755D01*
X739948Y1403495D01*
G01X736448Y1408401D02*
X737608Y1407241D01*
Y1404755D01*
X736348Y1403495D01*
G01X760828Y1353093D02*
X762088Y1351833D01*
Y1349347D01*
X760928Y1348187D01*
G01X764428Y1353093D02*
X763168Y1351833D01*
Y1349347D01*
X764328Y1348187D01*
G01X752188Y1353093D02*
X750928Y1351833D01*
Y1349347D01*
X752088Y1348187D01*
G01X764328Y1360099D02*
X763168Y1358939D01*
Y1356453D01*
X764428Y1355193D01*
G01X760928Y1360099D02*
X762088Y1358939D01*
Y1356453D01*
X760828Y1355193D01*
G01X752088Y1360099D02*
X750928Y1358939D01*
Y1356453D01*
X752188Y1355193D01*
G01Y1377291D02*
X750928Y1376031D01*
Y1373545D01*
X752088Y1372385D01*
G01Y1384297D02*
X750928Y1383137D01*
Y1380651D01*
X752188Y1379391D01*
G01X764428Y1377291D02*
X763168Y1376031D01*
Y1373545D01*
X764328Y1372385D01*
G01X760828Y1377291D02*
X762088Y1376031D01*
Y1373545D01*
X760928Y1372385D01*
G01X764328Y1384297D02*
X763168Y1383137D01*
Y1380651D01*
X764428Y1379391D01*
G01X760928Y1384297D02*
X762088Y1383137D01*
Y1380651D01*
X760828Y1379391D01*
G01X773173Y467206D02*
X774433Y468466D01*
X776919D01*
X778079Y467306D01*
G01X773173Y470806D02*
X774433Y469546D01*
X776919D01*
X778079Y470706D01*
G01X773173Y481379D02*
X774433Y482639D01*
X776919D01*
X778079Y481479D01*
G01X773173Y484979D02*
X774433Y483719D01*
X776919D01*
X778079Y484879D01*
G01X773173Y514939D02*
X774433Y513679D01*
X776919D01*
X778079Y514839D01*
G01X773173Y511339D02*
X774433Y512599D01*
X776919D01*
X778079Y511439D01*
G01X773173Y529113D02*
X774433Y527853D01*
X776919D01*
X778079Y529013D01*
G01X773173Y525513D02*
X774433Y526773D01*
X776919D01*
X778079Y525613D01*
G01X773173Y561379D02*
X774433Y562639D01*
X776919D01*
X778079Y561479D01*
G01X773173Y564979D02*
X774433Y563719D01*
X776919D01*
X778079Y564879D01*
G01X773173Y575552D02*
X774433Y576812D01*
X776919D01*
X778079Y575652D01*
G01X773173Y579152D02*
X774433Y577892D01*
X776919D01*
X778079Y579052D01*
G01X773173Y589725D02*
X774433Y590985D01*
X776919D01*
X778079Y589825D01*
G01X773173Y593325D02*
X774433Y592065D01*
X776919D01*
X778079Y593225D01*
G01X773173Y603899D02*
X774433Y605159D01*
X776919D01*
X778079Y603999D01*
G01X773173Y607499D02*
X774433Y606239D01*
X776919D01*
X778079Y607399D01*
G01X776668Y1353093D02*
X775408Y1351833D01*
Y1349347D01*
X776568Y1348187D01*
G01X773068Y1353093D02*
X774328Y1351833D01*
Y1349347D01*
X773168Y1348187D01*
G01Y1360099D02*
X774328Y1358939D01*
Y1356453D01*
X773068Y1355193D01*
G01X776568Y1360099D02*
X775408Y1358939D01*
Y1356453D01*
X776668Y1355193D01*
G01X806161Y133032D02*
X804281D01*
X803640Y133673D01*
X793719D01*
X792561Y132515D01*
G01X806161Y118859D02*
X804281D01*
X803640Y119500D01*
X793719D01*
X792561Y118342D01*
G01X806161Y121221D02*
X804261D01*
X803620Y120580D01*
X793723D01*
X792561Y121742D01*
G01X806161Y135394D02*
X804261D01*
X803620Y134753D01*
X793723D01*
X792561Y135915D01*
G01X783575Y477918D02*
X784835Y476658D01*
X787321D01*
X788481Y477818D01*
G01X783575Y488491D02*
X784835Y489751D01*
X787321D01*
X788481Y488591D01*
G01X783575Y474318D02*
X784835Y475578D01*
X787321D01*
X788481Y474418D01*
G01X783575Y492091D02*
X784835Y490831D01*
X787321D01*
X788481Y491991D01*
G01X783575Y518452D02*
X784835Y519712D01*
X787321D01*
X788481Y518552D01*
G01X783575Y522052D02*
X784835Y520792D01*
X787321D01*
X788481Y521952D01*
G01X783575Y532625D02*
X784835Y533885D01*
X787321D01*
X788481Y532725D01*
G01X783575Y536225D02*
X784835Y534965D01*
X787321D01*
X788481Y536125D01*
G01X783575Y572091D02*
X784835Y570831D01*
X787321D01*
X788481Y571991D01*
G01X783575Y568491D02*
X784835Y569751D01*
X787321D01*
X788481Y568591D01*
G01X783575Y586265D02*
X784835Y585005D01*
X787321D01*
X788481Y586165D01*
G01X783575Y582665D02*
X784835Y583925D01*
X787321D01*
X788481Y582765D01*
G01X783575Y600438D02*
X784835Y599178D01*
X787321D01*
X788481Y600338D01*
G01X783575Y596838D02*
X784835Y598098D01*
X787321D01*
X788481Y596938D01*
G01X783575Y614611D02*
X784835Y613351D01*
X787321D01*
X788481Y614511D01*
G01X783575Y611011D02*
X784835Y612271D01*
X787321D01*
X788481Y611111D01*
G01X806161Y114134D02*
Y114135D01*
X804275D01*
X803640Y113500D01*
X801016D01*
X799861Y114655D01*
G01X806161Y111772D02*
X804268D01*
X803620Y112420D01*
X801026D01*
X799861Y111255D01*
G01X806161Y128307D02*
X804274D01*
X803617Y127650D01*
X801039D01*
X799861Y128828D01*
G01X806161Y125945D02*
X804268D01*
X803643Y126570D01*
X801003D01*
X799861Y125428D01*
G01X833172Y111123D02*
X831875Y112420D01*
X826900D01*
X826252Y111772D01*
X824271D01*
G01X833172Y114723D02*
X831949Y113500D01*
X826872D01*
X826238Y114134D01*
X824271D01*
G01X831029Y104249D02*
X829878Y105400D01*
X826915D01*
X826200Y104685D01*
X824271D01*
G01X831029Y107649D02*
X829860Y106480D01*
X826821D01*
X826254Y107047D01*
X824271D01*
G01X833172Y125296D02*
X831948Y126520D01*
X826827D01*
X826252Y125945D01*
X824271D01*
G01X843574Y132409D02*
X842313Y133670D01*
X826905D01*
X826267Y133032D01*
X824271D01*
G01X833172Y128896D02*
X831876Y127600D01*
X826945D01*
X826238Y128307D01*
X824271D01*
G01X843574Y118235D02*
X842289Y119520D01*
X826913D01*
X826252Y118859D01*
X824271D01*
G01X843574Y121835D02*
X842339Y120600D01*
X826863D01*
X826242Y121221D01*
X824271D01*
G01X843574Y136009D02*
X842315Y134750D01*
X826895D01*
X826251Y135394D01*
X824271D01*
G01X845006Y-70022D02*
X845761D01*
X846205Y-70466D01*
X859190D01*
X863178Y-69763D01*
X863583Y-69185D01*
X861815Y-59150D01*
X863185Y-57185D01*
X867835Y-56366D01*
X869796Y-57738D01*
X874790Y-86056D01*
X876016Y-86914D01*
X879780Y-86249D01*
X880639Y-85022D01*
X876076Y-59137D01*
X877447Y-57176D01*
X877888Y-57098D01*
X877889D01*
X882097Y-56356D01*
X884056Y-57729D01*
X889047Y-86018D01*
X890271Y-86875D01*
X894035Y-86210D01*
X894894Y-84983D01*
X890332Y-59104D01*
X891703Y-57143D01*
X892144Y-57065D01*
X892145D01*
X896353Y-56323D01*
X898312Y-57696D01*
X903390Y-86476D01*
X904614Y-87333D01*
X908377Y-86669D01*
X909236Y-85441D01*
X904593Y-59099D01*
X905967Y-57138D01*
X910617Y-56317D01*
X912574Y-57690D01*
X917775Y-87189D01*
X919003Y-88049D01*
X922766Y-87385D01*
X923625Y-86157D01*
X918848Y-59056D01*
X920222Y-57095D01*
X924871Y-56273D01*
X926829Y-57646D01*
X931813Y-85919D01*
X933041Y-86778D01*
X936805Y-86114D01*
X937664Y-84887D01*
X933119Y-59108D01*
X934491Y-57153D01*
X939140Y-56331D01*
X941101Y-57703D01*
X946089Y-85967D01*
X947312Y-86824D01*
X951074Y-86160D01*
X951933Y-84933D01*
X947383Y-59122D01*
X948755Y-57164D01*
X953405Y-56343D01*
X955366Y-57715D01*
X957516Y-69913D01*
X958141Y-70438D01*
X973587D01*
X974031Y-69994D01*
X974786D01*
G01X845006Y-71990D02*
X845761D01*
X846205Y-71546D01*
X859285D01*
X863806Y-70750D01*
X864725Y-69439D01*
X862957Y-59402D01*
X863815Y-58172D01*
X867582Y-57508D01*
X868809Y-58367D01*
X873803Y-86685D01*
X875763Y-88056D01*
X880408Y-87235D01*
X881781Y-85276D01*
X877218Y-59390D01*
X878076Y-58162D01*
X881844Y-57498D01*
X883070Y-58357D01*
X888060Y-86647D01*
X890018Y-88017D01*
X894663Y-87196D01*
X896036Y-85237D01*
X891474Y-59357D01*
X892332Y-58129D01*
X896100Y-57465D01*
X897326Y-58324D01*
X902404Y-87104D01*
X904360Y-88475D01*
X909006Y-87656D01*
X910378Y-85694D01*
X905735Y-59352D01*
X906595Y-58124D01*
X910363Y-57459D01*
X911588Y-58318D01*
X916789Y-87817D01*
X918750Y-89191D01*
X923395Y-88372D01*
X924767Y-86410D01*
X919990Y-59309D01*
X920850Y-58081D01*
X924618Y-57415D01*
X925843Y-58274D01*
X930826Y-86548D01*
X932788Y-87920D01*
X937433Y-87100D01*
X938806Y-85141D01*
X934261Y-59362D01*
X935119Y-58139D01*
X938887Y-57473D01*
X940114Y-58332D01*
X945103Y-86595D01*
X947058Y-87966D01*
X951703Y-87147D01*
X953075Y-85186D01*
X948525Y-59375D01*
X949383Y-58150D01*
X953152Y-57485D01*
X954379Y-58344D01*
X956520Y-70488D01*
X957747Y-71518D01*
X973587D01*
X974031Y-71962D01*
X974786D01*
G01X840178Y114623D02*
X839055Y113500D01*
X836495D01*
X835272Y114723D01*
G01X840178Y111223D02*
X838981Y112420D01*
X836569D01*
X835272Y111123D01*
G01X850580Y118335D02*
X849415Y119500D01*
X846939D01*
X845674Y118235D01*
G01X850580Y132509D02*
X849419Y133670D01*
X846935D01*
X845674Y132409D01*
G01X850580Y121735D02*
X849425Y120580D01*
X846929D01*
X845674Y121835D01*
G01X840178Y128796D02*
X838982Y127600D01*
X836568D01*
X835272Y128896D01*
G01X840178Y125396D02*
X839054Y126520D01*
X836496D01*
X835272Y125296D01*
G01X850580Y135909D02*
X849421Y134750D01*
X846933D01*
X845674Y136009D01*
G01X903297Y233858D02*
X901321D01*
X900680Y234499D01*
X894444D01*
X893284Y233339D01*
G01X903297Y236221D02*
X901322D01*
X900680Y235579D01*
X894444D01*
X893284Y236739D01*
G01X904704Y309471D02*
X903740D01*
X903498Y309713D01*
X900505D01*
X899352Y308560D01*
G01X904704Y311046D02*
X903724D01*
X903421Y310743D01*
X900569D01*
X899352Y311960D01*
G01X909298Y302347D02*
X908113Y303532D01*
Y307533D01*
X908385Y307805D01*
Y309235D01*
G01X905898Y302347D02*
X907033Y303482D01*
Y307585D01*
X906811Y307807D01*
Y309235D01*
G01X906950Y322671D02*
Y317678D01*
X908163Y316465D01*
Y314517D01*
X908385Y314295D01*
Y312857D01*
G01X906950Y322671D02*
Y339125D01*
X908114Y340289D01*
G01X905870Y335995D02*
Y317230D01*
X907083Y316017D01*
Y314563D01*
X906811Y314291D01*
Y312857D01*
G01X908114Y343439D02*
X906904Y344649D01*
Y346076D01*
X909128Y348300D01*
X914449D01*
X916962Y350813D01*
Y352011D01*
X917406Y352455D01*
Y353756D01*
G01X904614Y343439D02*
X905824Y344649D01*
Y346524D01*
X908680Y349380D01*
X914001D01*
X915882Y351261D01*
Y352011D01*
X915437Y352456D01*
Y353756D01*
G01X905870Y335995D02*
Y339033D01*
X904614Y340289D01*
G01X915235Y326452D02*
X916118D01*
X917882Y328216D01*
G01X920752Y326452D02*
X919518D01*
X917882Y324816D01*
G01X931080Y313436D02*
X919264D01*
X917378Y315322D01*
Y319369D01*
X915235Y321512D01*
Y323302D01*
G01X918458Y317736D02*
Y319358D01*
X920752Y321652D01*
Y323302D01*
G01X918458Y317736D02*
Y315770D01*
X919712Y314516D01*
X921565D01*
X922105Y315056D01*
X923695D01*
X924235Y314516D01*
X925825D01*
X926365Y315056D01*
X927955D01*
X928495Y314516D01*
X930085D01*
X930625Y315056D01*
X932215D01*
X932755Y314516D01*
X935832D01*
X937000Y315684D01*
G01X915954Y344150D02*
X917226Y345422D01*
Y346354D01*
X919793Y348921D01*
Y352060D01*
X919374Y352479D01*
Y353755D01*
X919375Y353756D01*
G01X916229Y336333D02*
X917364Y335198D01*
Y333691D01*
X915235Y331562D01*
Y329602D01*
G01X919354Y344150D02*
X918306Y345198D01*
Y345906D01*
X920873Y348473D01*
Y352000D01*
X921343Y352470D01*
Y353756D01*
G01X920752Y329602D02*
Y331348D01*
X918444Y333656D01*
Y335148D01*
X919629Y336333D01*
G01X927964Y344041D02*
X926800Y345205D01*
Y352021D01*
X927249Y352470D01*
Y353756D01*
G01X924564Y344041D02*
X925720Y345197D01*
Y347147D01*
X925270Y347597D01*
Y349547D01*
X925720Y349997D01*
Y352039D01*
X925280Y352479D01*
Y353756D01*
G01X917589Y853166D02*
X919163Y851592D01*
G01X917589Y850016D02*
X919163Y848442D01*
G01X956161Y118859D02*
X954281D01*
X953640Y119500D01*
X943719D01*
X942561Y118342D01*
G01X956161Y133032D02*
X954281D01*
X953640Y133673D01*
X943719D01*
X942561Y132515D01*
G01X956161Y121221D02*
X954261D01*
X953620Y120580D01*
X943723D01*
X942561Y121742D01*
G01X956161Y135394D02*
X954261D01*
X953620Y134753D01*
X943723D01*
X942561Y135915D01*
G01X931080Y313436D02*
X935848D01*
X937000Y312284D01*
G01X943787Y330517D02*
Y328687D01*
X941580Y326480D01*
Y325195D01*
X942731Y324044D01*
G01X938287Y330517D02*
Y328719D01*
X940500Y326506D01*
Y325213D01*
X939331Y324044D01*
G01X942700Y346363D02*
X941500Y345163D01*
Y341270D01*
X943787Y338983D01*
Y336817D01*
G01X939300Y346363D02*
X940420Y345243D01*
Y341197D01*
X938287Y339064D01*
Y336817D01*
G01X940997Y331912D02*
X942752Y333667D01*
X943787D01*
G01X940997Y335312D02*
X939352Y333667D01*
X938287D01*
G01X956161Y111772D02*
X954268D01*
X953620Y112420D01*
X951026D01*
X949861Y111255D01*
G01X956161Y114134D02*
Y114135D01*
X954275D01*
X953640Y113500D01*
X951016D01*
X949861Y114655D01*
G01X956161Y125945D02*
X954268D01*
X953643Y126570D01*
X951003D01*
X949861Y125428D01*
G01X956161Y128307D02*
X954274D01*
X953617Y127650D01*
X951039D01*
X949861Y128828D01*
G01X947989Y899890D02*
X949449Y898430D01*
Y896077D01*
X947142Y893770D01*
Y887897D01*
X945982Y886737D01*
G01X951989Y899890D02*
X950529Y898430D01*
Y895629D01*
X948222Y893322D01*
Y887897D01*
X949382Y886737D01*
G01X983172Y114723D02*
X981949Y113500D01*
X976872D01*
X976238Y114134D01*
X974271D01*
G01X983172Y111123D02*
X981875Y112420D01*
X976900D01*
X976252Y111772D01*
X974271D01*
G01X981029Y104249D02*
X979878Y105400D01*
X976915D01*
X976200Y104685D01*
X974271D01*
G01X981029Y107649D02*
X979860Y106480D01*
X976821D01*
X976254Y107047D01*
X974271D01*
G01X993574Y121835D02*
X992339Y120600D01*
X976863D01*
X976242Y121221D01*
X974271D01*
G01X983172Y125296D02*
X981948Y126520D01*
X976827D01*
X976252Y125945D01*
X974271D01*
G01X993574Y132409D02*
X992313Y133670D01*
X976905D01*
X976267Y133032D01*
X974271D01*
G01X993574Y118235D02*
X992289Y119520D01*
X976913D01*
X976252Y118859D01*
X974271D01*
G01X983172Y128896D02*
X981876Y127600D01*
X976945D01*
X976238Y128307D01*
X974271D01*
G01X993574Y136009D02*
X992315Y134750D01*
X976895D01*
X976251Y135394D01*
X974271D01*
G01X990178Y114623D02*
X989055Y113500D01*
X986495D01*
X985272Y114723D01*
G01X990178Y111223D02*
X988981Y112420D01*
X986569D01*
X985272Y111123D01*
G01X990178Y128796D02*
X988982Y127600D01*
X986568D01*
X985272Y128896D01*
G01X990178Y125396D02*
X989054Y126520D01*
X986496D01*
X985272Y125296D01*
G01X1008506Y-32810D02*
X1011187Y-33526D01*
G01X1008506Y-30842D02*
X1011187Y-30126D01*
G01X1000580Y121735D02*
X999425Y120580D01*
X996929D01*
X995674Y121835D01*
G01X1000580Y118335D02*
X999415Y119500D01*
X996939D01*
X995674Y118235D01*
G01X1000580Y132509D02*
X999419Y133670D01*
X996935D01*
X995674Y132409D01*
G01X1000580Y135909D02*
X999421Y134750D01*
X996933D01*
X995674Y136009D01*
G01X1037386Y302676D02*
X1036080Y301370D01*
Y297503D01*
X1037290Y296293D01*
G01X1033890D02*
X1035000Y297403D01*
Y301435D01*
X1033786Y302649D01*
Y302676D01*
G01X1037386Y305826D02*
X1036101Y307111D01*
Y312499D01*
X1034676Y313924D01*
Y315103D01*
X1035145Y315572D01*
Y316659D01*
G01X1033786Y305826D02*
X1035021Y307061D01*
Y312051D01*
X1033596Y313476D01*
Y315157D01*
X1033177Y315576D01*
Y316659D01*
G01X1055650Y328156D02*
X1054365Y329441D01*
X1052241D01*
X1050263Y327463D01*
X1039158D01*
X1038689Y326994D01*
X1037606D01*
G01X1055650Y322843D02*
X1054365Y321558D01*
X1048741D01*
X1045743Y324556D01*
X1039162D01*
X1038693Y325025D01*
X1037606D01*
G01X1055650Y319243D02*
X1054415Y320478D01*
X1048293D01*
X1045295Y323476D01*
X1039108D01*
X1038689Y323057D01*
X1037606D01*
G01X1055650Y331756D02*
X1054415Y330521D01*
X1051793D01*
X1049815Y328543D01*
X1039212D01*
X1039162Y328493D01*
X1038693Y328962D01*
X1037606D01*
G01X1058523Y111772D02*
X1056630D01*
X1055982Y112420D01*
X1053388D01*
X1052223Y111255D01*
G01X1058523Y114134D02*
Y114135D01*
X1056637D01*
X1056002Y113500D01*
X1053378D01*
X1052223Y114655D01*
G01X1058523Y118859D02*
X1056643D01*
X1056002Y119500D01*
X1046081D01*
X1044923Y118342D01*
G01X1058523Y125945D02*
X1056630D01*
X1056005Y126570D01*
X1053365D01*
X1052223Y125428D01*
G01X1058523Y128307D02*
X1056636D01*
X1055979Y127650D01*
X1053401D01*
X1052223Y128828D01*
G01X1058523Y133032D02*
X1056643D01*
X1056002Y133673D01*
X1046081D01*
X1044923Y132515D01*
G01X1058523Y121221D02*
X1056623D01*
X1055982Y120580D01*
X1046085D01*
X1044923Y121742D01*
G01X1058523Y135394D02*
X1056623D01*
X1055982Y134753D01*
X1046085D01*
X1044923Y135915D01*
G01X1079748Y322743D02*
X1078563Y321558D01*
X1060085D01*
X1058800Y322843D01*
G01Y319243D02*
X1060035Y320478D01*
X1078613D01*
X1079748Y319343D01*
G01X1058800Y328156D02*
X1060064Y329420D01*
X1079187D01*
X1080351Y328256D01*
G01X1058800Y331756D02*
X1060056Y330500D01*
X1079195D01*
X1080351Y331656D01*
G01X1054863Y401513D02*
X1056076Y400300D01*
X1058456D01*
X1059769Y401613D01*
G01X1054863Y398113D02*
X1055970Y399220D01*
X1058562D01*
X1059769Y398013D01*
G01X1052463Y412287D02*
X1053596Y413420D01*
X1056136D01*
X1057369Y412187D01*
G01X1052463Y415687D02*
X1053650Y414500D01*
X1056082D01*
X1057369Y415787D01*
G01X1052463Y426460D02*
X1053623Y427620D01*
X1056109D01*
X1057369Y426360D01*
G01X1052463Y440633D02*
X1053650Y441820D01*
X1056082D01*
X1057369Y440533D01*
G01X1052463Y429860D02*
X1053623Y428700D01*
X1056109D01*
X1057369Y429960D01*
G01X1052463Y444033D02*
X1053596Y442900D01*
X1056136D01*
X1057369Y444133D01*
G01X1052463Y469387D02*
X1053596Y470520D01*
X1056136D01*
X1057369Y469287D01*
G01X1052463Y472787D02*
X1053650Y471600D01*
X1056082D01*
X1057369Y472887D01*
G01X1052463Y486960D02*
X1053623Y485800D01*
X1056109D01*
X1057369Y487060D01*
G01X1052463Y483560D02*
X1053622Y484720D01*
X1056109D01*
X1057369Y483460D01*
G01X1052463Y513521D02*
X1053589Y514647D01*
X1056143D01*
X1057369Y513421D01*
G01X1052463Y516921D02*
X1053657Y515727D01*
X1056075D01*
X1057369Y517021D01*
G01X1052463Y531094D02*
X1053657Y529900D01*
X1056075D01*
X1057369Y531194D01*
G01X1052463Y527694D02*
X1053589Y528820D01*
X1056143D01*
X1057369Y527594D01*
G01X1058213Y1353093D02*
X1056953Y1351833D01*
Y1349347D01*
X1058113Y1348187D01*
G01X1054613Y1353093D02*
X1055873Y1351833D01*
Y1349347D01*
X1054713Y1348187D01*
G01X1058213Y1355193D02*
X1056953Y1356453D01*
Y1358939D01*
X1058113Y1360099D01*
G01X1054613Y1355193D02*
X1055873Y1356453D01*
Y1358939D01*
X1054713Y1360099D01*
G01X1058213Y1377291D02*
X1056953Y1376031D01*
Y1373545D01*
X1058113Y1372385D01*
G01X1054613Y1377291D02*
X1055873Y1376031D01*
Y1373545D01*
X1054713Y1372385D01*
G01X1054613Y1379391D02*
X1055873Y1380651D01*
Y1383137D01*
X1054713Y1384297D01*
G01X1058213Y1379391D02*
X1056953Y1380651D01*
Y1383137D01*
X1058113Y1384297D01*
G01X1062865Y391001D02*
X1063984Y392120D01*
X1066552D01*
X1067771Y390901D01*
G01X1069871D02*
X1071090Y392120D01*
X1092859D01*
X1093463Y391516D01*
X1095442D01*
G01X1062865Y408574D02*
X1064039Y407400D01*
X1066497D01*
X1067771Y408674D01*
G01X1062865Y405174D02*
X1064011Y406320D01*
X1066525D01*
X1067771Y405074D01*
G01X1062865Y394401D02*
X1064066Y393200D01*
X1066470D01*
X1067771Y394501D01*
G01X1069871Y405074D02*
X1071117Y406320D01*
X1092832D01*
X1093463Y405689D01*
X1095442D01*
G01X1061869Y401613D02*
X1063134Y400348D01*
X1092826D01*
X1093443Y400965D01*
X1095442D01*
G01X1061869Y398013D02*
X1063124Y399268D01*
X1092810D01*
X1093476Y398602D01*
X1095442D01*
G01X1069871Y408674D02*
X1071145Y407400D01*
X1092796D01*
X1093447Y408051D01*
X1095442D01*
G01X1069871Y394501D02*
X1071172Y393200D01*
X1092769D01*
X1093447Y393878D01*
X1095442D01*
G01X1062865Y422747D02*
X1064012Y421600D01*
X1066524D01*
X1067771Y422847D01*
G01X1062865Y419347D02*
X1064038Y420520D01*
X1066498D01*
X1067771Y419247D01*
G01X1069871Y422847D02*
X1071118Y421600D01*
X1092823D01*
X1093447Y422224D01*
X1095442D01*
G01X1059469Y415787D02*
X1060756Y414500D01*
X1092824D01*
X1093462Y415138D01*
X1095442D01*
G01X1059469Y412187D02*
X1060702Y413420D01*
X1092832D01*
X1093476Y412776D01*
X1095442D01*
G01X1069871Y419247D02*
X1071144Y420520D01*
X1092805D01*
X1093463Y419862D01*
X1095442D01*
G01X1062865Y436921D02*
X1064006Y435780D01*
X1066530D01*
X1067771Y437021D01*
G01X1062865Y433521D02*
X1064044Y434700D01*
X1066492D01*
X1067771Y433421D01*
G01X1069871D02*
X1071070Y434620D01*
X1092879D01*
X1093463Y434036D01*
X1095442D01*
G01X1059469Y426360D02*
X1060729Y427620D01*
X1092805D01*
X1093476Y426949D01*
X1095442D01*
G01X1059469Y429960D02*
X1060729Y428700D01*
X1092851D01*
X1093462Y429311D01*
X1095442D01*
G01X1059469Y440533D02*
X1060656Y441720D01*
X1092878D01*
X1093476Y441122D01*
X1095442D01*
G01X1069871Y437021D02*
X1071192Y435700D01*
X1092749D01*
X1093447Y436398D01*
X1095442D01*
G01X1059469Y444133D02*
X1060802Y442800D01*
X1092778D01*
X1093462Y443484D01*
X1095442D01*
G01X1059469Y472887D02*
X1060758Y471598D01*
X1092781D01*
X1093447Y472264D01*
X1095442D01*
G01X1059469Y469287D02*
X1060700Y470518D01*
X1092847D01*
X1093463Y469902D01*
X1095442D01*
G01X1062865Y476499D02*
X1063986Y477620D01*
X1066550D01*
X1067771Y476399D01*
G01X1062865Y479899D02*
X1064064Y478700D01*
X1066472D01*
X1067771Y479999D01*
G01X1069871Y476399D02*
X1071092Y477620D01*
X1092844D01*
X1093476Y476988D01*
X1095442D01*
G01X1059469Y487060D02*
X1060758Y485771D01*
X1092781D01*
X1093447Y486437D01*
X1095442D01*
G01X1069871Y479999D02*
X1071170Y478700D01*
X1092812D01*
X1093462Y479350D01*
X1095442D01*
G01X1059469Y483460D02*
X1060700Y484691D01*
X1092847D01*
X1093463Y484075D01*
X1095442D01*
G01X1062865Y494073D02*
X1064038Y492900D01*
X1066498D01*
X1067771Y494173D01*
G01X1062865Y490673D02*
X1064012Y491820D01*
X1066524D01*
X1067771Y490573D01*
G01X1069871Y494173D02*
X1071144Y492900D01*
X1092838D01*
X1093462Y493524D01*
X1095442D01*
G01X1069871Y490573D02*
X1071118Y491820D01*
X1092818D01*
X1093476Y491162D01*
X1095442D01*
G01X1062865Y520633D02*
X1064032Y521800D01*
X1066504D01*
X1067771Y520533D01*
G01X1062865Y524033D02*
X1064018Y522880D01*
X1066518D01*
X1067771Y524133D01*
G01X1069871D02*
X1071124Y522880D01*
X1092858D01*
X1093462Y523484D01*
X1095442D01*
G01X1069871Y520533D02*
X1071138Y521800D01*
X1092798D01*
X1093476Y521122D01*
X1095442D01*
G01X1059469Y517021D02*
X1060758Y515732D01*
X1092781D01*
X1093447Y516398D01*
X1095442D01*
G01X1059469Y513421D02*
X1060700Y514652D01*
X1092847D01*
X1093463Y514036D01*
X1095442D01*
G01X1062865Y534806D02*
X1063959Y535900D01*
X1066577D01*
X1067771Y534706D01*
G01X1062865Y538206D02*
X1064091Y536980D01*
X1066445D01*
X1067771Y538306D01*
G01X1069871Y534706D02*
X1071165Y536000D01*
X1092771D01*
X1093476Y535295D01*
X1095442D01*
G01X1069871Y538306D02*
X1071097Y537080D01*
X1092957D01*
X1093535Y537658D01*
X1095442D01*
G01X1059469Y531194D02*
X1060758Y529905D01*
X1092781D01*
X1093447Y530571D01*
X1095442D01*
G01X1059469Y527594D02*
X1060700Y528825D01*
X1092847D01*
X1093463Y528209D01*
X1095442D01*
G01X1066853Y1353093D02*
X1068113Y1351833D01*
Y1349347D01*
X1066953Y1348187D01*
G01X1070453Y1353093D02*
X1069193Y1351833D01*
Y1349347D01*
X1070353Y1348187D01*
G01X1066853Y1355193D02*
X1068113Y1356453D01*
Y1358939D01*
X1066953Y1360099D01*
G01X1070453Y1355193D02*
X1069193Y1356453D01*
Y1358939D01*
X1070353Y1360099D01*
G01X1066853Y1379391D02*
X1068113Y1380651D01*
Y1383137D01*
X1066953Y1384297D01*
G01X1066853Y1377291D02*
X1068113Y1376031D01*
Y1373545D01*
X1066953Y1372385D01*
G01X1070453Y1377291D02*
X1069193Y1376031D01*
Y1373545D01*
X1070353Y1372385D01*
G01X1070453Y1379391D02*
X1069193Y1380651D01*
Y1383137D01*
X1070353Y1384297D01*
G01X1070453Y1401489D02*
X1069193Y1400229D01*
Y1397743D01*
X1070353Y1396583D01*
G01X1066853Y1401489D02*
X1068113Y1400229D01*
Y1397743D01*
X1066953Y1396583D01*
G01X1066853Y1403589D02*
X1068113Y1404849D01*
Y1407335D01*
X1066953Y1408495D01*
G01X1070453Y1403589D02*
X1069193Y1404849D01*
Y1407335D01*
X1070353Y1408495D01*
G01X1078506Y-71990D02*
X1081187Y-72706D01*
G01X1078506Y-70022D02*
X1081187Y-69306D01*
G01X1092540Y111223D02*
X1091343Y112420D01*
X1088931D01*
X1087634Y111123D01*
G01X1092540Y114623D02*
X1091417Y113500D01*
X1088857D01*
X1087634Y114723D01*
G01X1085534D02*
X1084311Y113500D01*
X1079234D01*
X1078600Y114134D01*
X1076633D01*
G01X1085534Y111123D02*
X1084237Y112420D01*
X1079262D01*
X1078614Y111772D01*
X1076633D01*
G01X1083391Y104249D02*
X1082240Y105400D01*
X1079277D01*
X1078562Y104685D01*
X1076633D01*
G01X1083391Y107649D02*
X1082222Y106480D01*
X1079183D01*
X1078616Y107047D01*
X1076633D01*
G01X1092540Y128796D02*
X1091344Y127600D01*
X1088930D01*
X1087634Y128896D01*
G01X1092540Y125396D02*
X1091416Y126520D01*
X1088858D01*
X1087634Y125296D01*
G01X1085534Y128896D02*
X1084238Y127600D01*
X1079307D01*
X1078600Y128307D01*
X1076633D01*
G01X1085534Y125296D02*
X1084310Y126520D01*
X1079189D01*
X1078614Y125945D01*
X1076633D01*
G01X1095936Y132409D02*
X1094675Y133670D01*
X1079267D01*
X1078629Y133032D01*
X1076633D01*
G01X1095936Y121835D02*
X1094701Y120600D01*
X1079225D01*
X1078604Y121221D01*
X1076633D01*
G01X1095936Y118235D02*
X1094651Y119520D01*
X1079275D01*
X1078614Y118859D01*
X1076633D01*
G01X1095936Y136009D02*
X1094677Y134750D01*
X1079257D01*
X1078613Y135394D01*
X1076633D01*
G01X1089096Y541863D02*
X1090153Y542920D01*
X1092958D01*
X1093496Y542382D01*
X1095442D01*
G01X1089096Y545263D02*
X1090359Y544000D01*
X1092976D01*
X1093720Y544744D01*
X1095442D01*
G01X1091333Y1353093D02*
X1092593Y1351833D01*
Y1349347D01*
X1091433Y1348187D01*
G01X1082693Y1353093D02*
X1081433Y1351833D01*
Y1349347D01*
X1082593Y1348187D01*
G01X1079093Y1353093D02*
X1080353Y1351833D01*
Y1349347D01*
X1079193Y1348187D01*
G01X1091333Y1355193D02*
X1092593Y1356453D01*
Y1358939D01*
X1091433Y1360099D01*
G01X1082693Y1355193D02*
X1081433Y1356453D01*
Y1358939D01*
X1082593Y1360099D01*
G01X1079093Y1355193D02*
X1080353Y1356453D01*
Y1358939D01*
X1079193Y1360099D01*
G01X1079093Y1377291D02*
X1080353Y1376031D01*
Y1373545D01*
X1079193Y1372385D01*
G01X1082693Y1377291D02*
X1081433Y1376031D01*
Y1373545D01*
X1082593Y1372385D01*
G01X1082693Y1379391D02*
X1081433Y1380651D01*
Y1383137D01*
X1082593Y1384297D01*
G01X1079093Y1379391D02*
X1080353Y1380651D01*
Y1383137D01*
X1079193Y1384297D01*
G01X1091333Y1379391D02*
X1092593Y1380651D01*
Y1383137D01*
X1091433Y1384297D01*
G01X1091333Y1377291D02*
X1092593Y1376031D01*
Y1373545D01*
X1091433Y1372385D01*
G01X1091333Y1401489D02*
X1092593Y1400229D01*
Y1397743D01*
X1091433Y1396583D01*
G01X1082693Y1401489D02*
X1081433Y1400229D01*
Y1397743D01*
X1082593Y1396583D01*
G01X1079093Y1401489D02*
X1080353Y1400229D01*
Y1397743D01*
X1079193Y1396583D01*
G01X1091333Y1403589D02*
X1092593Y1404849D01*
Y1407335D01*
X1091433Y1408495D01*
G01X1082693Y1403589D02*
X1081433Y1404849D01*
Y1407335D01*
X1082593Y1408495D01*
G01X1079093Y1403589D02*
X1080353Y1404849D01*
Y1407335D01*
X1079193Y1408495D01*
G01X1102942Y118335D02*
X1101777Y119500D01*
X1099301D01*
X1098036Y118235D01*
G01X1102942Y132509D02*
X1101781Y133670D01*
X1099297D01*
X1098036Y132409D01*
G01X1102942Y121735D02*
X1101787Y120580D01*
X1099291D01*
X1098036Y121835D01*
G01X1102942Y135909D02*
X1101783Y134750D01*
X1099295D01*
X1098036Y136009D01*
G01X1094933Y1353093D02*
X1093673Y1351833D01*
Y1349347D01*
X1094833Y1348187D01*
G01X1107173Y1353093D02*
X1105913Y1351833D01*
Y1349347D01*
X1107073Y1348187D01*
G01X1103573Y1353093D02*
X1104833Y1351833D01*
Y1349347D01*
X1103673Y1348187D01*
G01X1094933Y1355193D02*
X1093673Y1356453D01*
Y1358939D01*
X1094833Y1360099D01*
G01X1103573Y1355193D02*
X1104833Y1356453D01*
Y1358939D01*
X1103673Y1360099D01*
G01X1107173Y1355193D02*
X1105913Y1356453D01*
Y1358939D01*
X1107073Y1360099D01*
G01X1107173Y1377291D02*
X1105913Y1376031D01*
Y1373545D01*
X1107073Y1372385D01*
G01X1103573Y1377291D02*
X1104833Y1376031D01*
Y1373545D01*
X1103673Y1372385D01*
G01X1107173Y1379391D02*
X1105913Y1380651D01*
Y1383137D01*
X1107073Y1384297D01*
G01X1103573Y1379391D02*
X1104833Y1380651D01*
Y1383137D01*
X1103673Y1384297D01*
G01X1094933Y1379391D02*
X1093673Y1380651D01*
Y1383137D01*
X1094833Y1384297D01*
G01X1094933Y1377291D02*
X1093673Y1376031D01*
Y1373545D01*
X1094833Y1372385D01*
G01X1094933Y1401489D02*
X1093673Y1400229D01*
Y1397743D01*
X1094833Y1396583D01*
G01X1107173Y1401489D02*
X1105913Y1400229D01*
Y1397743D01*
X1107073Y1396583D01*
G01X1103573Y1401489D02*
X1104833Y1400229D01*
Y1397743D01*
X1103673Y1396583D01*
G01X1094933Y1403589D02*
X1093673Y1404849D01*
Y1407335D01*
X1094833Y1408495D01*
G01X1107173Y1403589D02*
X1105913Y1404849D01*
Y1407335D01*
X1107073Y1408495D01*
G01X1103573Y1403589D02*
X1104833Y1404849D01*
Y1407335D01*
X1103673Y1408495D01*
G01X1127153Y390995D02*
X1126028Y392120D01*
X1116057D01*
X1115453Y391516D01*
X1113553D01*
G01X1127153Y408568D02*
X1125965Y407380D01*
X1116104D01*
X1115433Y408051D01*
X1113553D01*
G01X1127153Y405168D02*
X1126021Y406300D01*
X1116064D01*
X1115453Y405689D01*
X1113553D01*
G01X1127153Y394395D02*
X1125958Y393200D01*
X1116111D01*
X1115433Y393878D01*
X1113553D01*
G01Y398602D02*
X1115439D01*
X1116057Y399220D01*
X1118715D01*
X1119853Y398082D01*
G01Y401482D02*
X1118671Y400300D01*
X1116111D01*
X1115446Y400965D01*
X1113553D01*
G01X1119853Y412255D02*
X1118688Y413420D01*
X1116084D01*
X1115440Y412776D01*
X1113553D01*
G01X1127153Y422741D02*
X1126012Y421600D01*
X1116057D01*
X1115433Y422224D01*
X1113553D01*
G01X1127153Y419341D02*
X1125974Y420520D01*
X1116111D01*
X1115453Y419862D01*
X1113553D01*
G01X1119853Y415655D02*
X1118698Y414500D01*
X1116084D01*
X1115446Y415138D01*
X1113553D01*
G01X1119853Y440602D02*
X1118655Y441800D01*
X1116117D01*
X1115439Y441122D01*
X1113553D01*
G01X1119853Y426428D02*
X1118661Y427620D01*
X1116111D01*
X1115440Y426949D01*
X1113553D01*
G01X1127153Y436915D02*
X1125938Y435700D01*
X1116131D01*
X1115433Y436398D01*
X1113553D01*
G01X1127153Y433515D02*
X1126048Y434620D01*
X1116037D01*
X1115453Y434036D01*
X1113553D01*
G01X1119853Y429828D02*
X1118725Y428700D01*
X1116057D01*
X1115446Y429311D01*
X1113553D01*
G01X1119853Y444002D02*
X1118731Y442880D01*
X1116051D01*
X1115447Y443484D01*
X1113553D01*
G01X1127153Y472781D02*
X1125972Y471600D01*
X1116101D01*
X1115437Y472264D01*
X1113553D01*
G01X1127153Y469381D02*
X1126014Y470520D01*
X1116071D01*
X1115453Y469902D01*
X1113553D01*
G01X1119853Y476468D02*
X1118701Y477620D01*
X1116071D01*
X1115439Y476988D01*
X1113553D01*
G01X1127153Y486954D02*
X1125999Y485800D01*
X1116070D01*
X1115433Y486437D01*
X1113553D01*
G01X1119853Y479868D02*
X1118685Y478700D01*
X1116097D01*
X1115447Y479350D01*
X1113553D01*
G01X1127153Y483554D02*
X1125987Y484720D01*
X1116098D01*
X1115453Y484075D01*
X1113553D01*
G01X1119853Y490641D02*
X1118674Y491820D01*
X1116098D01*
X1115440Y491162D01*
X1113553D01*
G01X1119853Y494041D02*
X1118712Y492900D01*
X1116070D01*
X1115446Y493524D01*
X1113553D01*
G01X1127153Y516915D02*
X1125938Y515700D01*
X1116131D01*
X1115433Y516398D01*
X1113553D01*
G01X1119853Y524002D02*
X1118667Y522816D01*
X1116115D01*
X1115447Y523484D01*
X1113553D01*
G01X1127153Y513515D02*
X1126048Y514620D01*
X1116037D01*
X1115453Y514036D01*
X1113553D01*
G01X1119853Y520602D02*
X1118719Y521736D01*
X1116053D01*
X1115439Y521122D01*
X1113553D01*
G01X1119853Y538175D02*
X1118658Y536980D01*
X1116124D01*
X1115446Y537658D01*
X1113553D01*
G01X1119853Y534775D02*
X1118728Y535900D01*
X1116044D01*
X1115439Y535295D01*
X1113553D01*
G01X1127153Y527688D02*
X1125941Y528900D01*
X1116144D01*
X1115453Y528209D01*
X1113553D01*
G01X1127153Y531088D02*
X1126045Y529980D01*
X1116024D01*
X1115433Y530571D01*
X1113553D01*
G01X1115813Y1353093D02*
X1117073Y1351833D01*
Y1349347D01*
X1115913Y1348187D01*
G01X1119413Y1353093D02*
X1118153Y1351833D01*
Y1349347D01*
X1119313Y1348187D01*
G01X1115813Y1355193D02*
X1117073Y1356453D01*
Y1358939D01*
X1115913Y1360099D01*
G01X1119413Y1355193D02*
X1118153Y1356453D01*
Y1358939D01*
X1119313Y1360099D01*
G01X1119413Y1379391D02*
X1118153Y1380651D01*
Y1383137D01*
X1119313Y1384297D01*
G01X1115813Y1377291D02*
X1117073Y1376031D01*
Y1373545D01*
X1115913Y1372385D01*
G01X1119413Y1377291D02*
X1118153Y1376031D01*
Y1373545D01*
X1119313Y1372385D01*
G01X1115813Y1379391D02*
X1117073Y1380651D01*
Y1383137D01*
X1115913Y1384297D01*
G01X1115813Y1401489D02*
X1117073Y1400229D01*
Y1397743D01*
X1115913Y1396583D01*
G01X1119413Y1401489D02*
X1118153Y1400229D01*
Y1397743D01*
X1119313Y1396583D01*
G01X1115813Y1403589D02*
X1117073Y1404849D01*
Y1407335D01*
X1115913Y1408495D01*
G01X1119413Y1403589D02*
X1118153Y1404849D01*
Y1407335D01*
X1119313Y1408495D01*
G01X1131653Y1353093D02*
X1130393Y1351833D01*
Y1349347D01*
X1131553Y1348187D01*
G01X1128053Y1353093D02*
X1129313Y1351833D01*
Y1349347D01*
X1128153Y1348187D01*
G01X1131653Y1355193D02*
X1130393Y1356453D01*
Y1358939D01*
X1131553Y1360099D01*
G01X1128053Y1355193D02*
X1129313Y1356453D01*
Y1358939D01*
X1128153Y1360099D01*
G01X1128053Y1379391D02*
X1129313Y1380651D01*
Y1383137D01*
X1128153Y1384297D01*
G01X1131653Y1379391D02*
X1130393Y1380651D01*
Y1383137D01*
X1131553Y1384297D01*
G01X1128053Y1377291D02*
X1129313Y1376031D01*
Y1373545D01*
X1128153Y1372385D01*
G01X1131653Y1377291D02*
X1130393Y1376031D01*
Y1373545D01*
X1131553Y1372385D01*
G01X1131653Y1401489D02*
X1130393Y1400229D01*
Y1397743D01*
X1131553Y1396583D01*
G01X1128053Y1401489D02*
X1129313Y1400229D01*
Y1397743D01*
X1128153Y1396583D01*
G01X1128053Y1403589D02*
X1129313Y1404849D01*
Y1407335D01*
X1128153Y1408495D01*
G01X1131653Y1403589D02*
X1130393Y1404849D01*
Y1407335D01*
X1131553Y1408495D01*
G01X1160885Y114134D02*
Y114135D01*
X1158999D01*
X1158364Y113500D01*
X1155740D01*
X1154585Y114655D01*
G01X1160885Y111772D02*
X1158992D01*
X1158344Y112420D01*
X1155750D01*
X1154585Y111255D01*
G01X1160885Y128307D02*
X1158998D01*
X1158341Y127650D01*
X1155763D01*
X1154585Y128828D01*
G01X1160885Y118859D02*
X1159005D01*
X1158364Y119500D01*
X1148443D01*
X1147285Y118342D01*
G01X1160885Y121221D02*
X1158985D01*
X1158344Y120580D01*
X1148447D01*
X1147285Y121742D01*
G01X1160885Y133032D02*
X1159005D01*
X1158364Y133673D01*
X1148443D01*
X1147285Y132515D01*
G01X1160885Y125945D02*
X1158992D01*
X1158367Y126570D01*
X1155727D01*
X1154585Y125428D01*
G01X1160885Y135394D02*
X1158985D01*
X1158344Y134753D01*
X1148447D01*
X1147285Y135915D01*
G01X1150885Y1211712D02*
X1149015Y1213582D01*
G01X1150885Y1215452D02*
X1149015Y1217322D01*
G01X1140293Y1353093D02*
X1141553Y1351833D01*
Y1349347D01*
X1140393Y1348187D01*
G01X1143893Y1353093D02*
X1142633Y1351833D01*
Y1349347D01*
X1143793Y1348187D01*
G01X1156133Y1353093D02*
X1154873Y1351833D01*
Y1349347D01*
X1156033Y1348187D01*
G01X1152533Y1353093D02*
X1153793Y1351833D01*
Y1349347D01*
X1152633Y1348187D01*
G01X1140293Y1355193D02*
X1141553Y1356453D01*
Y1358939D01*
X1140393Y1360099D01*
G01X1143893Y1355193D02*
X1142633Y1356453D01*
Y1358939D01*
X1143793Y1360099D01*
G01X1152533Y1355193D02*
X1153793Y1356453D01*
Y1358939D01*
X1152633Y1360099D01*
G01X1156133Y1355193D02*
X1154873Y1356453D01*
Y1358939D01*
X1156033Y1360099D01*
G01X1156133Y1379391D02*
X1154873Y1380651D01*
Y1383137D01*
X1156033Y1384297D01*
G01X1152533Y1379391D02*
X1153793Y1380651D01*
Y1383137D01*
X1152633Y1384297D01*
G01X1156133Y1377291D02*
X1154873Y1376031D01*
Y1373545D01*
X1156033Y1372385D01*
G01X1152533Y1377291D02*
X1153793Y1376031D01*
Y1373545D01*
X1152633Y1372385D01*
G01X1140293Y1379391D02*
X1141553Y1380651D01*
Y1383137D01*
X1140393Y1384297D01*
G01X1143893Y1377291D02*
X1142633Y1376031D01*
Y1373545D01*
X1143793Y1372385D01*
G01X1140293Y1377291D02*
X1141553Y1376031D01*
Y1373545D01*
X1140393Y1372385D01*
G01X1143893Y1379391D02*
X1142633Y1380651D01*
Y1383137D01*
X1143793Y1384297D01*
G01X1143893Y1401489D02*
X1142633Y1400229D01*
Y1397743D01*
X1143793Y1396583D01*
G01X1140293Y1401489D02*
X1141553Y1400229D01*
Y1397743D01*
X1140393Y1396583D01*
G01X1156133Y1401489D02*
X1154873Y1400229D01*
Y1397743D01*
X1156033Y1396583D01*
G01X1152533Y1401489D02*
X1153793Y1400229D01*
Y1397743D01*
X1152633Y1396583D01*
G01X1143893Y1403589D02*
X1142633Y1404849D01*
Y1407335D01*
X1143793Y1408495D01*
G01X1140293Y1403589D02*
X1141553Y1404849D01*
Y1407335D01*
X1140393Y1408495D01*
G01X1152533Y1403589D02*
X1153793Y1404849D01*
Y1407335D01*
X1152633Y1408495D01*
G01X1156133Y1403589D02*
X1154873Y1404849D01*
Y1407335D01*
X1156033Y1408495D01*
G01X1184478Y474941D02*
X1182598D01*
X1181969Y475570D01*
X1172024D01*
X1170878Y474424D01*
G01X1184478Y477303D02*
X1182578D01*
X1181925Y476650D01*
X1172052D01*
X1170878Y477824D01*
G01X1184478Y489114D02*
X1182598D01*
X1181992Y489720D01*
X1172001D01*
X1170878Y488597D01*
G01X1184478Y491476D02*
X1182578D01*
X1181902Y490800D01*
X1172075D01*
X1170878Y491997D01*
G01X1184478Y519075D02*
X1182598D01*
X1181953Y519720D01*
X1172040D01*
X1170878Y518558D01*
G01X1184478Y521437D02*
X1182578D01*
X1181941Y520800D01*
X1172036D01*
X1170878Y521958D01*
G01X1184478Y533248D02*
X1182598D01*
X1181976Y533870D01*
X1172017D01*
X1170878Y532731D01*
G01X1184478Y535610D02*
X1182578D01*
X1181918Y534950D01*
X1172059D01*
X1170878Y536131D01*
G01Y571997D02*
X1172075Y570800D01*
X1181902D01*
X1182578Y571476D01*
X1184478D01*
G01X1170878Y568597D02*
X1172001Y569720D01*
X1181992D01*
X1182598Y569114D01*
X1184478D01*
G01X1170878Y586171D02*
X1172049Y585000D01*
X1181928D01*
X1182578Y585650D01*
X1184478D01*
G01X1170878Y582771D02*
X1172027Y583920D01*
X1181966D01*
X1182598Y583288D01*
X1184478D01*
G01X1170878Y596944D02*
X1172054Y598120D01*
X1181939D01*
X1182598Y597461D01*
X1184478D01*
G01X1170878Y600344D02*
X1172022Y599200D01*
X1181955D01*
X1182578Y599823D01*
X1184478D01*
G01Y613996D02*
X1182578D01*
X1181982Y613400D01*
X1171995D01*
X1170878Y614517D01*
G01X1184478Y611634D02*
X1182598D01*
X1181912Y612320D01*
X1172081D01*
X1170878Y611117D01*
G01X1168373Y1353093D02*
X1167113Y1351833D01*
Y1349347D01*
X1168273Y1348187D01*
G01X1164773Y1353093D02*
X1166033Y1351833D01*
Y1349347D01*
X1164873Y1348187D01*
G01X1164773Y1355193D02*
X1166033Y1356453D01*
Y1358939D01*
X1164873Y1360099D01*
G01X1168373Y1355193D02*
X1167113Y1356453D01*
Y1358939D01*
X1168273Y1360099D01*
G01X1168373Y1379391D02*
X1167113Y1380651D01*
Y1383137D01*
X1168273Y1384297D01*
G01X1164773Y1379391D02*
X1166033Y1380651D01*
Y1383137D01*
X1164873Y1384297D01*
G01X1168373Y1377291D02*
X1167113Y1376031D01*
Y1373545D01*
X1168273Y1372385D01*
G01X1164773Y1377291D02*
X1166033Y1376031D01*
Y1373545D01*
X1164873Y1372385D01*
G01X1164773Y1401489D02*
X1166033Y1400229D01*
Y1397743D01*
X1164873Y1396583D01*
G01X1168373Y1401489D02*
X1167113Y1400229D01*
Y1397743D01*
X1168273Y1396583D01*
G01X1168373Y1403589D02*
X1167113Y1404849D01*
Y1407335D01*
X1168273Y1408495D01*
G01X1164773Y1403589D02*
X1166033Y1404849D01*
Y1407335D01*
X1164873Y1408495D01*
G01X1187896Y111123D02*
X1186599Y112420D01*
X1181624D01*
X1180976Y111772D01*
X1178995D01*
G01X1187896Y114723D02*
X1186673Y113500D01*
X1181596D01*
X1180962Y114134D01*
X1178995D01*
G01X1185753Y107649D02*
X1184584Y106480D01*
X1181545D01*
X1180978Y107047D01*
X1178995D01*
G01X1185753Y104249D02*
X1184602Y105400D01*
X1181639D01*
X1180924Y104685D01*
X1178995D01*
G01X1187896Y128896D02*
X1186600Y127600D01*
X1181669D01*
X1180962Y128307D01*
X1178995D01*
G01X1187896Y125296D02*
X1186672Y126520D01*
X1181551D01*
X1180976Y125945D01*
X1178995D01*
G01X1198298Y132409D02*
X1197037Y133670D01*
X1181629D01*
X1180991Y133032D01*
X1178995D01*
G01X1198298Y121835D02*
X1197063Y120600D01*
X1181587D01*
X1180966Y121221D01*
X1178995D01*
G01X1198298Y118235D02*
X1197013Y119520D01*
X1181637D01*
X1180976Y118859D01*
X1178995D01*
G01X1198298Y136009D02*
X1197039Y134750D01*
X1181619D01*
X1180975Y135394D01*
X1178995D01*
G01X1184478Y467854D02*
X1182585D01*
X1181916Y468523D01*
X1179364D01*
X1178178Y467337D01*
G01X1184478Y470217D02*
X1182592D01*
X1181978Y469603D01*
X1179312D01*
X1178178Y470737D01*
G01Y484910D02*
X1179338Y483750D01*
X1181952D01*
X1182592Y484390D01*
X1184478D01*
G01X1178178Y481510D02*
X1179338Y482670D01*
X1181942D01*
X1182584Y482028D01*
X1184478D01*
G01Y511988D02*
X1182585D01*
X1181923Y512650D01*
X1179357D01*
X1178178Y511471D01*
G01X1184478Y514350D02*
X1182591D01*
X1181971Y513730D01*
X1179319D01*
X1178178Y514871D01*
G01X1184478Y528524D02*
X1182592D01*
X1181948Y527880D01*
X1179342D01*
X1178178Y529044D01*
G01X1184478Y526162D02*
X1182584D01*
X1181946Y526800D01*
X1179334D01*
X1178178Y525644D01*
G01Y564910D02*
X1179388Y563700D01*
X1181900D01*
X1182590Y564390D01*
X1184478D01*
G01X1178178Y561510D02*
X1179288Y562620D01*
X1181992D01*
X1182584Y562028D01*
X1184478D01*
G01X1178178Y579084D02*
X1179362Y577900D01*
X1181900D01*
X1182563Y578563D01*
X1184478D01*
G01X1178178Y575684D02*
X1179314Y576820D01*
X1181966D01*
X1182585Y576201D01*
X1184478D01*
G01X1178178Y604030D02*
X1179368Y605220D01*
X1181912D01*
X1182585Y604547D01*
X1184478D01*
G01X1178178Y593257D02*
X1179335Y592100D01*
X1181955D01*
X1182591Y592736D01*
X1184478D01*
G01X1178178Y589857D02*
X1179341Y591020D01*
X1181939D01*
X1182585Y590374D01*
X1184478D01*
G01X1178178Y607430D02*
X1179308Y606300D01*
X1181982D01*
X1182592Y606910D01*
X1184478D01*
G01X1177013Y1353093D02*
X1178273Y1351833D01*
Y1349347D01*
X1177113Y1348187D01*
G01X1180613Y1353093D02*
X1179353Y1351833D01*
Y1349347D01*
X1180513Y1348187D01*
G01X1177013Y1355193D02*
X1178273Y1356453D01*
Y1358939D01*
X1177113Y1360099D01*
G01X1180613Y1355193D02*
X1179353Y1356453D01*
Y1358939D01*
X1180513Y1360099D01*
G01X1177013Y1379391D02*
X1178273Y1380651D01*
Y1383137D01*
X1177113Y1384297D01*
G01X1180613Y1379391D02*
X1179353Y1380651D01*
Y1383137D01*
X1180513Y1384297D01*
G01X1177013Y1377291D02*
X1178273Y1376031D01*
Y1373545D01*
X1177113Y1372385D01*
G01X1180613Y1377291D02*
X1179353Y1376031D01*
Y1373545D01*
X1180513Y1372385D01*
G01X1180613Y1401489D02*
X1179353Y1400229D01*
Y1397743D01*
X1180513Y1396583D01*
G01X1177013Y1401489D02*
X1178273Y1400229D01*
Y1397743D01*
X1177113Y1396583D01*
G01X1177013Y1403589D02*
X1178273Y1404849D01*
Y1407335D01*
X1177113Y1408495D01*
G01X1180613Y1403589D02*
X1179353Y1404849D01*
Y1407335D01*
X1180513Y1408495D01*
G01X1194902Y114623D02*
X1193779Y113500D01*
X1191219D01*
X1189996Y114723D01*
G01X1194902Y111223D02*
X1193705Y112420D01*
X1191293D01*
X1189996Y111123D01*
G01X1205304Y118335D02*
X1204139Y119500D01*
X1201663D01*
X1200398Y118235D01*
G01X1205304Y121735D02*
X1204149Y120580D01*
X1201653D01*
X1200398Y121835D01*
G01X1194902Y128796D02*
X1193706Y127600D01*
X1191292D01*
X1189996Y128896D01*
G01X1205304Y132509D02*
X1204143Y133670D01*
X1201659D01*
X1200398Y132409D01*
G01X1194902Y125396D02*
X1193778Y126520D01*
X1191220D01*
X1189996Y125296D01*
G01X1205304Y135909D02*
X1204145Y134750D01*
X1201657D01*
X1200398Y136009D01*
G01X1228160Y470806D02*
X1226904Y469550D01*
X1205222D01*
X1204555Y470217D01*
X1202589D01*
G01X1228160Y467206D02*
X1226896Y468470D01*
X1205112D01*
X1204496Y467854D01*
X1202589D01*
G01X1209184Y463618D02*
X1208096Y462530D01*
X1205120D01*
X1204520Y463130D01*
X1202589D01*
G01X1209184Y460218D02*
X1207952Y461450D01*
X1205092D01*
X1204410Y460768D01*
X1202589D01*
G01X1228160Y481379D02*
X1226919Y482620D01*
X1205161D01*
X1204569Y482028D01*
X1202589D01*
G01X1238562Y474318D02*
X1237310Y475570D01*
X1205213D01*
X1204584Y474941D01*
X1202589D01*
G01X1238562Y477918D02*
X1237294Y476650D01*
X1205221D01*
X1204568Y477303D01*
X1202589D01*
G01X1228160Y484979D02*
X1226881Y483700D01*
X1205245D01*
X1204555Y484390D01*
X1202589D01*
G01X1238562Y488491D02*
X1237333Y489720D01*
X1205190D01*
X1204584Y489114D01*
X1202589D01*
G01X1238562Y492091D02*
X1237271Y490800D01*
X1205244D01*
X1204568Y491476D01*
X1202589D01*
G01X1228160Y511339D02*
X1226879Y512620D01*
X1205201D01*
X1204569Y511988D01*
X1202589D01*
G01X1238562Y518452D02*
X1237294Y519720D01*
X1205229D01*
X1204584Y519075D01*
X1202589D01*
G01X1238562Y522052D02*
X1237310Y520800D01*
X1205205D01*
X1204568Y521437D01*
X1202589D01*
G01X1228160Y514939D02*
X1226921Y513700D01*
X1205205D01*
X1204555Y514350D01*
X1202589D01*
G01X1238562Y536225D02*
X1237287Y534950D01*
X1205228D01*
X1204568Y535610D01*
X1202589D01*
G01X1228160Y525513D02*
X1226873Y526800D01*
X1205207D01*
X1204569Y526162D01*
X1202589D01*
G01X1238562Y532625D02*
X1237317Y533870D01*
X1205206D01*
X1204584Y533248D01*
X1202589D01*
G01X1228160Y529113D02*
X1226927Y527880D01*
X1205199D01*
X1204555Y528524D01*
X1202589D01*
G01X1228160Y564979D02*
X1226905Y563724D01*
X1205221D01*
X1204555Y564390D01*
X1202589D01*
G01X1238562Y568491D02*
X1237303Y569750D01*
X1205220D01*
X1204584Y569114D01*
X1202589D01*
G01X1238562Y572091D02*
X1237301Y570830D01*
X1205214D01*
X1204568Y571476D01*
X1202589D01*
G01X1228160Y561379D02*
X1226895Y562644D01*
X1205185D01*
X1204569Y562028D01*
X1202589D01*
G01X1228160Y575552D02*
X1226892Y576820D01*
X1205188D01*
X1204569Y576201D01*
X1202589D01*
G01X1238562Y586265D02*
X1237297Y585000D01*
X1205218D01*
X1204568Y585650D01*
X1202589D01*
G01X1228160Y579152D02*
X1226908Y577900D01*
X1205218D01*
X1204555Y578563D01*
X1202589D01*
G01X1238562Y582665D02*
X1237307Y583920D01*
X1205216D01*
X1204584Y583288D01*
X1202589D01*
G01X1228160Y589725D02*
X1226865Y591020D01*
X1205215D01*
X1204569Y590374D01*
X1202589D01*
G01X1238562Y596838D02*
X1237280Y598120D01*
X1205243D01*
X1204584Y597461D01*
X1202589D01*
G01X1228160Y593325D02*
X1226935Y592100D01*
X1205191D01*
X1204555Y592736D01*
X1202589D01*
G01X1238562Y600438D02*
X1237324Y599200D01*
X1205191D01*
X1204568Y599823D01*
X1202589D01*
G01X1228160Y603899D02*
X1226939Y605120D01*
X1205161D01*
X1204588Y604547D01*
X1202589D01*
G01X1238562Y614611D02*
X1237331Y613380D01*
X1205184D01*
X1204568Y613996D01*
X1202589D01*
G01X1228160Y607499D02*
X1226861Y606200D01*
X1205265D01*
X1204555Y606910D01*
X1202589D01*
G01X1238562Y611011D02*
X1237273Y612300D01*
X1205250D01*
X1204584Y611634D01*
X1202589D01*
G01X1228086Y-71962D02*
X1225405Y-72678D01*
G01X1228086Y-69994D02*
X1225405Y-69278D01*
G01X1233442Y-32912D02*
X1230761Y-33628D01*
G01X1233442Y-30944D02*
X1230761Y-30228D01*
G01X1235166Y470706D02*
X1233990Y469530D01*
X1231536D01*
X1230260Y470806D01*
G01X1235166Y467306D02*
X1234022Y468450D01*
X1231504D01*
X1230260Y467206D01*
G01X1235166Y484879D02*
X1233987Y483700D01*
X1231539D01*
X1230260Y484979D01*
G01X1235166Y481479D02*
X1234025Y482620D01*
X1231501D01*
X1230260Y481379D01*
G01X1235166Y514839D02*
X1234027Y513700D01*
X1231499D01*
X1230260Y514939D01*
G01X1235166Y511439D02*
X1233985Y512620D01*
X1231541D01*
X1230260Y511339D01*
G01X1235166Y529013D02*
X1233983Y527830D01*
X1231543D01*
X1230260Y529113D01*
G01X1235166Y525613D02*
X1234029Y526750D01*
X1231497D01*
X1230260Y525513D01*
G01X1235166Y564879D02*
X1233987Y563700D01*
X1231539D01*
X1230260Y564979D01*
G01X1235166Y561479D02*
X1234025Y562620D01*
X1231501D01*
X1230260Y561379D01*
G01X1235166Y575652D02*
X1233998Y576820D01*
X1231528D01*
X1230260Y575552D01*
G01X1235166Y579052D02*
X1234014Y577900D01*
X1231512D01*
X1230260Y579152D01*
G01X1235166Y593225D02*
X1234041Y592100D01*
X1231485D01*
X1230260Y593325D01*
G01X1235166Y603999D02*
X1234045Y605120D01*
X1231481D01*
X1230260Y603899D01*
G01X1235166Y589825D02*
X1233971Y591020D01*
X1231555D01*
X1230260Y589725D01*
G01X1235166Y607399D02*
X1233967Y606200D01*
X1231559D01*
X1230260Y607499D01*
G01X1230226Y1353093D02*
X1231486Y1351833D01*
Y1349347D01*
X1230326Y1348187D01*
G01X1233826Y1353093D02*
X1232566Y1351833D01*
Y1349347D01*
X1233726Y1348187D01*
G01X1230226Y1355193D02*
X1231486Y1356453D01*
Y1358939D01*
X1230326Y1360099D01*
G01X1233826Y1355193D02*
X1232566Y1356453D01*
Y1358939D01*
X1233726Y1360099D01*
G01X1230326Y1372385D02*
X1231486Y1373545D01*
Y1376031D01*
X1230226Y1377291D01*
G01X1233826D02*
X1232566Y1376031D01*
Y1373545D01*
X1233726Y1372385D01*
G01X1230326Y1384297D02*
X1231486Y1383137D01*
Y1380651D01*
X1230226Y1379391D01*
G01X1233826D02*
X1232566Y1380651D01*
Y1383137D01*
X1233726Y1384297D01*
G01X1263247Y118859D02*
X1261367D01*
X1260726Y119500D01*
X1250805D01*
X1249647Y118342D01*
G01X1263247Y133032D02*
X1261367D01*
X1260726Y133673D01*
X1250805D01*
X1249647Y132515D01*
G01X1263247Y121221D02*
X1261347D01*
X1260706Y120580D01*
X1250809D01*
X1249647Y121742D01*
G01X1263247Y135394D02*
X1261347D01*
X1260706Y134753D01*
X1250809D01*
X1249647Y135915D01*
G01X1245568Y488591D02*
X1244389Y489770D01*
X1241941D01*
X1240662Y488491D01*
G01X1245568Y474418D02*
X1244366Y475620D01*
X1241964D01*
X1240662Y474318D01*
G01X1245568Y477818D02*
X1244450Y476700D01*
X1241880D01*
X1240662Y477918D01*
G01X1245568Y491991D02*
X1244427Y490850D01*
X1241903D01*
X1240662Y492091D01*
G01X1245568Y521952D02*
X1244416Y520800D01*
X1241914D01*
X1240662Y522052D01*
G01X1245568Y518552D02*
X1244400Y519720D01*
X1241930D01*
X1240662Y518452D01*
G01X1245568Y536125D02*
X1244423Y534980D01*
X1241907D01*
X1240662Y536225D01*
G01X1245568Y532725D02*
X1244393Y533900D01*
X1241937D01*
X1240662Y532625D01*
G01X1245568Y568591D02*
X1244437Y569722D01*
X1241893D01*
X1240662Y568491D01*
G01X1245568Y571991D02*
X1244379Y570802D01*
X1241951D01*
X1240662Y572091D01*
G01X1245568Y582765D02*
X1244413Y583920D01*
X1241917D01*
X1240662Y582665D01*
G01X1245568Y586165D02*
X1244403Y585000D01*
X1241927D01*
X1240662Y586265D01*
G01X1245568Y596938D02*
X1244386Y598120D01*
X1241944D01*
X1240662Y596838D01*
G01X1245568Y600338D02*
X1244430Y599200D01*
X1241900D01*
X1240662Y600438D01*
G01X1245568Y611111D02*
X1244409Y612270D01*
X1241921D01*
X1240662Y611011D01*
G01X1245568Y614511D02*
X1244407Y613350D01*
X1241923D01*
X1240662Y614611D01*
G01X1246066Y1353093D02*
X1244806Y1351833D01*
Y1349347D01*
X1245966Y1348187D01*
G01X1242466Y1353093D02*
X1243726Y1351833D01*
Y1349347D01*
X1242566Y1348187D01*
G01X1242466Y1355193D02*
X1243726Y1356453D01*
Y1358939D01*
X1242566Y1360099D01*
G01X1246066Y1355193D02*
X1244806Y1356453D01*
Y1358939D01*
X1245966Y1360099D01*
G01X1242466Y1377291D02*
X1243726Y1376031D01*
Y1373545D01*
X1242566Y1372385D01*
G01X1246066Y1377291D02*
X1244806Y1376031D01*
Y1373545D01*
X1245966Y1372385D01*
G01X1242466Y1379391D02*
X1243726Y1380651D01*
Y1383137D01*
X1242566Y1384297D01*
G01X1246066Y1379391D02*
X1244806Y1380651D01*
Y1383137D01*
X1245966Y1384297D01*
G01X1246066Y1401489D02*
X1244806Y1400229D01*
Y1397743D01*
X1245966Y1396583D01*
G01X1242566D02*
X1243726Y1397743D01*
Y1400229D01*
X1242466Y1401489D01*
G01Y1403589D02*
X1243726Y1404849D01*
Y1407335D01*
X1242566Y1408495D01*
G01X1246066Y1403589D02*
X1244806Y1404849D01*
Y1407335D01*
X1245966Y1408495D01*
G01X1263247Y114134D02*
Y114135D01*
X1261361D01*
X1260726Y113500D01*
X1258102D01*
X1256947Y114655D01*
G01X1263247Y111772D02*
X1261354D01*
X1260706Y112420D01*
X1258112D01*
X1256947Y111255D01*
G01X1263247Y128307D02*
X1261360D01*
X1260703Y127650D01*
X1258125D01*
X1256947Y128828D01*
G01X1263247Y125945D02*
X1261354D01*
X1260729Y126570D01*
X1258089D01*
X1256947Y125428D01*
G01X1266946Y1353093D02*
X1268206Y1351833D01*
Y1349347D01*
X1267046Y1348187D01*
G01X1270546Y1353093D02*
X1269286Y1351833D01*
Y1349347D01*
X1270446Y1348187D01*
G01X1254706Y1353093D02*
X1255966Y1351833D01*
Y1349347D01*
X1254806Y1348187D01*
G01X1258306Y1353093D02*
X1257046Y1351833D01*
Y1349347D01*
X1258206Y1348187D01*
G01X1254706Y1355193D02*
X1255966Y1356453D01*
Y1358939D01*
X1254806Y1360099D01*
G01X1258306Y1355193D02*
X1257046Y1356453D01*
Y1358939D01*
X1258206Y1360099D01*
G01X1270546Y1355193D02*
X1269286Y1356453D01*
Y1358939D01*
X1270446Y1360099D01*
G01X1266946Y1355193D02*
X1268206Y1356453D01*
Y1358939D01*
X1267046Y1360099D01*
G01X1254706Y1377291D02*
X1255966Y1376031D01*
Y1373545D01*
X1254806Y1372385D01*
G01X1258306Y1377291D02*
X1257046Y1376031D01*
Y1373545D01*
X1258206Y1372385D01*
G01X1270546Y1377291D02*
X1269286Y1376031D01*
Y1373545D01*
X1270446Y1372385D01*
G01X1266946Y1377291D02*
X1268206Y1376031D01*
Y1373545D01*
X1267046Y1372385D01*
G01X1270446Y1384297D02*
X1269286Y1383137D01*
Y1380651D01*
X1270546Y1379391D01*
G01X1266946D02*
X1268206Y1380651D01*
Y1383137D01*
X1267046Y1384297D01*
G01X1254806D02*
X1255966Y1383137D01*
Y1380651D01*
X1254706Y1379391D01*
G01X1258306D02*
X1257046Y1380651D01*
Y1383137D01*
X1258206Y1384297D01*
G01X1267046Y1396583D02*
X1268206Y1397743D01*
Y1400229D01*
X1266946Y1401489D01*
G01X1270546D02*
X1269286Y1400229D01*
Y1397743D01*
X1270446Y1396583D01*
G01X1258306Y1401489D02*
X1257046Y1400229D01*
Y1397743D01*
X1258206Y1396583D01*
G01X1254706Y1401489D02*
X1255966Y1400229D01*
Y1397743D01*
X1254806Y1396583D01*
G01X1258306Y1403589D02*
X1257046Y1404849D01*
Y1407335D01*
X1258206Y1408495D01*
G01X1254806D02*
X1255966Y1407335D01*
Y1404849D01*
X1254706Y1403589D01*
G01X1270546D02*
X1269286Y1404849D01*
Y1407335D01*
X1270446Y1408495D01*
G01X1266946Y1403589D02*
X1268206Y1404849D01*
Y1407335D01*
X1267046Y1408495D01*
G01X1290258Y114723D02*
X1289035Y113500D01*
X1283958D01*
X1283324Y114134D01*
X1281357D01*
G01X1290258Y111123D02*
X1288961Y112420D01*
X1283986D01*
X1283338Y111772D01*
X1281357D01*
G01X1288115Y104249D02*
X1286964Y105400D01*
X1284001D01*
X1283286Y104685D01*
X1281357D01*
G01X1288115Y107649D02*
X1286946Y106480D01*
X1283907D01*
X1283340Y107047D01*
X1281357D01*
G01X1300660Y118235D02*
X1299375Y119520D01*
X1283999D01*
X1283338Y118859D01*
X1281357D01*
G01X1290258Y125296D02*
X1289034Y126520D01*
X1283913D01*
X1283338Y125945D01*
X1281357D01*
G01X1290258Y128896D02*
X1288962Y127600D01*
X1284031D01*
X1283324Y128307D01*
X1281357D01*
G01X1300660Y132409D02*
X1299399Y133670D01*
X1283991D01*
X1283353Y133032D01*
X1281357D01*
G01X1300660Y121835D02*
X1299425Y120600D01*
X1283949D01*
X1283328Y121221D01*
X1281357D01*
G01X1300660Y136009D02*
X1299401Y134750D01*
X1283981D01*
X1283337Y135394D01*
X1281357D01*
G01X1282786Y1353093D02*
X1281526Y1351833D01*
Y1349347D01*
X1282686Y1348187D01*
G01X1279186Y1353093D02*
X1280446Y1351833D01*
Y1349347D01*
X1279286Y1348187D01*
G01X1279186Y1355193D02*
X1280446Y1356453D01*
Y1358939D01*
X1279286Y1360099D01*
G01X1282786Y1355193D02*
X1281526Y1356453D01*
Y1358939D01*
X1282686Y1360099D01*
G01X1279186Y1377291D02*
X1280446Y1376031D01*
Y1373545D01*
X1279286Y1372385D01*
G01X1282786Y1377291D02*
X1281526Y1376031D01*
Y1373545D01*
X1282686Y1372385D01*
G01X1282786Y1379391D02*
X1281526Y1380651D01*
Y1383137D01*
X1282686Y1384297D01*
G01X1279186Y1379391D02*
X1280446Y1380651D01*
Y1383137D01*
X1279286Y1384297D01*
G01X1279186Y1401489D02*
X1280446Y1400229D01*
Y1397743D01*
X1279286Y1396583D01*
G01X1282786Y1401489D02*
X1281526Y1400229D01*
Y1397743D01*
X1282686Y1396583D01*
G01X1279186Y1403589D02*
X1280446Y1404849D01*
Y1407335D01*
X1279286Y1408495D01*
G01X1282786Y1403589D02*
X1281526Y1404849D01*
Y1407335D01*
X1282686Y1408495D01*
G01X1295006Y-32940D02*
X1297687Y-33656D01*
G01X1295006Y-30972D02*
X1297687Y-30256D01*
G01X1297264Y114623D02*
X1296141Y113500D01*
X1293581D01*
X1292358Y114723D01*
G01X1297264Y111223D02*
X1296067Y112420D01*
X1293655D01*
X1292358Y111123D01*
G01X1297264Y128796D02*
X1296068Y127600D01*
X1293654D01*
X1292358Y128896D01*
G01X1297264Y125396D02*
X1296140Y126520D01*
X1293582D01*
X1292358Y125296D01*
G01X1291426Y1353093D02*
X1292686Y1351833D01*
Y1349347D01*
X1291526Y1348187D01*
G01X1295026Y1353093D02*
X1293766Y1351833D01*
Y1349347D01*
X1294926Y1348187D01*
G01X1291426Y1355193D02*
X1292686Y1356453D01*
Y1358939D01*
X1291526Y1360099D01*
G01X1295026Y1355193D02*
X1293766Y1356453D01*
Y1358939D01*
X1294926Y1360099D01*
G01X1291426Y1377291D02*
X1292686Y1376031D01*
Y1373545D01*
X1291526Y1372385D01*
G01X1295026Y1377291D02*
X1293766Y1376031D01*
Y1373545D01*
X1294926Y1372385D01*
G01X1291426Y1379391D02*
X1292686Y1380651D01*
Y1383137D01*
X1291526Y1384297D01*
G01X1295026Y1379391D02*
X1293766Y1380651D01*
Y1383137D01*
X1294926Y1384297D01*
G01X1295026Y1401489D02*
X1293766Y1400229D01*
Y1397743D01*
X1294926Y1396583D01*
G01X1291426Y1401489D02*
X1292686Y1400229D01*
Y1397743D01*
X1291526Y1396583D01*
G01X1291426Y1403589D02*
X1292686Y1404849D01*
Y1407335D01*
X1291526Y1408495D01*
G01X1295026Y1403589D02*
X1293766Y1404849D01*
Y1407335D01*
X1294926Y1408495D01*
G01X1307666Y118335D02*
X1306501Y119500D01*
X1304025D01*
X1302760Y118235D01*
G01X1307666Y132509D02*
X1306505Y133670D01*
X1304021D01*
X1302760Y132409D01*
G01X1307666Y121735D02*
X1306511Y120580D01*
X1304015D01*
X1302760Y121835D01*
G01X1307666Y135909D02*
X1306507Y134750D01*
X1304019D01*
X1302760Y136009D01*
G01X1318262Y315778D02*
X1319500Y314540D01*
Y311700D01*
X1318362Y310562D01*
G01X1318262Y318928D02*
X1319497Y320163D01*
Y322625D01*
X1322646Y325774D01*
Y328076D01*
X1322424Y328298D01*
Y329978D01*
G01X1302896Y343797D02*
X1304031Y342662D01*
X1307794D01*
X1311349Y343370D01*
X1316030Y345306D01*
X1317569D01*
X1317792Y345529D01*
X1319471D01*
G01Y343954D02*
X1317787D01*
X1317515Y344226D01*
X1316245D01*
X1311664Y342331D01*
X1307901Y341582D01*
X1304081D01*
X1302896Y340397D01*
G01X1319506Y1353093D02*
X1318246Y1351833D01*
Y1349347D01*
X1319406Y1348187D01*
G01X1315906Y1353093D02*
X1317166Y1351833D01*
Y1349347D01*
X1316006Y1348187D01*
G01X1307266Y1353093D02*
X1306006Y1351833D01*
Y1349347D01*
X1307166Y1348187D01*
G01X1303666Y1353093D02*
X1304926Y1351833D01*
Y1349347D01*
X1303766Y1348187D01*
G01X1319506Y1355193D02*
X1318246Y1356453D01*
Y1358939D01*
X1319406Y1360099D01*
G01X1315906Y1355193D02*
X1317166Y1356453D01*
Y1358939D01*
X1316006Y1360099D01*
G01X1307266Y1355193D02*
X1306006Y1356453D01*
Y1358939D01*
X1307166Y1360099D01*
G01X1303666Y1355193D02*
X1304926Y1356453D01*
Y1358939D01*
X1303766Y1360099D01*
G01X1315906Y1377291D02*
X1317166Y1376031D01*
Y1373545D01*
X1316006Y1372385D01*
G01X1307266Y1377291D02*
X1306006Y1376031D01*
Y1373545D01*
X1307166Y1372385D01*
G01X1303666Y1377291D02*
X1304926Y1376031D01*
Y1373545D01*
X1303766Y1372385D01*
G01X1303666Y1379391D02*
X1304926Y1380651D01*
Y1383137D01*
X1303766Y1384297D01*
G01X1307266Y1379391D02*
X1306006Y1380651D01*
Y1383137D01*
X1307166Y1384297D01*
G01X1319506Y1377291D02*
X1318246Y1376031D01*
Y1373545D01*
X1319406Y1372385D01*
G01X1315906Y1379391D02*
X1317166Y1380651D01*
Y1383137D01*
X1316006Y1384297D01*
G01X1319506Y1379391D02*
X1318246Y1380651D01*
Y1383137D01*
X1319406Y1384297D01*
G01X1319506Y1401489D02*
X1318246Y1400229D01*
Y1397743D01*
X1319406Y1396583D01*
G01X1315906Y1401489D02*
X1317166Y1400229D01*
Y1397743D01*
X1316006Y1396583D01*
G01X1303666Y1401489D02*
X1304926Y1400229D01*
Y1397743D01*
X1303766Y1396583D01*
G01X1307266Y1401489D02*
X1306006Y1400229D01*
Y1397743D01*
X1307166Y1396583D01*
G01X1315906Y1403589D02*
X1317166Y1404849D01*
Y1407335D01*
X1316006Y1408495D01*
G01X1319506Y1403589D02*
X1318246Y1404849D01*
Y1407335D01*
X1319406Y1408495D01*
G01X1307266Y1403589D02*
X1306006Y1404849D01*
Y1407335D01*
X1307166Y1408495D01*
G01X1303666Y1403589D02*
X1304926Y1404849D01*
Y1407335D01*
X1303766Y1408495D01*
G01X1335006Y-70022D02*
X1337687Y-69306D01*
G01X1335006Y-71990D02*
X1337687Y-72706D01*
G01X1334010Y315778D02*
X1335300Y314488D01*
Y311752D01*
X1334110Y310562D01*
G01X1321862Y315778D02*
X1320580Y314496D01*
Y311744D01*
X1321762Y310562D01*
G01X1329736Y315778D02*
X1328480Y314522D01*
Y308718D01*
X1329636Y307562D01*
G01X1326136Y315778D02*
X1327400Y314514D01*
Y308726D01*
X1326236Y307562D01*
G01X1329736Y318928D02*
X1328500Y320164D01*
Y328071D01*
X1328723Y328294D01*
Y329978D01*
G01X1321862Y318928D02*
X1320577Y320213D01*
Y322177D01*
X1323726Y325326D01*
Y328022D01*
X1323998Y328294D01*
Y329978D01*
G01X1326136Y318928D02*
X1327420Y320212D01*
Y328027D01*
X1327148Y328299D01*
Y329978D01*
G01X1334010Y318928D02*
X1335300Y320218D01*
Y328021D01*
X1335022Y328299D01*
Y329978D01*
G01X1334009Y365035D02*
X1335300Y363744D01*
Y355168D01*
X1335022Y354890D01*
Y353206D01*
G01X1334009Y368185D02*
X1335300Y369476D01*
Y372210D01*
X1334109Y373401D01*
G01X1328146Y1353093D02*
X1329406Y1351833D01*
Y1349347D01*
X1328246Y1348187D01*
G01X1331746Y1353093D02*
X1330486Y1351833D01*
Y1349347D01*
X1331646Y1348187D01*
G01X1328146Y1355193D02*
X1329406Y1356453D01*
Y1358939D01*
X1328246Y1360099D01*
G01X1331746Y1355193D02*
X1330486Y1356453D01*
Y1358939D01*
X1331646Y1360099D01*
G01X1331746Y1379391D02*
X1330486Y1380651D01*
Y1383137D01*
X1331646Y1384297D01*
G01X1331746Y1377291D02*
X1330486Y1376031D01*
Y1373545D01*
X1331646Y1372385D01*
G01X1328146Y1377291D02*
X1329406Y1376031D01*
Y1373545D01*
X1328246Y1372385D01*
G01X1328146Y1379391D02*
X1329406Y1380651D01*
Y1383137D01*
X1328246Y1384297D01*
G01X1331746Y1401489D02*
X1330486Y1400229D01*
Y1397743D01*
X1331646Y1396583D01*
G01X1328146Y1401489D02*
X1329406Y1400229D01*
Y1397743D01*
X1328246Y1396583D01*
G01X1331746Y1403589D02*
X1330486Y1404849D01*
Y1407335D01*
X1331646Y1408495D01*
G01X1328146Y1403589D02*
X1329406Y1404849D01*
Y1407335D01*
X1328246Y1408495D01*
G01X1337610Y315778D02*
X1336380Y314548D01*
Y311692D01*
X1337510Y310562D01*
G01X1337610Y318928D02*
X1336380Y320158D01*
Y328077D01*
X1336597Y328294D01*
Y329978D01*
G01X1355169Y343525D02*
X1353902Y344792D01*
X1350406D01*
X1349041Y344227D01*
X1344651D01*
X1344378Y343954D01*
X1342699D01*
G01X1355169Y339251D02*
X1353934Y338016D01*
X1351135D01*
X1348740Y339008D01*
X1344605D01*
X1344383Y339230D01*
X1342699D01*
G01X1355169Y327777D02*
X1353934Y329012D01*
X1350161D01*
X1346020Y333153D01*
X1344601D01*
X1344379Y332931D01*
X1342699D01*
G01X1355169Y335651D02*
X1353884Y336936D01*
X1350920D01*
X1348525Y337928D01*
X1344651D01*
X1344378Y337655D01*
X1342699D01*
G01X1355169Y331377D02*
X1353884Y330092D01*
X1350609D01*
X1346468Y334233D01*
X1344655D01*
X1344383Y334505D01*
X1342699D01*
G01X1355169Y351399D02*
X1353884Y352684D01*
X1351585D01*
X1347852Y348951D01*
X1344651D01*
X1344379Y348679D01*
X1342699D01*
G01X1337609Y365035D02*
X1336380Y363806D01*
Y355102D01*
X1336597Y354885D01*
Y353206D01*
G01X1355169Y354999D02*
X1353934Y353764D01*
X1351137D01*
X1347404Y350031D01*
X1344605D01*
X1344383Y350253D01*
X1342699D01*
G01X1355169Y347125D02*
X1353916Y345872D01*
X1350191D01*
X1348826Y345307D01*
X1344605D01*
X1344383Y345529D01*
X1342699D01*
G01X1337609Y368185D02*
X1336380Y369414D01*
Y372272D01*
X1337509Y373401D01*
G01X1343986Y1353093D02*
X1342726Y1351833D01*
Y1349347D01*
X1343886Y1348187D01*
G01X1340386Y1353093D02*
X1341646Y1351833D01*
Y1349347D01*
X1340486Y1348187D01*
G01X1343986Y1355193D02*
X1342726Y1356453D01*
Y1358939D01*
X1343886Y1360099D01*
G01X1340386Y1355193D02*
X1341646Y1356453D01*
Y1358939D01*
X1340486Y1360099D01*
G01X1343986Y1377291D02*
X1342726Y1376031D01*
Y1373545D01*
X1343886Y1372385D01*
G01X1340386Y1377291D02*
X1341646Y1376031D01*
Y1373545D01*
X1340486Y1372385D01*
G01X1340386Y1379391D02*
X1341646Y1380651D01*
Y1383137D01*
X1340486Y1384297D01*
G01X1343986Y1379391D02*
X1342726Y1380651D01*
Y1383137D01*
X1343886Y1384297D01*
G01X1340386Y1401489D02*
X1341646Y1400229D01*
Y1397743D01*
X1340486Y1396583D01*
G01X1343986Y1401489D02*
X1342726Y1400229D01*
Y1397743D01*
X1343886Y1396583D01*
G01X1343986Y1403589D02*
X1342726Y1404849D01*
Y1407335D01*
X1343886Y1408495D01*
G01X1340486D02*
X1341646Y1407335D01*
Y1404849D01*
X1340386Y1403589D01*
G01X1358319Y327777D02*
X1359562Y329020D01*
X1362392D01*
X1363535Y327877D01*
G01X1358319Y335651D02*
X1359588Y336920D01*
X1365366D01*
X1366535Y335751D01*
G01X1358319Y339251D02*
X1359570Y338000D01*
X1365384D01*
X1366535Y339151D01*
G01X1358319Y331377D02*
X1359596Y330100D01*
X1362358D01*
X1363535Y331277D01*
G01X1358319Y343525D02*
X1359554Y344760D01*
X1362400D01*
X1363535Y343625D01*
G01X1358319Y354999D02*
X1359538Y353780D01*
X1365416D01*
X1366535Y354899D01*
G01X1358319Y351399D02*
X1359620Y352700D01*
X1365334D01*
X1366535Y351499D01*
G01X1358319Y347125D02*
X1359604Y345840D01*
X1362350D01*
X1363535Y347025D01*
G01X1356226Y1353093D02*
X1354966Y1351833D01*
Y1349347D01*
X1356126Y1348187D01*
G01X1352626Y1353093D02*
X1353886Y1351833D01*
Y1349347D01*
X1352726Y1348187D01*
G01X1356226Y1355193D02*
X1354966Y1356453D01*
Y1358939D01*
X1356126Y1360099D01*
G01X1352626Y1355193D02*
X1353886Y1356453D01*
Y1358939D01*
X1352726Y1360099D01*
G01X1352626Y1379391D02*
X1353886Y1380651D01*
Y1383137D01*
X1352726Y1384297D01*
G01X1356226Y1377291D02*
X1354966Y1376031D01*
Y1373545D01*
X1356126Y1372385D01*
G01X1356226Y1379391D02*
X1354966Y1380651D01*
Y1383137D01*
X1356126Y1384297D01*
G01X1352626Y1377291D02*
X1353886Y1376031D01*
Y1373545D01*
X1352726Y1372385D01*
G01X1356226Y1401489D02*
X1354966Y1400229D01*
Y1397743D01*
X1356126Y1396583D01*
G01X1352726D02*
X1353886Y1397743D01*
Y1400229D01*
X1352626Y1401489D01*
G01Y1403589D02*
X1353886Y1404849D01*
Y1407335D01*
X1352726Y1408495D01*
G01X1356226Y1403589D02*
X1354966Y1404849D01*
Y1407335D01*
X1356126Y1408495D01*
G01X1413248Y133032D02*
X1411368D01*
X1410730Y133670D01*
X1400803D01*
X1399648Y132515D01*
G01X1413248Y121221D02*
X1411348D01*
X1410707Y120580D01*
X1400810D01*
X1399648Y121742D01*
G01X1413248Y118859D02*
X1411368D01*
X1410727Y119500D01*
X1400806D01*
X1399648Y118342D01*
G01X1413248Y135394D02*
X1411348D01*
X1410704Y134750D01*
X1400813D01*
X1399648Y135915D01*
G01X1413248Y111772D02*
X1411355D01*
X1410757Y112370D01*
X1408063D01*
X1406948Y111255D01*
G01X1413248Y114134D02*
Y114135D01*
X1411362D01*
X1410677Y113450D01*
X1408153D01*
X1406948Y114655D01*
G01X1413248Y128307D02*
X1411361D01*
X1410734Y127680D01*
X1408096D01*
X1406948Y128828D01*
G01X1413248Y125945D02*
X1411355D01*
X1410700Y126600D01*
X1408120D01*
X1406948Y125428D01*
G01X1440259Y114723D02*
X1439036Y113500D01*
X1433959D01*
X1433325Y114134D01*
X1431358D01*
G01X1440259Y111123D02*
X1438962Y112420D01*
X1433987D01*
X1433339Y111772D01*
X1431358D01*
G01X1438116Y107649D02*
X1436867Y106400D01*
X1433988D01*
X1433341Y107047D01*
X1431358D01*
G01X1438116Y104249D02*
X1437045Y105320D01*
X1433922D01*
X1433287Y104685D01*
X1431358D01*
G01X1440259Y128896D02*
X1439043Y127680D01*
X1433952D01*
X1433325Y128307D01*
X1431358D01*
G01X1440259Y125296D02*
X1438955Y126600D01*
X1433994D01*
X1433339Y125945D01*
X1431358D01*
G01X1450661Y121835D02*
X1449406Y120580D01*
X1433970D01*
X1433329Y121221D01*
X1431358D01*
G01X1450661Y132409D02*
X1449370Y133700D01*
X1434022D01*
X1433354Y133032D01*
X1431358D01*
G01X1450661Y118235D02*
X1449396Y119500D01*
X1433980D01*
X1433339Y118859D01*
X1431358D01*
G01X1450661Y136009D02*
X1449432Y134780D01*
X1433952D01*
X1433338Y135394D01*
X1431358D01*
G01X1447265Y111223D02*
X1446118Y112370D01*
X1443606D01*
X1442359Y111123D01*
G01X1447265Y114623D02*
X1446092Y113450D01*
X1443632D01*
X1442359Y114723D01*
G01X1447265Y125396D02*
X1446111Y126550D01*
X1443613D01*
X1442359Y125296D01*
G01X1447265Y128796D02*
X1446099Y127630D01*
X1443625D01*
X1442359Y128896D01*
G01X1457667Y118335D02*
X1456502Y119500D01*
X1454026D01*
X1452761Y118235D01*
G01X1457667Y121735D02*
X1456512Y120580D01*
X1454016D01*
X1452761Y121835D01*
G01X1457667Y132509D02*
X1456476Y133700D01*
X1454052D01*
X1452761Y132409D01*
G01X1457667Y135909D02*
X1456538Y134780D01*
X1453990D01*
X1452761Y136009D01*
G01X1464870Y1353093D02*
X1463608Y1351831D01*
Y1349349D01*
X1464770Y1348187D01*
G01X1461270Y1353093D02*
X1462528Y1351835D01*
Y1349345D01*
X1461370Y1348187D01*
G01X1464870Y1355193D02*
X1463612Y1356451D01*
Y1358941D01*
X1464770Y1360099D01*
G01X1461270Y1355193D02*
X1462532Y1356455D01*
Y1358937D01*
X1461370Y1360099D01*
G01X1464870Y1377291D02*
X1463608Y1376029D01*
Y1373547D01*
X1464770Y1372385D01*
G01X1461270Y1377291D02*
X1462528Y1376033D01*
Y1373543D01*
X1461370Y1372385D01*
G01X1464870Y1379391D02*
X1463612Y1380649D01*
Y1383139D01*
X1464770Y1384297D01*
G01X1461270Y1379391D02*
X1462532Y1380653D01*
Y1383135D01*
X1461370Y1384297D01*
G01X1477110Y1353093D02*
X1475848Y1351831D01*
Y1349349D01*
X1477010Y1348187D01*
G01X1473510Y1353093D02*
X1474768Y1351835D01*
Y1349345D01*
X1473610Y1348187D01*
G01X1473510Y1355193D02*
X1474772Y1356455D01*
Y1358937D01*
X1473610Y1360099D01*
G01X1477110Y1355193D02*
X1475852Y1356451D01*
Y1358941D01*
X1477010Y1360099D01*
G01X1473510Y1377291D02*
X1474768Y1376033D01*
Y1373543D01*
X1473610Y1372385D01*
G01X1477110Y1377291D02*
X1475848Y1376029D01*
Y1373547D01*
X1477010Y1372385D01*
G01X1473510Y1379391D02*
X1474772Y1380653D01*
Y1383135D01*
X1473610Y1384297D01*
G01X1477110Y1379391D02*
X1475852Y1380649D01*
Y1383139D01*
X1477010Y1384297D01*
G01X1477110Y1401489D02*
X1475848Y1400227D01*
Y1397745D01*
X1477010Y1396583D01*
G01X1473510Y1401489D02*
X1474768Y1400231D01*
Y1397741D01*
X1473610Y1396583D01*
G01X1473510Y1403589D02*
X1474772Y1404851D01*
Y1407333D01*
X1473610Y1408495D01*
G01X1477110Y1403589D02*
X1475852Y1404847D01*
Y1407337D01*
X1477010Y1408495D01*
G01X1484586Y-69994D02*
X1481905Y-69278D01*
G01X1484586Y-71962D02*
X1481905Y-72678D01*
G01X1489350Y1353093D02*
X1488088Y1351831D01*
Y1349349D01*
X1489250Y1348187D01*
G01X1485750Y1353093D02*
X1487008Y1351835D01*
Y1349345D01*
X1485850Y1348187D01*
G01X1485750Y1355193D02*
X1487012Y1356455D01*
Y1358937D01*
X1485850Y1360099D01*
G01X1489350Y1355193D02*
X1488092Y1356451D01*
Y1358941D01*
X1489250Y1360099D01*
G01X1489350Y1377291D02*
X1488088Y1376029D01*
Y1373547D01*
X1489250Y1372385D01*
G01X1485750Y1377291D02*
X1487008Y1376033D01*
Y1373543D01*
X1485850Y1372385D01*
G01X1485750Y1379391D02*
X1487012Y1380653D01*
Y1383135D01*
X1485850Y1384297D01*
G01X1489350Y1379391D02*
X1488092Y1380649D01*
Y1383139D01*
X1489250Y1384297D01*
G01X1485750Y1401489D02*
X1487008Y1400231D01*
Y1397741D01*
X1485850Y1396583D01*
G01X1489350Y1401489D02*
X1488088Y1400227D01*
Y1397745D01*
X1489250Y1396583D01*
G01X1489350Y1403589D02*
X1488092Y1404847D01*
Y1407337D01*
X1489250Y1408495D01*
G01X1485750Y1403589D02*
X1487012Y1404851D01*
Y1407333D01*
X1485850Y1408495D01*
G01X1515610Y114134D02*
Y114135D01*
X1513724D01*
X1513069Y113480D01*
X1510485D01*
X1509310Y114655D01*
G01X1515610Y111772D02*
X1513717D01*
X1513089Y112400D01*
X1510455D01*
X1509310Y111255D01*
G01X1515610Y121221D02*
X1513710D01*
X1513039Y120550D01*
X1503202D01*
X1502010Y121742D01*
G01X1509310Y125428D02*
X1510502Y126620D01*
X1513042D01*
X1513717Y125945D01*
X1515610D01*
G01X1509310Y128828D02*
X1510438Y127700D01*
X1513116D01*
X1513723Y128307D01*
X1515610D01*
G01Y118859D02*
X1513730D01*
X1513119Y119470D01*
X1503138D01*
X1502010Y118342D01*
G01X1515610Y133032D02*
X1513730D01*
X1513112Y133650D01*
X1503145D01*
X1502010Y132515D01*
G01X1515610Y135394D02*
X1513710D01*
X1513046Y134730D01*
X1503195D01*
X1502010Y135915D01*
G01X1511950Y401513D02*
X1513163Y400300D01*
X1515543D01*
X1516856Y401613D01*
G01X1511950Y398113D02*
X1513057Y399220D01*
X1515649D01*
X1516856Y398013D01*
G01X1509550Y412287D02*
X1510683Y413420D01*
X1513223D01*
X1514456Y412187D01*
G01X1509550Y415687D02*
X1510737Y414500D01*
X1513169D01*
X1514456Y415787D01*
G01X1509550Y440633D02*
X1510737Y441820D01*
X1513169D01*
X1514456Y440533D01*
G01X1509550Y429860D02*
X1510710Y428700D01*
X1513196D01*
X1514456Y429960D01*
G01X1509550Y426460D02*
X1510710Y427620D01*
X1513196D01*
X1514456Y426360D01*
G01X1509550Y444033D02*
X1510683Y442900D01*
X1513223D01*
X1514456Y444133D01*
G01X1509550Y472787D02*
X1510737Y471600D01*
X1513169D01*
X1514456Y472887D01*
G01X1509550Y469387D02*
X1510683Y470520D01*
X1513223D01*
X1514456Y469287D01*
G01X1509550Y483560D02*
X1510710Y484720D01*
X1513196D01*
X1514456Y483460D01*
G01X1509550Y486960D02*
X1510710Y485800D01*
X1513196D01*
X1514456Y487060D01*
G01X1509550Y516921D02*
X1510771Y515700D01*
X1513135D01*
X1514456Y517021D01*
G01X1509550Y513521D02*
X1510649Y514620D01*
X1513257D01*
X1514456Y513421D01*
G01X1509550Y527694D02*
X1510676Y528820D01*
X1513230D01*
X1514456Y527594D01*
G01X1509550Y531094D02*
X1510744Y529900D01*
X1513162D01*
X1514456Y531194D01*
G01X1510527Y908951D02*
X1511687Y910111D01*
X1511686Y910112D01*
Y913883D01*
X1511242Y914327D01*
Y916678D01*
G01X1513927Y908951D02*
X1512766Y910112D01*
Y913883D01*
X1513211Y914328D01*
Y916678D01*
G01X1513830Y1353093D02*
X1512568Y1351831D01*
Y1349349D01*
X1513730Y1348187D01*
G01X1510230Y1353093D02*
X1511488Y1351835D01*
Y1349345D01*
X1510330Y1348187D01*
G01X1501590Y1353093D02*
X1500328Y1351831D01*
Y1349349D01*
X1501490Y1348187D01*
G01X1497990Y1353093D02*
X1499248Y1351835D01*
Y1349345D01*
X1498090Y1348187D01*
G01X1510230Y1355193D02*
X1511492Y1356455D01*
Y1358937D01*
X1510330Y1360099D01*
G01X1501590Y1355193D02*
X1500332Y1356451D01*
Y1358941D01*
X1501490Y1360099D01*
G01X1513830Y1355193D02*
X1512572Y1356451D01*
Y1358941D01*
X1513730Y1360099D01*
G01X1497990Y1355193D02*
X1499252Y1356455D01*
Y1358937D01*
X1498090Y1360099D01*
G01X1510230Y1377291D02*
X1511488Y1376033D01*
Y1373543D01*
X1510330Y1372385D01*
G01X1513830Y1377291D02*
X1512568Y1376029D01*
Y1373547D01*
X1513730Y1372385D01*
G01X1501590Y1377291D02*
X1500328Y1376029D01*
Y1373547D01*
X1501490Y1372385D01*
G01X1497990Y1377291D02*
X1499248Y1376033D01*
Y1373543D01*
X1498090Y1372385D01*
G01X1501590Y1379391D02*
X1500332Y1380649D01*
Y1383139D01*
X1501490Y1384297D01*
G01X1497990Y1379391D02*
X1499252Y1380653D01*
Y1383135D01*
X1498090Y1384297D01*
G01X1513830Y1379391D02*
X1512572Y1380649D01*
Y1383139D01*
X1513730Y1384297D01*
G01X1510230Y1379391D02*
X1511492Y1380653D01*
Y1383135D01*
X1510330Y1384297D01*
G01X1497990Y1401489D02*
X1499248Y1400231D01*
Y1397741D01*
X1498090Y1396583D01*
G01X1510230Y1401489D02*
X1511488Y1400231D01*
Y1397741D01*
X1510330Y1396583D01*
G01X1513830Y1401489D02*
X1512568Y1400227D01*
Y1397745D01*
X1513730Y1396583D01*
G01X1501590Y1401489D02*
X1500328Y1400227D01*
Y1397745D01*
X1501490Y1396583D01*
G01X1497990Y1403589D02*
X1499252Y1404851D01*
Y1407333D01*
X1498090Y1408495D01*
G01X1510230Y1403589D02*
X1511492Y1404851D01*
Y1407333D01*
X1510330Y1408495D01*
G01X1513830Y1403589D02*
X1512572Y1404847D01*
Y1407337D01*
X1513730Y1408495D01*
G01X1501590Y1403589D02*
X1500332Y1404847D01*
Y1407337D01*
X1501490Y1408495D01*
G01X1519942Y-33042D02*
X1517261Y-33758D01*
G01X1519942Y-31074D02*
X1517261Y-30358D01*
G01X1519952Y391001D02*
X1521071Y392120D01*
X1523639D01*
X1524858Y390901D01*
G01X1526958D02*
X1528177Y392120D01*
X1549946D01*
X1550550Y391516D01*
X1552529D01*
G01X1519952Y394401D02*
X1521153Y393200D01*
X1523557D01*
X1524858Y394501D01*
G01X1519952Y408574D02*
X1521126Y407400D01*
X1523584D01*
X1524858Y408674D01*
G01X1519952Y405174D02*
X1521098Y406320D01*
X1523612D01*
X1524858Y405074D01*
G01X1518956Y398013D02*
X1520163Y399220D01*
X1549945D01*
X1550563Y398602D01*
X1552529D01*
G01X1526958Y405074D02*
X1528204Y406320D01*
X1549919D01*
X1550550Y405689D01*
X1552529D01*
G01X1526958Y394501D02*
X1528259Y393200D01*
X1549856D01*
X1550534Y393878D01*
X1552529D01*
G01X1518956Y401613D02*
X1520269Y400300D01*
X1549865D01*
X1550530Y400965D01*
X1552529D01*
G01X1526958Y408674D02*
X1528232Y407400D01*
X1549883D01*
X1550534Y408051D01*
X1552529D01*
G01X1519952Y422747D02*
X1521099Y421600D01*
X1523611D01*
X1524858Y422847D01*
G01X1519952Y419347D02*
X1521125Y420520D01*
X1523585D01*
X1524858Y419247D01*
G01X1516556Y412187D02*
X1517789Y413420D01*
X1549919D01*
X1550563Y412776D01*
X1552529D01*
G01X1526958Y422847D02*
X1528205Y421600D01*
X1549910D01*
X1550534Y422224D01*
X1552529D01*
G01X1526958Y419247D02*
X1528231Y420520D01*
X1549892D01*
X1550550Y419862D01*
X1552529D01*
G01X1516556Y415787D02*
X1517843Y414500D01*
X1549911D01*
X1550549Y415138D01*
X1552529D01*
G01X1519952Y436921D02*
X1521073Y435800D01*
X1523637D01*
X1524858Y437021D01*
G01X1519952Y433521D02*
X1521151Y434720D01*
X1523559D01*
X1524858Y433421D01*
G01X1516556Y426360D02*
X1517816Y427620D01*
X1549892D01*
X1550563Y426949D01*
X1552529D01*
G01X1516556Y429960D02*
X1517816Y428700D01*
X1549938D01*
X1550549Y429311D01*
X1552529D01*
G01X1526958Y433421D02*
X1528237Y434700D01*
X1549886D01*
X1550550Y434036D01*
X1552529D01*
G01X1526958Y437021D02*
X1528199Y435780D01*
X1549916D01*
X1550534Y436398D01*
X1552529D01*
G01X1516556Y440533D02*
X1517743Y441720D01*
X1549965D01*
X1550563Y441122D01*
X1552529D01*
G01X1516556Y444133D02*
X1517889Y442800D01*
X1549865D01*
X1550549Y443484D01*
X1552529D01*
G01X1516556Y472887D02*
X1517843Y471600D01*
X1549870D01*
X1550534Y472264D01*
X1552529D01*
G01X1516556Y469287D02*
X1517789Y470520D01*
X1549932D01*
X1550550Y469902D01*
X1552529D01*
G01X1519952Y479899D02*
X1521151Y478700D01*
X1523559D01*
X1524858Y479999D01*
G01X1519952Y476499D02*
X1521073Y477620D01*
X1523637D01*
X1524858Y476399D01*
G01X1516556Y483460D02*
X1517816Y484720D01*
X1549905D01*
X1550550Y484075D01*
X1552529D01*
G01X1516556Y487060D02*
X1517816Y485800D01*
X1549897D01*
X1550534Y486437D01*
X1552529D01*
G01X1526958Y476399D02*
X1528179Y477620D01*
X1549931D01*
X1550563Y476988D01*
X1552529D01*
G01X1526958Y479999D02*
X1528257Y478700D01*
X1549899D01*
X1550549Y479350D01*
X1552529D01*
G01X1519952Y494073D02*
X1521125Y492900D01*
X1523585D01*
X1524858Y494173D01*
G01X1519952Y490673D02*
X1521099Y491820D01*
X1523611D01*
X1524858Y490573D01*
G01X1526958Y494173D02*
X1528231Y492900D01*
X1549925D01*
X1550549Y493524D01*
X1552529D01*
G01X1526958Y490573D02*
X1528205Y491820D01*
X1549905D01*
X1550563Y491162D01*
X1552529D01*
G01X1519952Y520633D02*
X1521139Y521820D01*
X1523571D01*
X1524858Y520533D01*
G01X1519952Y524033D02*
X1521085Y522900D01*
X1523625D01*
X1524858Y524133D01*
G01X1516556Y513421D02*
X1517805Y514670D01*
X1549916D01*
X1550550Y514036D01*
X1552529D01*
G01X1526958Y524133D02*
X1528291Y522800D01*
X1549865D01*
X1550549Y523484D01*
X1552529D01*
G01X1526958Y520533D02*
X1528145Y521720D01*
X1549965D01*
X1550563Y521122D01*
X1552529D01*
G01X1516556Y517021D02*
X1517827Y515750D01*
X1549886D01*
X1550534Y516398D01*
X1552529D01*
G01X1519952Y534806D02*
X1521166Y536020D01*
X1523544D01*
X1524858Y534706D01*
G01X1519952Y538206D02*
X1521058Y537100D01*
X1523652D01*
X1524858Y538306D01*
G01X1516556Y527594D02*
X1517782Y528820D01*
X1549939D01*
X1550550Y528209D01*
X1552529D01*
G01X1526958Y538306D02*
X1528284Y536980D01*
X1549944D01*
X1550622Y537658D01*
X1552529D01*
G01X1526958Y534706D02*
X1528152Y535900D01*
X1549958D01*
X1550563Y535295D01*
X1552529D01*
G01X1516556Y531194D02*
X1517850Y529900D01*
X1549863D01*
X1550534Y530571D01*
X1552529D01*
G01X1526070Y1353093D02*
X1524808Y1351831D01*
Y1349349D01*
X1525970Y1348187D01*
G01X1522470Y1353093D02*
X1523728Y1351835D01*
Y1349345D01*
X1522570Y1348187D01*
G01X1522470Y1355193D02*
X1523732Y1356455D01*
Y1358937D01*
X1522570Y1360099D01*
G01X1526070Y1355193D02*
X1524812Y1356451D01*
Y1358941D01*
X1525970Y1360099D01*
G01X1526070Y1377291D02*
X1524808Y1376029D01*
Y1373547D01*
X1525970Y1372385D01*
G01X1522470Y1377291D02*
X1523728Y1376033D01*
Y1373543D01*
X1522570Y1372385D01*
G01X1526070Y1379391D02*
X1524812Y1380649D01*
Y1383139D01*
X1525970Y1384297D01*
G01X1522470Y1379391D02*
X1523732Y1380653D01*
Y1383135D01*
X1522570Y1384297D01*
G01X1522470Y1401489D02*
X1523728Y1400231D01*
Y1397741D01*
X1522570Y1396583D01*
G01X1526070Y1401489D02*
X1524808Y1400227D01*
Y1397745D01*
X1525970Y1396583D01*
G01X1526070Y1403589D02*
X1524812Y1404847D01*
Y1407337D01*
X1525970Y1408495D01*
G01X1522470Y1403589D02*
X1523732Y1404851D01*
Y1407333D01*
X1522570Y1408495D01*
G01X1549627Y111223D02*
X1548480Y112370D01*
X1545968D01*
X1544721Y111123D01*
G01X1549627Y114623D02*
X1548454Y113450D01*
X1545994D01*
X1544721Y114723D01*
G01X1542621D02*
X1541398Y113500D01*
X1536321D01*
X1535687Y114134D01*
X1533720D01*
G01X1542621Y111123D02*
X1541324Y112420D01*
X1536349D01*
X1535701Y111772D01*
X1533720D01*
G01X1540478Y107649D02*
X1539229Y106400D01*
X1536350D01*
X1535703Y107047D01*
X1533720D01*
G01X1540478Y104249D02*
X1539407Y105320D01*
X1536284D01*
X1535649Y104685D01*
X1533720D01*
G01X1549627Y128796D02*
X1548461Y127630D01*
X1545987D01*
X1544721Y128896D01*
G01X1549627Y125396D02*
X1548473Y126550D01*
X1545975D01*
X1544721Y125296D01*
G01X1553023Y121835D02*
X1551738Y120550D01*
X1536362D01*
X1535691Y121221D01*
X1533720D01*
G01X1553023Y132409D02*
X1551762Y133670D01*
X1536354D01*
X1535716Y133032D01*
X1533720D01*
G01X1553023Y118235D02*
X1551788Y119470D01*
X1536312D01*
X1535701Y118859D01*
X1533720D01*
G01X1542621Y125296D02*
X1541367Y126550D01*
X1536306D01*
X1535701Y125945D01*
X1533720D01*
G01X1542621Y128896D02*
X1541355Y127630D01*
X1536364D01*
X1535687Y128307D01*
X1533720D01*
G01X1553023Y136009D02*
X1551764Y134750D01*
X1536344D01*
X1535700Y135394D01*
X1533720D01*
G01X1546183Y541863D02*
X1547240Y542920D01*
X1550045D01*
X1550583Y542382D01*
X1552529D01*
G01X1546183Y545263D02*
X1547446Y544000D01*
X1550063D01*
X1550807Y544744D01*
X1552529D01*
G01X1538310Y1353093D02*
X1537048Y1351831D01*
Y1349349D01*
X1538210Y1348187D01*
G01X1534710Y1353093D02*
X1535968Y1351835D01*
Y1349345D01*
X1534810Y1348187D01*
G01X1538310Y1355193D02*
X1537052Y1356451D01*
Y1358941D01*
X1538210Y1360099D01*
G01X1534710Y1355193D02*
X1535972Y1356455D01*
Y1358937D01*
X1534810Y1360099D01*
G01X1538310Y1377291D02*
X1537048Y1376029D01*
Y1373547D01*
X1538210Y1372385D01*
G01X1534710Y1377291D02*
X1535968Y1376033D01*
Y1373543D01*
X1534810Y1372385D01*
G01X1534710Y1379391D02*
X1535972Y1380653D01*
Y1383135D01*
X1534810Y1384297D01*
G01X1538310Y1379391D02*
X1537052Y1380649D01*
Y1383139D01*
X1538210Y1384297D01*
G01X1538310Y1401489D02*
X1537048Y1400227D01*
Y1397745D01*
X1538210Y1396583D01*
G01X1534710Y1401489D02*
X1535968Y1400231D01*
Y1397741D01*
X1534810Y1396583D01*
G01X1538310Y1403589D02*
X1537052Y1404847D01*
Y1407337D01*
X1538210Y1408495D01*
G01X1534710Y1403589D02*
X1535972Y1404851D01*
Y1407333D01*
X1534810Y1408495D01*
G01X1560029Y132509D02*
X1558838Y133700D01*
X1556414D01*
X1555123Y132409D01*
G01X1560029Y121735D02*
X1558894Y120600D01*
X1556358D01*
X1555123Y121835D01*
G01X1560029Y118335D02*
X1558844Y119520D01*
X1556408D01*
X1555123Y118235D01*
G01X1560029Y135909D02*
X1558900Y134780D01*
X1556352D01*
X1555123Y136009D01*
G01X1550550Y1353093D02*
X1549288Y1351831D01*
Y1349349D01*
X1550450Y1348187D01*
G01X1546950Y1353093D02*
X1548208Y1351835D01*
Y1349345D01*
X1547050Y1348187D01*
G01X1559190Y1353093D02*
X1560448Y1351835D01*
Y1349345D01*
X1559290Y1348187D01*
G01X1562790Y1353093D02*
X1561528Y1351831D01*
Y1349349D01*
X1562690Y1348187D01*
G01X1559190Y1355193D02*
X1560452Y1356455D01*
Y1358937D01*
X1559290Y1360099D01*
G01X1562790Y1355193D02*
X1561532Y1356451D01*
Y1358941D01*
X1562690Y1360099D01*
G01X1550550Y1355193D02*
X1549292Y1356451D01*
Y1358941D01*
X1550450Y1360099D01*
G01X1546950Y1355193D02*
X1548212Y1356455D01*
Y1358937D01*
X1547050Y1360099D01*
G01X1562790Y1377291D02*
X1561528Y1376029D01*
Y1373547D01*
X1562690Y1372385D01*
G01X1559190Y1377291D02*
X1560448Y1376033D01*
Y1373543D01*
X1559290Y1372385D01*
G01X1546950Y1377291D02*
X1548208Y1376033D01*
Y1373543D01*
X1547050Y1372385D01*
G01X1550550Y1377291D02*
X1549288Y1376029D01*
Y1373547D01*
X1550450Y1372385D01*
G01X1546950Y1379391D02*
X1548212Y1380653D01*
Y1383135D01*
X1547050Y1384297D01*
G01X1562790Y1379391D02*
X1561532Y1380649D01*
Y1383139D01*
X1562690Y1384297D01*
G01X1559190Y1379391D02*
X1560452Y1380653D01*
Y1383135D01*
X1559290Y1384297D01*
G01X1550550Y1379391D02*
X1549292Y1380649D01*
Y1383139D01*
X1550450Y1384297D01*
G01X1550550Y1401489D02*
X1549288Y1400227D01*
Y1397745D01*
X1550450Y1396583D01*
G01X1562790Y1401489D02*
X1561528Y1400227D01*
Y1397745D01*
X1562690Y1396583D01*
G01X1559190Y1401489D02*
X1560448Y1400231D01*
Y1397741D01*
X1559290Y1396583D01*
G01X1546950Y1401489D02*
X1548208Y1400231D01*
Y1397741D01*
X1547050Y1396583D01*
G01X1559190Y1403589D02*
X1560452Y1404851D01*
Y1407333D01*
X1559290Y1408495D01*
G01X1562790Y1403589D02*
X1561532Y1404847D01*
Y1407337D01*
X1562690Y1408495D01*
G01X1550550Y1403589D02*
X1549292Y1404847D01*
Y1407337D01*
X1550450Y1408495D01*
G01X1546950Y1403589D02*
X1548212Y1404851D01*
Y1407333D01*
X1547050Y1408495D01*
G01X1584240Y390995D02*
X1583115Y392120D01*
X1573144D01*
X1572540Y391516D01*
X1570640D01*
G01X1584240Y408568D02*
X1583052Y407380D01*
X1573191D01*
X1572520Y408051D01*
X1570640D01*
G01X1576940Y398082D02*
X1575802Y399220D01*
X1573144D01*
X1572526Y398602D01*
X1570640D01*
G01X1584240Y405168D02*
X1583108Y406300D01*
X1573151D01*
X1572540Y405689D01*
X1570640D01*
G01X1576940Y401482D02*
X1575758Y400300D01*
X1573198D01*
X1572533Y400965D01*
X1570640D01*
G01X1584240Y394395D02*
X1583045Y393200D01*
X1573198D01*
X1572520Y393878D01*
X1570640D01*
G01X1576940Y415655D02*
X1575765Y414480D01*
X1573191D01*
X1572533Y415138D01*
X1570640D01*
G01X1584240Y419341D02*
X1583061Y420520D01*
X1573198D01*
X1572540Y419862D01*
X1570640D01*
G01X1576940Y412255D02*
X1575795Y413400D01*
X1573151D01*
X1572527Y412776D01*
X1570640D01*
G01X1584240Y422741D02*
X1583099Y421600D01*
X1573144D01*
X1572520Y422224D01*
X1570640D01*
G01X1584240Y433515D02*
X1583035Y434720D01*
X1573224D01*
X1572540Y434036D01*
X1570640D01*
G01X1576940Y440602D02*
X1575822Y441720D01*
X1573124D01*
X1572526Y441122D01*
X1570640D01*
G01X1576940Y429828D02*
X1575812Y428700D01*
X1573144D01*
X1572533Y429311D01*
X1570640D01*
G01X1584240Y436915D02*
X1583125Y435800D01*
X1573118D01*
X1572520Y436398D01*
X1570640D01*
G01X1576940Y426428D02*
X1575748Y427620D01*
X1573198D01*
X1572527Y426949D01*
X1570640D01*
G01X1576940Y444002D02*
X1575738Y442800D01*
X1573218D01*
X1572534Y443484D01*
X1570640D01*
G01X1584240Y472781D02*
X1583059Y471600D01*
X1573184D01*
X1572520Y472264D01*
X1570640D01*
G01X1584240Y469381D02*
X1583101Y470520D01*
X1573158D01*
X1572540Y469902D01*
X1570640D01*
G01X1584240Y483554D02*
X1583074Y484720D01*
X1573185D01*
X1572540Y484075D01*
X1570640D01*
G01X1576940Y476468D02*
X1575788Y477620D01*
X1573158D01*
X1572526Y476988D01*
X1570640D01*
G01X1584240Y486954D02*
X1583086Y485800D01*
X1573157D01*
X1572520Y486437D01*
X1570640D01*
G01X1576940Y479868D02*
X1575772Y478700D01*
X1573184D01*
X1572534Y479350D01*
X1570640D01*
G01X1576940Y494041D02*
X1575799Y492900D01*
X1573157D01*
X1572533Y493524D01*
X1570640D01*
G01X1576940Y490641D02*
X1575761Y491820D01*
X1573185D01*
X1572527Y491162D01*
X1570640D01*
G01X1576940Y520602D02*
X1575792Y521750D01*
X1573154D01*
X1572526Y521122D01*
X1570640D01*
G01X1584240Y516915D02*
X1583075Y515750D01*
X1573168D01*
X1572520Y516398D01*
X1570640D01*
G01X1576940Y524002D02*
X1575768Y522830D01*
X1573188D01*
X1572534Y523484D01*
X1570640D01*
G01X1584240Y513515D02*
X1583085Y514670D01*
X1573174D01*
X1572540Y514036D01*
X1570640D01*
G01X1576940Y534775D02*
X1575765Y535950D01*
X1573181D01*
X1572526Y535295D01*
X1570640D01*
G01X1584240Y531088D02*
X1583102Y529950D01*
X1573141D01*
X1572520Y530571D01*
X1570640D01*
G01X1576940Y538175D02*
X1575795Y537030D01*
X1573161D01*
X1572533Y537658D01*
X1570640D01*
G01X1584240Y527688D02*
X1583058Y528870D01*
X1573201D01*
X1572540Y528209D01*
X1570640D01*
G01X1575030Y1353093D02*
X1573768Y1351831D01*
Y1349349D01*
X1574930Y1348187D01*
G01X1571430Y1353093D02*
X1572688Y1351835D01*
Y1349345D01*
X1571530Y1348187D01*
G01X1575030Y1355193D02*
X1573772Y1356451D01*
Y1358941D01*
X1574930Y1360099D01*
G01X1571430Y1355193D02*
X1572692Y1356455D01*
Y1358937D01*
X1571530Y1360099D01*
G01X1575030Y1377291D02*
X1573768Y1376029D01*
Y1373547D01*
X1574930Y1372385D01*
G01X1571430Y1377291D02*
X1572688Y1376033D01*
Y1373543D01*
X1571530Y1372385D01*
G01X1571430Y1379391D02*
X1572692Y1380653D01*
Y1383135D01*
X1571530Y1384297D01*
G01X1575030Y1379391D02*
X1573772Y1380649D01*
Y1383139D01*
X1574930Y1384297D01*
G01X1571430Y1401489D02*
X1572688Y1400231D01*
Y1397741D01*
X1571530Y1396583D01*
G01X1575030Y1401489D02*
X1573768Y1400227D01*
Y1397745D01*
X1574930Y1396583D01*
G01X1571530Y1408495D02*
X1572692Y1407333D01*
Y1404851D01*
X1571430Y1403589D01*
G01X1575030D02*
X1573772Y1404847D01*
Y1407337D01*
X1574930Y1408495D01*
G01X1589506Y-70022D02*
X1592187Y-69306D01*
G01X1589506Y-71990D02*
X1592187Y-72706D01*
G01X1579506Y-33070D02*
X1582187Y-33786D01*
G01X1579506Y-31102D02*
X1582187Y-30386D01*
G01X1587270Y1353093D02*
X1586008Y1351831D01*
Y1349349D01*
X1587170Y1348187D01*
G01X1583670Y1353093D02*
X1584928Y1351835D01*
Y1349345D01*
X1583770Y1348187D01*
G01X1587270Y1355193D02*
X1586012Y1356451D01*
Y1358941D01*
X1587170Y1360099D01*
G01X1583670Y1355193D02*
X1584932Y1356455D01*
Y1358937D01*
X1583770Y1360099D01*
G01X1587270Y1377291D02*
X1586008Y1376029D01*
Y1373547D01*
X1587170Y1372385D01*
G01X1583670Y1377291D02*
X1584928Y1376033D01*
Y1373543D01*
X1583770Y1372385D01*
G01X1583670Y1379391D02*
X1584932Y1380653D01*
Y1383135D01*
X1583770Y1384297D01*
G01X1587270Y1379391D02*
X1586012Y1380649D01*
Y1383139D01*
X1587170Y1384297D01*
G01X1583670Y1401489D02*
X1584928Y1400231D01*
Y1397741D01*
X1583770Y1396583D01*
G01X1587270Y1401489D02*
X1586008Y1400227D01*
Y1397745D01*
X1587170Y1396583D01*
G01X1583670Y1403589D02*
X1584932Y1404851D01*
Y1407333D01*
X1583770Y1408495D01*
G01X1587270Y1403589D02*
X1586012Y1404847D01*
Y1407337D01*
X1587170Y1408495D01*
G01X1617972Y118859D02*
X1616092D01*
X1615431Y119520D01*
X1605550D01*
X1604372Y118342D01*
G01X1617972Y121221D02*
X1616072D01*
X1615451Y120600D01*
X1605514D01*
X1604372Y121742D01*
G01X1617972Y133032D02*
X1616092D01*
X1615424Y133700D01*
X1605557D01*
X1604372Y132515D01*
G01X1617972Y135394D02*
X1616072D01*
X1615458Y134780D01*
X1605507D01*
X1604372Y135915D01*
G01X1607972Y1215452D02*
X1606102Y1217322D01*
G01X1607972Y1211712D02*
X1606102Y1213582D01*
G01X1617972Y111772D02*
X1616079D01*
X1615431Y112420D01*
X1612837D01*
X1611672Y111255D01*
G01X1617972Y114134D02*
Y114135D01*
X1616086D01*
X1615451Y113500D01*
X1612827D01*
X1611672Y114655D01*
G01Y125428D02*
X1612864Y126620D01*
X1615404D01*
X1616079Y125945D01*
X1617972D01*
G01X1611672Y128828D02*
X1612800Y127700D01*
X1615478D01*
X1616085Y128307D01*
X1617972D01*
G01X1614898Y1353093D02*
X1613636Y1351831D01*
Y1349349D01*
X1614798Y1348187D01*
G01X1611298Y1353093D02*
X1612556Y1351835D01*
Y1349345D01*
X1611398Y1348187D01*
G01X1623538Y1353093D02*
X1624796Y1351835D01*
Y1349345D01*
X1623638Y1348187D01*
G01X1627138Y1353093D02*
X1625876Y1351831D01*
Y1349349D01*
X1627038Y1348187D01*
G01X1614898Y1355193D02*
X1613640Y1356451D01*
Y1358941D01*
X1614798Y1360099D01*
G01X1611298Y1355193D02*
X1612560Y1356455D01*
Y1358937D01*
X1611398Y1360099D01*
G01X1623538Y1355193D02*
X1624800Y1356455D01*
Y1358937D01*
X1623638Y1360099D01*
G01X1627138Y1355193D02*
X1625880Y1356451D01*
Y1358941D01*
X1627038Y1360099D01*
G01X1627138Y1377291D02*
X1625876Y1376029D01*
Y1373547D01*
X1627038Y1372385D01*
G01X1623538Y1377291D02*
X1624796Y1376033D01*
Y1373543D01*
X1623638Y1372385D01*
G01X1627138Y1379391D02*
X1625880Y1380649D01*
Y1383139D01*
X1627038Y1384297D01*
G01X1623538Y1379391D02*
X1624800Y1380653D01*
Y1383135D01*
X1623638Y1384297D01*
G01X1611298Y1379391D02*
X1612560Y1380653D01*
Y1383135D01*
X1611398Y1384297D01*
G01X1614898Y1377291D02*
X1613636Y1376029D01*
Y1373547D01*
X1614798Y1372385D01*
G01X1614898Y1379391D02*
X1613640Y1380649D01*
Y1383139D01*
X1614798Y1384297D01*
G01X1611298Y1377291D02*
X1612556Y1376033D01*
Y1373543D01*
X1611398Y1372385D01*
G01X1627138Y1401489D02*
X1625876Y1400227D01*
Y1397745D01*
X1627038Y1396583D01*
G01X1623538Y1401489D02*
X1624796Y1400231D01*
Y1397741D01*
X1623638Y1396583D01*
G01X1627138Y1403589D02*
X1625880Y1404847D01*
Y1407337D01*
X1627038Y1408495D01*
G01X1623538Y1403589D02*
X1624800Y1404851D01*
Y1407333D01*
X1623638Y1408495D01*
G01X1644983Y114723D02*
X1643710Y113450D01*
X1638733D01*
X1638049Y114134D01*
X1636082D01*
G01X1644983Y111123D02*
X1643736Y112370D01*
X1638661D01*
X1638063Y111772D01*
X1636082D01*
G01X1642840Y104249D02*
X1641769Y105320D01*
X1638646D01*
X1638011Y104685D01*
X1636082D01*
G01X1642840Y107649D02*
X1641591Y106400D01*
X1638712D01*
X1638065Y107047D01*
X1636082D01*
G01X1644983Y125296D02*
X1643759Y126520D01*
X1638638D01*
X1638063Y125945D01*
X1636082D01*
G01X1655385Y121835D02*
X1654100Y120550D01*
X1638724D01*
X1638053Y121221D01*
X1636082D01*
G01X1655385Y132409D02*
X1654094Y133700D01*
X1638746D01*
X1638078Y133032D01*
X1636082D01*
G01X1644983Y128896D02*
X1643687Y127600D01*
X1638756D01*
X1638049Y128307D01*
X1636082D01*
G01X1655385Y118235D02*
X1654150Y119470D01*
X1638674D01*
X1638063Y118859D01*
X1636082D01*
G01X1655385Y136009D02*
X1654156Y134780D01*
X1638676D01*
X1638062Y135394D01*
X1636082D01*
G01X1635265Y470737D02*
X1636422Y469580D01*
X1639042D01*
X1639679Y470217D01*
X1641565D01*
G01X1635265Y467337D02*
X1636428Y468500D01*
X1639026D01*
X1639672Y467854D01*
X1641565D01*
G01Y489114D02*
X1639685D01*
X1639079Y489720D01*
X1629088D01*
X1627965Y488597D01*
G01X1641565Y474941D02*
X1639685D01*
X1639046Y475580D01*
X1629121D01*
X1627965Y474424D01*
G01X1635265Y484910D02*
X1636425Y483750D01*
X1639039D01*
X1639679Y484390D01*
X1641565D01*
G01Y477303D02*
X1639665D01*
X1639022Y476660D01*
X1629129D01*
X1627965Y477824D01*
G01X1635265Y481510D02*
X1636425Y482670D01*
X1639029D01*
X1639671Y482028D01*
X1641565D01*
G01Y491476D02*
X1639665D01*
X1638989Y490800D01*
X1629162D01*
X1627965Y491997D01*
G01X1641565Y521437D02*
X1639665D01*
X1639008Y520780D01*
X1629143D01*
X1627965Y521958D01*
G01X1641565Y514350D02*
X1639678D01*
X1639008Y513680D01*
X1636456D01*
X1635265Y514871D01*
G01X1641565Y511988D02*
X1639672D01*
X1639060Y512600D01*
X1636394D01*
X1635265Y511471D01*
G01X1641565Y519075D02*
X1639685D01*
X1639060Y519700D01*
X1629107D01*
X1627965Y518558D01*
G01Y536131D02*
X1629116Y534980D01*
X1639035D01*
X1639665Y535610D01*
X1641565D01*
G01Y528524D02*
X1639679D01*
X1639035Y527880D01*
X1636429D01*
X1635265Y529044D01*
G01X1627965Y532731D02*
X1629134Y533900D01*
X1639033D01*
X1639685Y533248D01*
X1641565D01*
G01Y526162D02*
X1639671D01*
X1639033Y526800D01*
X1636421D01*
X1635265Y525644D01*
G01Y564910D02*
X1636425Y563750D01*
X1639039D01*
X1639679Y564390D01*
X1641565D01*
G01X1627965Y571997D02*
X1629112Y570850D01*
X1639039D01*
X1639665Y571476D01*
X1641565D01*
G01X1627965Y568597D02*
X1629138Y569770D01*
X1639029D01*
X1639685Y569114D01*
X1641565D01*
G01X1635265Y561510D02*
X1636425Y562670D01*
X1639029D01*
X1639671Y562028D01*
X1641565D01*
G01X1635265Y575684D02*
X1636401Y576820D01*
X1639053D01*
X1639672Y576201D01*
X1641565D01*
G01X1635265Y579084D02*
X1636449Y577900D01*
X1639015D01*
X1639678Y578563D01*
X1641565D01*
G01X1627965Y582771D02*
X1629114Y583920D01*
X1639053D01*
X1639685Y583288D01*
X1641565D01*
G01X1627965Y586171D02*
X1629136Y585000D01*
X1639015D01*
X1639665Y585650D01*
X1641565D01*
G01X1627965Y596944D02*
X1629141Y598120D01*
X1639026D01*
X1639685Y597461D01*
X1641565D01*
G01X1627965Y600344D02*
X1629109Y599200D01*
X1639042D01*
X1639665Y599823D01*
X1641565D01*
G01X1635265Y593257D02*
X1636422Y592100D01*
X1639042D01*
X1639678Y592736D01*
X1641565D01*
G01X1635265Y604030D02*
X1636555Y605320D01*
X1638899D01*
X1639672Y604547D01*
X1641565D01*
G01X1635265Y589857D02*
X1636428Y591020D01*
X1639026D01*
X1639672Y590374D01*
X1641565D01*
G01X1635265Y607430D02*
X1636295Y606400D01*
X1639169D01*
X1639679Y606910D01*
X1641565D01*
G01Y613996D02*
X1639665D01*
X1639019Y613350D01*
X1629132D01*
X1627965Y614517D01*
G01X1641565Y611634D02*
X1639685D01*
X1639049Y612270D01*
X1629118D01*
X1627965Y611117D01*
G01X1639378Y1353093D02*
X1638116Y1351831D01*
Y1349349D01*
X1639278Y1348187D01*
G01X1635778Y1353093D02*
X1637036Y1351835D01*
Y1349345D01*
X1635878Y1348187D01*
G01X1639378Y1355193D02*
X1638120Y1356451D01*
Y1358941D01*
X1639278Y1360099D01*
G01X1635778Y1355193D02*
X1637040Y1356455D01*
Y1358937D01*
X1635878Y1360099D01*
G01X1635778Y1379391D02*
X1637040Y1380653D01*
Y1383135D01*
X1635878Y1384297D01*
G01X1639378Y1379391D02*
X1638120Y1380649D01*
Y1383139D01*
X1639278Y1384297D01*
G01X1639378Y1377291D02*
X1638116Y1376029D01*
Y1373547D01*
X1639278Y1372385D01*
G01X1635778Y1377291D02*
X1637036Y1376033D01*
Y1373543D01*
X1635878Y1372385D01*
G01X1639378Y1401489D02*
X1638116Y1400227D01*
Y1397745D01*
X1639278Y1396583D01*
G01X1635778Y1401489D02*
X1637036Y1400231D01*
Y1397741D01*
X1635878Y1396583D01*
G01X1635778Y1403589D02*
X1637040Y1404851D01*
Y1407333D01*
X1635878Y1408495D01*
G01X1639378Y1403589D02*
X1638120Y1404847D01*
Y1407337D01*
X1639278Y1408495D01*
G01X1651989Y114623D02*
X1650816Y113450D01*
X1648356D01*
X1647083Y114723D01*
G01X1651989Y111223D02*
X1650842Y112370D01*
X1648330D01*
X1647083Y111123D01*
G01X1662391Y118335D02*
X1661226Y119500D01*
X1658750D01*
X1657485Y118235D01*
G01X1662391Y121735D02*
X1661236Y120580D01*
X1658740D01*
X1657485Y121835D01*
G01X1662391Y132509D02*
X1661230Y133670D01*
X1658746D01*
X1657485Y132409D01*
G01X1651989Y125396D02*
X1650865Y126520D01*
X1648307D01*
X1647083Y125296D01*
G01X1651989Y128796D02*
X1650793Y127600D01*
X1648379D01*
X1647083Y128896D01*
G01X1662391Y135909D02*
X1661232Y134750D01*
X1658744D01*
X1657485Y136009D01*
G01X1685247Y470806D02*
X1683991Y469550D01*
X1662309D01*
X1661642Y470217D01*
X1659676D01*
G01X1685247Y467206D02*
X1683983Y468470D01*
X1662199D01*
X1661583Y467854D01*
X1659676D01*
G01Y460768D02*
X1661497D01*
X1662149Y461420D01*
X1665069D01*
X1666271Y460218D01*
G01Y463618D02*
X1665153Y462500D01*
X1662237D01*
X1661607Y463130D01*
X1659676D01*
G01X1685247Y481379D02*
X1683976Y482650D01*
X1662278D01*
X1661656Y482028D01*
X1659676D01*
G01X1695649Y477918D02*
X1694361Y476630D01*
X1662328D01*
X1661655Y477303D01*
X1659676D01*
G01X1695649Y474318D02*
X1694417Y475550D01*
X1662280D01*
X1661671Y474941D01*
X1659676D01*
G01X1695649Y488491D02*
X1694340Y489800D01*
X1662357D01*
X1661671Y489114D01*
X1659676D01*
G01X1685247Y484979D02*
X1683998Y483730D01*
X1662302D01*
X1661642Y484390D01*
X1659676D01*
G01X1695649Y492091D02*
X1694438Y490880D01*
X1662251D01*
X1661655Y491476D01*
X1659676D01*
G01X1685247Y514939D02*
X1683958Y513650D01*
X1662342D01*
X1661642Y514350D01*
X1659676D01*
G01X1695649Y522052D02*
X1694377Y520780D01*
X1662312D01*
X1661655Y521437D01*
X1659676D01*
G01X1685247Y511339D02*
X1684016Y512570D01*
X1662238D01*
X1661656Y511988D01*
X1659676D01*
G01X1695649Y518452D02*
X1694401Y519700D01*
X1662296D01*
X1661671Y519075D01*
X1659676D01*
G01X1685247Y529113D02*
X1684014Y527880D01*
X1662286D01*
X1661642Y528524D01*
X1659676D01*
G01X1695649Y532625D02*
X1694374Y533900D01*
X1662323D01*
X1661671Y533248D01*
X1659676D01*
G01X1685247Y525513D02*
X1683960Y526800D01*
X1662294D01*
X1661656Y526162D01*
X1659676D01*
G01X1695649Y536225D02*
X1694404Y534980D01*
X1662285D01*
X1661655Y535610D01*
X1659676D01*
G01X1685247Y561379D02*
X1684006Y562620D01*
X1662248D01*
X1661656Y562028D01*
X1659676D01*
G01X1695649Y568491D02*
X1694420Y569720D01*
X1662277D01*
X1661671Y569114D01*
X1659676D01*
G01X1695649Y572091D02*
X1694358Y570800D01*
X1662331D01*
X1661655Y571476D01*
X1659676D01*
G01X1685247Y564979D02*
X1683968Y563700D01*
X1662332D01*
X1661642Y564390D01*
X1659676D01*
G01X1695649Y586265D02*
X1694384Y585000D01*
X1662305D01*
X1661655Y585650D01*
X1659676D01*
G01X1685247Y575552D02*
X1683979Y576820D01*
X1662275D01*
X1661656Y576201D01*
X1659676D01*
G01X1685247Y579152D02*
X1683995Y577900D01*
X1662305D01*
X1661642Y578563D01*
X1659676D01*
G01X1695649Y582665D02*
X1694394Y583920D01*
X1662303D01*
X1661671Y583288D01*
X1659676D01*
G01X1685247Y589725D02*
X1683952Y591020D01*
X1662302D01*
X1661656Y590374D01*
X1659676D01*
G01X1685247Y593325D02*
X1684022Y592100D01*
X1662278D01*
X1661642Y592736D01*
X1659676D01*
G01X1695649Y600438D02*
X1694411Y599200D01*
X1662278D01*
X1661655Y599823D01*
X1659676D01*
G01X1695649Y596838D02*
X1694367Y598120D01*
X1662330D01*
X1661671Y597461D01*
X1659676D01*
G01X1685247Y603899D02*
X1683946Y605200D01*
X1662328D01*
X1661675Y604547D01*
X1659676D01*
G01X1695649Y611011D02*
X1694390Y612270D01*
X1662307D01*
X1661671Y611634D01*
X1659676D01*
G01X1695649Y614611D02*
X1694388Y613350D01*
X1662301D01*
X1661655Y613996D01*
X1659676D01*
G01X1685247Y607499D02*
X1684028Y606280D01*
X1662272D01*
X1661642Y606910D01*
X1659676D01*
G01X1651618Y1353093D02*
X1650356Y1351831D01*
Y1349349D01*
X1651518Y1348187D01*
G01X1648018Y1353093D02*
X1649276Y1351835D01*
Y1349345D01*
X1648118Y1348187D01*
G01X1651618Y1355193D02*
X1650360Y1356451D01*
Y1358941D01*
X1651518Y1360099D01*
G01X1648018Y1355193D02*
X1649280Y1356455D01*
Y1358937D01*
X1648118Y1360099D01*
G01X1648018Y1377291D02*
X1649276Y1376033D01*
Y1373543D01*
X1648118Y1372385D01*
G01X1651618Y1377291D02*
X1650356Y1376029D01*
Y1373547D01*
X1651518Y1372385D01*
G01X1648018Y1379391D02*
X1649280Y1380653D01*
Y1383135D01*
X1648118Y1384297D01*
G01X1651618Y1379391D02*
X1650360Y1380649D01*
Y1383139D01*
X1651518Y1384297D01*
G01X1651618Y1401489D02*
X1650356Y1400227D01*
Y1397745D01*
X1651518Y1396583D01*
G01X1648018Y1401489D02*
X1649276Y1400231D01*
Y1397741D01*
X1648118Y1396583D01*
G01X1648018Y1403589D02*
X1649280Y1404851D01*
Y1407333D01*
X1648118Y1408495D01*
G01X1651618Y1403589D02*
X1650360Y1404847D01*
Y1407337D01*
X1651518Y1408495D01*
G01X1663858Y1353093D02*
X1662596Y1351831D01*
Y1349349D01*
X1663758Y1348187D01*
G01X1660258Y1353093D02*
X1661516Y1351835D01*
Y1349345D01*
X1660358Y1348187D01*
G01X1672498Y1353093D02*
X1673756Y1351835D01*
Y1349345D01*
X1672598Y1348187D01*
G01X1676098Y1353093D02*
X1674836Y1351831D01*
Y1349349D01*
X1675998Y1348187D01*
G01X1663858Y1355193D02*
X1662600Y1356451D01*
Y1358941D01*
X1663758Y1360099D01*
G01X1660258Y1355193D02*
X1661520Y1356455D01*
Y1358937D01*
X1660358Y1360099D01*
G01X1676098Y1355193D02*
X1674840Y1356451D01*
Y1358941D01*
X1675998Y1360099D01*
G01X1672498Y1355193D02*
X1673760Y1356455D01*
Y1358937D01*
X1672598Y1360099D01*
G01X1676098Y1377291D02*
X1674836Y1376029D01*
Y1373547D01*
X1675998Y1372385D01*
G01X1672498Y1377291D02*
X1673756Y1376033D01*
Y1373543D01*
X1672598Y1372385D01*
G01X1672498Y1379391D02*
X1673760Y1380653D01*
Y1383135D01*
X1672598Y1384297D01*
G01X1676098Y1379391D02*
X1674840Y1380649D01*
Y1383139D01*
X1675998Y1384297D01*
G01X1663858Y1379391D02*
X1662600Y1380649D01*
Y1383139D01*
X1663758Y1384297D01*
G01X1660258Y1379391D02*
X1661520Y1380653D01*
Y1383135D01*
X1660358Y1384297D01*
G01X1660258Y1377291D02*
X1661516Y1376033D01*
Y1373543D01*
X1660358Y1372385D01*
G01X1663858Y1377291D02*
X1662596Y1376029D01*
Y1373547D01*
X1663758Y1372385D01*
G01X1663858Y1401489D02*
X1662596Y1400227D01*
Y1397745D01*
X1663758Y1396583D01*
G01X1660258Y1401489D02*
X1661516Y1400231D01*
Y1397741D01*
X1660358Y1396583D01*
G01X1676098Y1401489D02*
X1674836Y1400227D01*
Y1397745D01*
X1675998Y1396583D01*
G01X1672498Y1401489D02*
X1673756Y1400231D01*
Y1397741D01*
X1672598Y1396583D01*
G01X1660258Y1403589D02*
X1661520Y1404851D01*
Y1407333D01*
X1660358Y1408495D01*
G01X1663858Y1403589D02*
X1662600Y1404847D01*
Y1407337D01*
X1663758Y1408495D01*
G01X1676098Y1403589D02*
X1674840Y1404847D01*
Y1407337D01*
X1675998Y1408495D01*
G01X1672498Y1403589D02*
X1673760Y1404851D01*
Y1407333D01*
X1672598Y1408495D01*
G01X1692253Y467306D02*
X1691109Y468450D01*
X1688591D01*
X1687347Y467206D01*
G01X1692253Y470706D02*
X1691077Y469530D01*
X1688623D01*
X1687347Y470806D01*
G01X1692253Y484879D02*
X1691096Y483722D01*
X1688604D01*
X1687347Y484979D01*
G01X1692253Y481479D02*
X1691090Y482642D01*
X1688610D01*
X1687347Y481379D01*
G01X1692253Y511439D02*
X1691092Y512600D01*
X1688608D01*
X1687347Y511339D01*
G01X1692253Y514839D02*
X1691094Y513680D01*
X1688606D01*
X1687347Y514939D01*
G01X1692253Y529013D02*
X1691120Y527880D01*
X1688580D01*
X1687347Y529113D01*
G01X1692253Y525613D02*
X1691066Y526800D01*
X1688634D01*
X1687347Y525513D01*
G01X1692253Y561479D02*
X1691112Y562620D01*
X1688588D01*
X1687347Y561379D01*
G01X1692253Y564879D02*
X1691074Y563700D01*
X1688626D01*
X1687347Y564979D01*
G01X1692253Y575652D02*
X1691105Y576800D01*
X1688595D01*
X1687347Y575552D01*
G01X1692253Y579052D02*
X1691081Y577880D01*
X1688619D01*
X1687347Y579152D01*
G01X1692253Y593225D02*
X1691128Y592100D01*
X1688572D01*
X1687347Y593325D01*
G01X1692253Y603999D02*
X1691132Y605120D01*
X1688568D01*
X1687347Y603899D01*
G01X1692253Y589825D02*
X1691058Y591020D01*
X1688642D01*
X1687347Y589725D01*
G01X1692253Y607399D02*
X1691054Y606200D01*
X1688646D01*
X1687347Y607499D01*
G01X1688338Y1353093D02*
X1687076Y1351831D01*
Y1349349D01*
X1688238Y1348187D01*
G01X1684738Y1353093D02*
X1685996Y1351835D01*
Y1349345D01*
X1684838Y1348187D01*
G01X1688338Y1355193D02*
X1687080Y1356451D01*
Y1358941D01*
X1688238Y1360099D01*
G01X1684738Y1355193D02*
X1686000Y1356455D01*
Y1358937D01*
X1684838Y1360099D01*
G01X1684738Y1379391D02*
X1686000Y1380653D01*
Y1383135D01*
X1684838Y1384297D01*
G01X1688338Y1379391D02*
X1687080Y1380649D01*
Y1383139D01*
X1688238Y1384297D01*
G01X1684738Y1377291D02*
X1685996Y1376033D01*
Y1373543D01*
X1684838Y1372385D01*
G01X1688338Y1377291D02*
X1687076Y1376029D01*
Y1373547D01*
X1688238Y1372385D01*
G01X1684738Y1401489D02*
X1685996Y1400231D01*
Y1397741D01*
X1684838Y1396583D01*
G01X1688338Y1401489D02*
X1687076Y1400227D01*
Y1397745D01*
X1688238Y1396583D01*
G01X1688338Y1403589D02*
X1687080Y1404847D01*
Y1407337D01*
X1688238Y1408495D01*
G01X1684738Y1403589D02*
X1686000Y1404851D01*
Y1407333D01*
X1684838Y1408495D01*
G01X1720334Y118859D02*
X1718454D01*
X1717813Y119500D01*
X1707892D01*
X1706734Y118342D01*
G01X1720334Y133032D02*
X1718454D01*
X1717836Y133650D01*
X1707869D01*
X1706734Y132515D01*
G01X1720334Y121221D02*
X1718434D01*
X1717793Y120580D01*
X1707896D01*
X1706734Y121742D01*
G01X1720334Y135394D02*
X1718434D01*
X1717770Y134730D01*
X1707919D01*
X1706734Y135915D01*
G01X1702655Y477818D02*
X1701517Y476680D01*
X1698987D01*
X1697749Y477918D01*
G01X1702655Y474418D02*
X1701473Y475600D01*
X1699031D01*
X1697749Y474318D01*
G01X1702655Y488591D02*
X1701496Y489750D01*
X1699008D01*
X1697749Y488491D01*
G01X1702655Y491991D02*
X1701494Y490830D01*
X1699010D01*
X1697749Y492091D01*
G01X1702655Y521952D02*
X1701483Y520780D01*
X1699021D01*
X1697749Y522052D01*
G01X1702655Y518552D02*
X1701507Y519700D01*
X1698997D01*
X1697749Y518452D01*
G01X1702655Y536125D02*
X1701510Y534980D01*
X1698994D01*
X1697749Y536225D01*
G01X1702655Y532725D02*
X1701480Y533900D01*
X1699024D01*
X1697749Y532625D01*
G01X1702655Y571991D02*
X1701494Y570830D01*
X1699010D01*
X1697749Y572091D01*
G01X1702655Y568591D02*
X1701496Y569750D01*
X1699008D01*
X1697749Y568491D01*
G01X1702655Y586165D02*
X1701490Y585000D01*
X1699014D01*
X1697749Y586265D01*
G01X1702655Y582765D02*
X1701500Y583920D01*
X1699004D01*
X1697749Y582665D01*
G01X1702655Y600338D02*
X1701517Y599200D01*
X1698987D01*
X1697749Y600438D01*
G01X1702655Y596938D02*
X1701473Y598120D01*
X1699031D01*
X1697749Y596838D01*
G01X1702655Y611111D02*
X1701466Y612300D01*
X1699038D01*
X1697749Y611011D01*
G01X1702655Y614511D02*
X1701524Y613380D01*
X1698980D01*
X1697749Y614611D01*
G01X1700578Y1353093D02*
X1699316Y1351831D01*
Y1349349D01*
X1700478Y1348187D01*
G01X1696978Y1353093D02*
X1698236Y1351835D01*
Y1349345D01*
X1697078Y1348187D01*
G01X1696978Y1355193D02*
X1698240Y1356455D01*
Y1358937D01*
X1697078Y1360099D01*
G01X1700578Y1355193D02*
X1699320Y1356451D01*
Y1358941D01*
X1700478Y1360099D01*
G01X1696978Y1377291D02*
X1698236Y1376033D01*
Y1373543D01*
X1697078Y1372385D01*
G01X1700578Y1377291D02*
X1699316Y1376029D01*
Y1373547D01*
X1700478Y1372385D01*
G01X1696978Y1379391D02*
X1698240Y1380653D01*
Y1383135D01*
X1697078Y1384297D01*
G01X1700578Y1379391D02*
X1699320Y1380649D01*
Y1383139D01*
X1700478Y1384297D01*
G01X1700578Y1401489D02*
X1699316Y1400227D01*
Y1397745D01*
X1700478Y1396583D01*
G01X1696978Y1401489D02*
X1698236Y1400231D01*
Y1397741D01*
X1697078Y1396583D01*
G01X1696978Y1403589D02*
X1698240Y1404851D01*
Y1407333D01*
X1697078Y1408495D01*
G01X1700578Y1403589D02*
X1699320Y1404847D01*
Y1407337D01*
X1700478Y1408495D01*
G01X1720334Y111772D02*
X1718441D01*
X1717813Y112400D01*
X1715179D01*
X1714034Y111255D01*
G01X1720334Y114134D02*
Y114135D01*
X1718448D01*
X1717793Y113480D01*
X1715209D01*
X1714034Y114655D01*
G01X1720334Y125945D02*
X1718441D01*
X1717786Y126600D01*
X1715206D01*
X1714034Y125428D01*
G01X1720334Y128307D02*
X1718447D01*
X1717820Y127680D01*
X1715182D01*
X1714034Y128828D01*
G01X1709218Y1353093D02*
X1710476Y1351835D01*
Y1349345D01*
X1709318Y1348187D01*
G01X1712818Y1353093D02*
X1711556Y1351831D01*
Y1349349D01*
X1712718Y1348187D01*
G01X1721458Y1353093D02*
X1722716Y1351835D01*
Y1349345D01*
X1721558Y1348187D01*
G01X1725058Y1353093D02*
X1723796Y1351831D01*
Y1349349D01*
X1724958Y1348187D01*
G01X1712818Y1355193D02*
X1711560Y1356451D01*
Y1358941D01*
X1712718Y1360099D01*
G01X1709218Y1355193D02*
X1710480Y1356455D01*
Y1358937D01*
X1709318Y1360099D01*
G01X1725058Y1355193D02*
X1723800Y1356451D01*
Y1358941D01*
X1724958Y1360099D01*
G01X1721458Y1355193D02*
X1722720Y1356455D01*
Y1358937D01*
X1721558Y1360099D01*
G01X1721458Y1377291D02*
X1722716Y1376033D01*
Y1373543D01*
X1721558Y1372385D01*
G01X1725058Y1377291D02*
X1723796Y1376029D01*
Y1373547D01*
X1724958Y1372385D01*
G01X1725058Y1379391D02*
X1723800Y1380649D01*
Y1383139D01*
X1724958Y1384297D01*
G01X1721458Y1379391D02*
X1722720Y1380653D01*
Y1383135D01*
X1721558Y1384297D01*
G01X1709218Y1379391D02*
X1710480Y1380653D01*
Y1383135D01*
X1709318Y1384297D01*
G01X1712818Y1377291D02*
X1711556Y1376029D01*
Y1373547D01*
X1712718Y1372385D01*
G01X1712818Y1379391D02*
X1711560Y1380649D01*
Y1383139D01*
X1712718Y1384297D01*
G01X1709218Y1377291D02*
X1710476Y1376033D01*
Y1373543D01*
X1709318Y1372385D01*
G01X1712818Y1401489D02*
X1711556Y1400227D01*
Y1397745D01*
X1712718Y1396583D01*
G01X1709218Y1401489D02*
X1710476Y1400231D01*
Y1397741D01*
X1709318Y1396583D01*
G01X1721458Y1401489D02*
X1722716Y1400231D01*
Y1397741D01*
X1721558Y1396583D01*
G01X1725058Y1401489D02*
X1723796Y1400227D01*
Y1397745D01*
X1724958Y1396583D01*
G01X1712818Y1403589D02*
X1711560Y1404847D01*
Y1407337D01*
X1712718Y1408495D01*
G01X1709218Y1403589D02*
X1710480Y1404851D01*
Y1407333D01*
X1709318Y1408495D01*
G01X1721458Y1403589D02*
X1722720Y1404851D01*
Y1407333D01*
X1721558Y1408495D01*
G01X1725058Y1403589D02*
X1723800Y1404847D01*
Y1407337D01*
X1724958Y1408495D01*
G01X1739086Y-69994D02*
X1736405Y-69278D01*
G01X1739086Y-71962D02*
X1736405Y-72678D01*
G01X1747345Y114723D02*
X1746102Y113480D01*
X1741065D01*
X1740411Y114134D01*
X1738444D01*
G01X1747345Y111123D02*
X1746068Y112400D01*
X1741053D01*
X1740425Y111772D01*
X1738444D01*
G01X1745202Y104249D02*
X1744131Y105320D01*
X1741008D01*
X1740373Y104685D01*
X1738444D01*
G01X1745202Y107649D02*
X1743953Y106400D01*
X1741074D01*
X1740427Y107047D01*
X1738444D01*
G01X1757747Y121835D02*
X1756492Y120580D01*
X1741056D01*
X1740415Y121221D01*
X1738444D01*
G01X1747345Y125296D02*
X1746121Y126520D01*
X1741000D01*
X1740425Y125945D01*
X1738444D01*
G01X1757747Y132409D02*
X1756486Y133670D01*
X1741078D01*
X1740440Y133032D01*
X1738444D01*
G01X1757747Y118235D02*
X1756482Y119500D01*
X1741066D01*
X1740425Y118859D01*
X1738444D01*
G01X1747345Y128896D02*
X1746049Y127600D01*
X1741118D01*
X1740411Y128307D01*
X1738444D01*
G01X1757747Y136009D02*
X1756488Y134750D01*
X1741068D01*
X1740424Y135394D01*
X1738444D01*
G01X1733698Y1353093D02*
X1734956Y1351835D01*
Y1349345D01*
X1733798Y1348187D01*
G01X1737298Y1353093D02*
X1736036Y1351831D01*
Y1349349D01*
X1737198Y1348187D01*
G01X1733698Y1355193D02*
X1734960Y1356455D01*
Y1358937D01*
X1733798Y1360099D01*
G01X1737298Y1355193D02*
X1736040Y1356451D01*
Y1358941D01*
X1737198Y1360099D01*
G01X1737298Y1379391D02*
X1736040Y1380649D01*
Y1383139D01*
X1737198Y1384297D01*
G01X1733698Y1379391D02*
X1734960Y1380653D01*
Y1383135D01*
X1733798Y1384297D01*
G01X1733698Y1377291D02*
X1734956Y1376033D01*
Y1373543D01*
X1733798Y1372385D01*
G01X1737298Y1377291D02*
X1736036Y1376029D01*
Y1373547D01*
X1737198Y1372385D01*
G01X1737298Y1401489D02*
X1736036Y1400227D01*
Y1397745D01*
X1737198Y1396583D01*
G01X1733698Y1401489D02*
X1734956Y1400231D01*
Y1397741D01*
X1733798Y1396583D01*
G01X1737298Y1403589D02*
X1736040Y1404847D01*
Y1407337D01*
X1737198Y1408495D01*
G01X1733698Y1403589D02*
X1734960Y1404851D01*
Y1407333D01*
X1733798Y1408495D01*
G01X1754351Y111223D02*
X1753174Y112400D01*
X1750722D01*
X1749445Y111123D01*
G01X1754351Y114623D02*
X1753208Y113480D01*
X1750688D01*
X1749445Y114723D01*
G01X1754351Y128796D02*
X1753185Y127630D01*
X1750711D01*
X1749445Y128896D01*
G01X1754351Y125396D02*
X1753197Y126550D01*
X1750699D01*
X1749445Y125296D01*
G01X1760932Y824383D02*
X1759749Y823200D01*
X1756039D01*
X1754906Y824333D01*
G01X1760932Y820883D02*
X1759695Y822120D01*
X1756093D01*
X1754906Y820933D01*
Y820737D01*
G01X1764753Y121735D02*
X1763618Y120600D01*
X1761082D01*
X1759847Y121835D01*
G01X1764753Y118335D02*
X1763568Y119520D01*
X1761132D01*
X1759847Y118235D01*
G01X1764753Y132509D02*
X1763592Y133670D01*
X1761108D01*
X1759847Y132409D01*
G01X1764753Y135909D02*
X1763594Y134750D01*
X1761106D01*
X1759847Y136009D01*
G01X1783471Y826570D02*
X1780081Y823180D01*
X1765285D01*
X1764082Y824383D01*
G01X1783471Y818696D02*
X1780067Y822100D01*
X1765299D01*
X1764082Y820883D01*
G01X1768205Y912920D02*
Y914271D01*
X1768649Y914715D01*
Y918656D01*
X1766824Y920481D01*
Y922564D01*
X1765664Y923724D01*
G01X1770173Y912920D02*
Y914271D01*
X1769729Y914715D01*
Y919104D01*
X1767904Y920929D01*
Y922564D01*
X1769064Y923724D01*
G01X1783471Y826570D02*
X1786861Y823180D01*
X1793283D01*
X1794001Y823898D01*
X1796437D01*
G01X1783471Y818696D02*
X1786875Y822100D01*
X1793262D01*
X1794023Y821339D01*
X1796437D01*
G01X1804442Y-33172D02*
X1801761Y-33888D01*
G01X1804442Y-31204D02*
X1801761Y-30488D01*
G54D267*
G01X9364Y105001D02*
Y107501D01*
G01X8460Y111710D02*
Y109993D01*
X6214Y107747D01*
Y105001D01*
G01X8000Y102500D02*
X6214Y104286D01*
Y105001D01*
G01X9745Y252371D02*
Y254096D01*
X8970Y254871D01*
G01X9745Y272371D02*
X7036D01*
G01X10952Y1480986D02*
Y1479361D01*
X13606Y1476707D01*
G01D02*
X20852D01*
X21544Y1477399D01*
Y1479662D01*
G01X6690Y1496782D02*
X5933Y1496025D01*
Y1478560D01*
X7786Y1476707D01*
X13606D01*
G01X9115Y1496782D02*
X6690D01*
G01X19365Y1494298D02*
Y1496782D01*
G01X17644Y1489648D02*
X21544D01*
G01X27966Y236109D02*
Y238689D01*
G01X32201Y236134D02*
Y238714D01*
G01X21544Y1489648D02*
Y1479662D01*
G01X39452Y1248448D02*
Y1250932D01*
G01X60098Y97599D02*
X63911D01*
X64863Y98551D01*
X70577D01*
G01X67659Y1079656D02*
X70059D01*
G01X80809Y168697D02*
X83756D01*
G01X90563Y996129D02*
X94821Y1000387D01*
X98971D01*
X101260Y1002676D01*
G01X112107Y248371D02*
X109329D01*
G01X125861Y121934D02*
X123599Y119672D01*
G01X124780Y134838D02*
Y129084D01*
X125861Y128003D01*
Y121934D01*
G01X130328Y236109D02*
Y238689D01*
G01X134563Y236134D02*
Y238714D01*
G01X162460Y97599D02*
X166273D01*
X167225Y98551D01*
X172939D01*
G01X160039Y1135039D02*
X158169Y1133169D01*
G01X188526Y108237D02*
X188008D01*
X185957Y106186D01*
G01X183171Y168697D02*
X186118D01*
G01X186220Y1183661D02*
X184350Y1185531D01*
G01X206398Y58013D02*
Y55513D01*
G01X203248Y58013D02*
X202994Y58267D01*
Y64722D01*
G01X203248Y55513D02*
Y58013D01*
G01X228223Y121934D02*
X225961Y119672D01*
G01X227142Y134838D02*
Y129084D01*
X228223Y128003D01*
Y121934D01*
G01X232690Y236109D02*
Y238689D01*
G01X236925Y236134D02*
Y238714D01*
G01X264822Y97599D02*
X268635D01*
X269587Y98551D01*
X275301D01*
G01X290888Y108237D02*
X290370D01*
X288319Y106186D01*
G01X285533Y168697D02*
X288480D01*
G01X308760Y58013D02*
Y55513D01*
G01X305610Y58013D02*
X305356Y58267D01*
Y64722D01*
G01X305610Y55513D02*
Y58013D01*
G01X303285Y342319D02*
X306812D01*
G01X317333Y350850D02*
X314181D01*
X311947Y348616D01*
Y347437D01*
G01X328323Y119672D02*
X330585Y121934D01*
G01D02*
Y128003D01*
X329504Y129084D01*
Y134838D01*
G01X335052Y236109D02*
Y238689D01*
G01X339287Y236134D02*
Y238714D01*
G01X354486Y379573D02*
Y377173D01*
G01X367184Y97599D02*
X370997D01*
X371949Y98551D01*
X377663D01*
G01X386112Y30618D02*
X383612D01*
G01Y33768D02*
X386112D01*
G01D02*
X386366Y34022D01*
X392821D01*
G01X393250Y108237D02*
X392732D01*
X390681Y106186D01*
G01X387895Y168697D02*
X390842D01*
G01X389237Y376629D02*
X390785D01*
X391737Y377581D01*
G01X387493Y380185D02*
Y378373D01*
X389237Y376629D01*
G01X384537Y480638D02*
X386349D01*
X388093Y482382D01*
G01D02*
Y483930D01*
X387141Y484882D01*
G01X389595Y864408D02*
X386589D01*
G01X389620Y868286D02*
X386614D01*
G01X400728Y344439D02*
X397374D01*
G01X400728Y349939D02*
Y353152D01*
G01X398834Y864409D02*
X396306D01*
G01X396945Y971780D02*
X393998D01*
G01X420013Y834800D02*
X422430D01*
G01X441832Y626193D02*
X442540Y625485D01*
X445745D01*
G01X445411Y711199D02*
X447836D01*
G01X456210Y1004680D02*
Y1007180D01*
G01X453710Y1016325D02*
Y1018825D01*
G01Y1012325D02*
Y1016325D01*
G01X445516Y1022766D02*
X443091D01*
G01X445516Y1026266D02*
X443091D01*
G01X445516Y1030266D02*
X443091D01*
G01X445516Y1034266D02*
X443091D01*
G01X465978Y491669D02*
X468558D01*
G01X465978Y503669D02*
X468558D01*
G01X465978Y495669D02*
X468558D01*
G01X465978Y507669D02*
X468558D01*
G01X465978Y512669D02*
X468558D01*
G01X465978Y516609D02*
X468558D01*
G01X480586Y121934D02*
X478324Y119672D01*
G01X479505Y134838D02*
Y129084D01*
X480586Y128003D01*
Y121934D01*
G01X485053Y236109D02*
Y238689D01*
G01X489288Y236134D02*
Y238714D01*
G01X504166Y1000766D02*
X506566D01*
G01X504166Y1004766D02*
X506566D01*
G01X504166Y1008766D02*
X506566D01*
G01X504166Y996766D02*
X506566D01*
G01X504166Y1016266D02*
X506566D01*
G01X504166Y1012266D02*
X506566D01*
G01X504166Y1030766D02*
X506566D01*
G01X517185Y97599D02*
X520998D01*
X521950Y98551D01*
X527664D01*
G01X512166Y1000766D02*
X514566D01*
G01X512166Y1016266D02*
X514566D01*
G01X537896Y168697D02*
X540843D01*
G01X543251Y108237D02*
X542733D01*
X540682Y106186D01*
G01X548761Y350223D02*
X551536D01*
G01X555104Y846389D02*
Y841985D01*
X555701Y841388D01*
G01X557836Y851669D02*
X556779D01*
X555104Y849994D01*
Y846389D01*
G01X561123Y58013D02*
Y55513D01*
G01X557973D02*
Y58013D01*
G01D02*
X557719Y58267D01*
Y64722D01*
G01X581867Y134838D02*
Y129084D01*
X582948Y128003D01*
Y121934D01*
G01D02*
X580686Y119672D01*
G01X587415Y236109D02*
Y238689D01*
G01X591650Y236134D02*
Y238714D01*
G01X592103Y949646D02*
X596871D01*
G01X619547Y97599D02*
X623360D01*
X624312Y98551D01*
X630026D01*
G01X645613Y108237D02*
X645095D01*
X643044Y106186D01*
G01X640258Y168697D02*
X643205D01*
G01X647361Y653161D02*
X643933D01*
G01X657967Y660402D02*
X656195D01*
X654072Y658279D01*
X652595D01*
G01X643307Y1183661D02*
X641437Y1185531D01*
G01X663485Y58013D02*
X665493D01*
X666209Y57297D01*
G01X660335Y58013D02*
X660081Y58267D01*
Y64722D01*
G01X657507Y58013D02*
X660335D01*
G01X656650Y694797D02*
Y692344D01*
X656157Y691851D01*
G01X661768Y702277D02*
Y705043D01*
G01X685310Y121934D02*
X683048Y119672D01*
G01X684229Y134838D02*
Y129084D01*
X685310Y128003D01*
Y121934D01*
G01X689777Y236109D02*
Y238689D01*
G01X694012Y236134D02*
Y238714D01*
G01X710643Y456335D02*
X707473D01*
X706211Y457597D01*
Y458859D01*
G01X709194Y762140D02*
X705975D01*
X704446Y760611D01*
G01X721909Y97599D02*
X725722D01*
X726674Y98551D01*
X732388D01*
G01X723811Y738981D02*
X726588Y736204D01*
X729727D01*
G01X747975Y108237D02*
X747457D01*
X745406Y106186D01*
G01X742620Y168697D02*
X745567D01*
G01X740640Y1586885D02*
X743140D01*
Y1587669D01*
X745964Y1590493D01*
Y1594417D01*
G01X748924Y1614943D02*
Y1617709D01*
G01X765847Y58013D02*
Y55513D01*
G01X762697Y58013D02*
X762443Y58267D01*
Y64722D01*
G01X762697Y55513D02*
Y58013D01*
G01X760371Y342319D02*
X763898D01*
G01X751140Y1583735D02*
Y1581335D01*
G01X774419Y350850D02*
X769571D01*
X769033Y350312D01*
Y347437D01*
G01X771557Y1449870D02*
Y1446818D01*
G01X787672Y121934D02*
X785410Y119672D01*
G01X786591Y134838D02*
Y129084D01*
X787672Y128003D01*
Y121934D01*
G01X792139Y236109D02*
Y238689D01*
G01X796374Y236134D02*
Y238714D01*
G01X824271Y97599D02*
X828084D01*
X829036Y98551D01*
X834750D01*
G01X826925Y758500D02*
X825500D01*
X824500Y759500D01*
Y760500D01*
G01X826925Y762500D02*
Y758500D01*
G01Y780500D02*
Y776500D01*
G01D02*
X825500D01*
X824500Y777500D01*
Y778500D01*
G01X826925Y794500D02*
Y798500D01*
G01X824500Y796500D02*
X824925D01*
X826925Y794500D01*
G01X824500Y814500D02*
Y813500D01*
X825500Y812500D01*
X826925D01*
G01D02*
Y816500D01*
G01X850337Y108237D02*
X849819D01*
X847768Y106186D01*
G01X844982Y168697D02*
X847929D01*
G01X841623Y475638D02*
X843435D01*
X845179Y477382D01*
G01D02*
Y478930D01*
X844227Y479882D01*
G01X858586Y387425D02*
X858400Y387239D01*
Y385186D01*
X858586Y385000D01*
G01X863443Y753254D02*
X864575Y754386D01*
Y756000D01*
G01X865830Y961600D02*
X863677Y959447D01*
Y945050D01*
X870526Y938201D01*
X883094D01*
X885947Y935348D01*
X924262D01*
X928574Y939660D01*
Y948023D01*
X934928Y954377D01*
G01X868209Y58013D02*
Y55513D01*
G01X865059Y58013D02*
X864805Y58267D01*
Y64722D01*
G01X865059Y55513D02*
Y58013D01*
G01X864575Y756000D02*
Y760000D01*
G01D02*
Y764000D01*
G01Y782000D02*
Y778000D01*
G01D02*
Y774000D01*
G01D02*
X867000D01*
G01X864575Y800000D02*
Y796000D01*
G01D02*
Y792000D01*
G01D02*
X867000D01*
G01X864575Y818000D02*
Y814000D01*
G01D02*
Y810000D01*
G01D02*
X867000D01*
G01X898692Y859465D02*
X897118Y857891D01*
G01X898692Y856316D02*
X897118Y854742D01*
G01X895542Y862615D02*
X893968Y864189D01*
G01X895542Y859465D02*
X893968Y857891D01*
G01X895542Y856316D02*
X893968Y854742D01*
G01X889243Y853166D02*
X887669Y851592D01*
G01X892392Y856316D02*
X890818Y854742D01*
G01X889243Y856316D02*
X887669Y854742D01*
G01X898692Y850016D02*
X897118Y848442D01*
G01X898692Y853166D02*
X897118Y851592D01*
G01X892392Y862615D02*
X890818Y864189D01*
G01X892392Y859465D02*
X890818Y857891D01*
G01X898692Y862615D02*
X897118Y864189D01*
G01X898692Y872064D02*
X897118Y873638D01*
G01X898692Y868914D02*
X897118Y870488D01*
G01X898692Y865764D02*
X897118Y867338D01*
G01X895542Y868914D02*
X893968Y870488D01*
G01X895542Y872064D02*
X893968Y873638D01*
G01X895542Y865764D02*
X893968Y867338D01*
G01X889243Y875213D02*
X887669Y876787D01*
G01X889243Y865764D02*
X887669Y867338D01*
G01X892392Y868914D02*
X890818Y870488D01*
G01X889243Y868914D02*
X887669Y870488D01*
G01X898692Y875213D02*
X897118Y876787D01*
G01X892392Y865764D02*
X890818Y867338D01*
G01X883142Y1257451D02*
Y1259935D01*
G01X909785Y810778D02*
X908266Y807110D01*
Y803985D01*
X908936Y803315D01*
X911416D01*
G01X911290Y846867D02*
X912864Y845293D01*
G01X911290Y843717D02*
X912864Y842143D01*
G01X908140Y846867D02*
X909714Y845293D01*
G01X908140Y843717D02*
X909714Y842143D01*
G01X908140Y840568D02*
X909714Y838994D01*
G01X904991Y850016D02*
X906565Y848442D01*
G01X901841Y850016D02*
X900267Y848442D01*
G01X904991Y840568D02*
X906565Y838994D01*
G01X901841Y862615D02*
X900267Y864189D01*
G01X908140Y856316D02*
X909714Y854742D01*
G01X904991Y859465D02*
X906565Y857891D01*
G01X908140Y859465D02*
X909714Y857891D01*
G01X904991Y862615D02*
X906565Y864189D01*
G01X908140Y862615D02*
X909714Y864189D01*
G01X911290Y850016D02*
X912864Y848442D01*
G01X904991Y856316D02*
X906565Y854742D01*
G01X901841Y859465D02*
X900267Y857891D01*
G01X901841Y856316D02*
X900267Y854742D01*
G01X911290Y853166D02*
X912864Y851592D01*
G01X911290Y862615D02*
X912864Y864189D01*
G01X911290Y859465D02*
X912864Y857891D01*
G01X911290Y856316D02*
X912864Y854742D01*
G01X901841Y853166D02*
X900267Y851592D01*
G01X904991Y853166D02*
X906565Y851592D01*
G01X908140Y872064D02*
X909714Y873638D01*
G01X908140Y868914D02*
X909714Y870488D01*
G01X904991Y872064D02*
X906565Y873638D01*
G01X904991Y868914D02*
X906565Y870488D01*
G01X904991Y865764D02*
X906565Y867338D01*
G01X901841Y872064D02*
X900267Y873638D01*
G01X901841Y868914D02*
X900267Y870488D01*
G01X901841Y865764D02*
X900267Y867338D01*
G01X908140Y865764D02*
X909714Y867338D01*
G01X911290Y868914D02*
X912864Y870488D01*
G01X911290Y865764D02*
X912864Y867338D01*
G01X908140Y875213D02*
X909714Y876787D01*
G01X901841Y875213D02*
X900267Y876787D01*
G01X904991Y875213D02*
X906565Y876787D01*
G01X911290Y872064D02*
X912864Y873638D01*
G01X910633Y1222799D02*
X908852Y1224580D01*
Y1224933D01*
G01X929227Y581578D02*
X931627D01*
G01X928612Y835844D02*
X927038Y837418D01*
G01X914440Y850016D02*
X916014Y848442D01*
G01X920739Y853166D02*
X922313Y851592D01*
G01X920739Y850016D02*
Y850018D01*
X922313Y851592D01*
G01X917589Y856316D02*
X919163Y854742D01*
G01X917589Y859465D02*
X919163Y857891D01*
G01X920739Y856316D02*
X922313Y854742D01*
G01X914440Y859465D02*
X916014Y857891D01*
G01X914440Y856316D02*
X916014Y854742D01*
G01X914440Y853166D02*
X916014Y851592D01*
G01X914440Y862615D02*
X916014Y864189D01*
G01X923888Y853166D02*
X925462Y851592D01*
G01X939269Y868921D02*
X938051D01*
X934322Y865192D01*
X931860Y859248D01*
Y857379D01*
X930793Y856312D01*
X930783Y856316D01*
X927038D01*
G01X914440Y868914D02*
X916014Y870488D01*
G01X914440Y865764D02*
X916014Y867338D01*
G01X914349Y1088659D02*
X916749D01*
G01X937672Y121934D02*
X935410Y119672D01*
G01X936591Y134838D02*
Y129084D01*
X937672Y128003D01*
Y121934D01*
G01X942805Y221280D02*
Y223860D01*
G01X945718Y236866D02*
Y232961D01*
X940696Y227939D01*
X934457D01*
X933403Y228993D01*
Y245507D01*
G01X944695Y874268D02*
Y872105D01*
X941511Y868921D01*
X939269D01*
G01X947040Y221305D02*
Y223885D01*
G01X947119Y1257451D02*
Y1259935D01*
G01X974271Y97599D02*
X978084D01*
X979036Y98551D01*
X984750D01*
G01X990699Y806295D02*
Y813120D01*
X990051Y813768D01*
G01X981628Y837159D02*
X979203D01*
G01X978326Y1088659D02*
X980726D01*
G01X1000337Y108237D02*
X999819D01*
X997768Y106186D01*
G01X994982Y168697D02*
X997929D01*
G01X1018209Y58013D02*
Y55513D01*
G01X1015059D02*
Y58013D01*
G01D02*
X1014805Y58267D01*
Y64722D01*
G01X1038953Y134838D02*
Y129084D01*
X1040034Y128003D01*
Y121934D01*
G01D02*
X1037772Y119672D01*
G01X1033719Y946661D02*
X1038432D01*
G01X1044501Y236109D02*
Y238689D01*
G01X1048736Y236134D02*
Y238714D01*
G01X1076633Y97599D02*
X1080446D01*
X1081398Y98551D01*
X1087112D01*
G01X1102699Y108237D02*
X1102181D01*
X1100130Y106186D01*
G01X1097344Y168697D02*
X1100291D01*
G01X1101020Y653161D02*
X1104448D01*
G01X1100393Y1183661D02*
X1098523Y1185531D01*
G01X1120571Y58013D02*
X1122550D01*
X1123052Y57511D01*
G01X1117421Y58013D02*
X1117167Y58267D01*
Y64722D01*
G01X1114781Y58013D02*
X1117421D01*
G01X1109682Y658279D02*
X1111329D01*
X1113452Y660402D01*
X1115054D01*
G01X1113737Y694797D02*
Y692344D01*
X1113244Y691851D01*
G01X1118855Y702277D02*
Y705043D01*
G01X1140134Y119672D02*
X1142396Y121934D01*
G01D02*
Y128003D01*
X1141315Y129084D01*
Y134838D01*
G01X1146863Y236109D02*
Y238689D01*
G01X1151098Y236134D02*
Y238714D01*
G01X1158488Y786294D02*
Y790639D01*
X1157985Y791142D01*
G01X1178995Y97599D02*
X1182808D01*
X1183760Y98551D01*
X1189474D01*
G01X1205061Y108237D02*
X1204543D01*
X1202492Y106186D01*
G01X1199706Y168697D02*
X1202653D01*
G01X1219783Y58013D02*
X1219529Y58267D01*
Y64722D01*
G01X1219783Y55513D02*
Y58013D01*
G01X1217458Y342319D02*
X1220985D01*
G01X1222933Y58013D02*
Y55513D01*
G01X1231506Y350850D02*
X1227078D01*
X1226120Y349892D01*
Y347437D01*
G01X1244758Y121934D02*
X1242496Y119672D01*
G01X1243677Y134838D02*
Y129084D01*
X1244758Y128003D01*
Y121934D01*
G01X1253460Y236134D02*
Y238714D01*
G01X1268659Y379573D02*
Y377173D01*
G01X1281357Y97599D02*
X1285170D01*
X1286122Y98551D01*
X1291836D01*
G01X1300285Y30618D02*
X1297785D01*
G01Y33768D02*
X1300285D01*
G01D02*
X1300539Y34022D01*
X1306994D01*
G01X1302068Y168697D02*
X1305015D01*
G01X1295425Y337000D02*
X1293925Y338500D01*
X1293000D01*
G01X1303313Y351454D02*
X1299959D01*
G01X1303313Y356954D02*
X1299959D01*
G01X1301666Y380185D02*
Y378373D01*
X1303410Y376629D01*
G01X1298710Y480638D02*
X1300522D01*
X1302266Y482382D01*
G01D02*
Y483930D01*
X1301314Y484882D01*
G01X1307423Y108237D02*
X1306905D01*
X1304854Y106186D01*
G01X1303410Y376629D02*
X1304958D01*
X1305910Y377581D01*
G01X1318480Y866091D02*
X1316906Y867665D01*
G01X1318480Y881839D02*
X1316906Y883413D01*
G01X1318480Y891288D02*
X1316906Y892862D01*
G01X1315330Y897587D02*
X1313756Y899161D01*
G01X1318500Y961925D02*
X1318000Y961425D01*
Y955937D01*
G01X1334228Y837744D02*
X1332654Y836170D01*
G01X1334228Y840894D02*
X1332654Y839320D01*
G01X1321629Y844044D02*
X1320055Y842470D01*
G01X1324779Y862941D02*
X1323205Y861367D01*
G01X1337377Y853492D02*
X1335803Y851918D01*
G01X1337377Y856642D02*
X1335803Y855068D01*
G01X1337377Y859792D02*
X1335803Y858218D01*
G01X1337377Y862941D02*
X1335803Y861367D01*
G01X1321629Y862941D02*
X1320055Y861367D01*
G01X1337377Y875540D02*
X1335803Y877114D01*
G01X1337377Y866091D02*
X1335803Y867665D01*
G01X1337377Y872390D02*
X1335803Y873964D01*
G01X1337377Y869240D02*
X1335803Y870814D01*
G01X1334228Y894437D02*
X1335802Y896011D01*
G01X1327929Y884988D02*
X1326355Y886562D01*
G01X1334228Y891288D02*
X1332654Y892862D01*
G01X1321629Y881839D02*
X1320055Y883413D01*
G01X1349976Y840894D02*
X1351550Y839320D01*
G01X1346826Y840894D02*
X1345252Y839320D01*
G01X1349976Y856642D02*
X1351550Y855068D01*
G01X1346826Y856642D02*
X1345252Y855068D01*
G01X1343677Y856642D02*
X1342103Y855068D01*
G01X1343677Y862941D02*
X1342103Y861367D01*
G01X1340527Y862941D02*
X1338953Y861367D01*
G01X1340527Y859792D02*
X1338953Y858218D01*
G01X1349976Y859792D02*
X1351550Y858218D01*
G01X1346826Y859792D02*
X1345252Y858218D01*
G01X1346826Y862941D02*
X1345252Y861367D01*
G01X1343677Y859792D02*
X1342103Y858218D01*
G01X1349976Y862941D02*
X1351550Y861367D01*
G01X1340527Y853492D02*
X1338953Y851918D01*
G01X1343677Y853492D02*
X1342103Y851918D01*
G01X1346826Y853492D02*
X1345252Y851918D01*
G01X1349976Y853492D02*
X1351550Y851918D01*
G01X1340527Y869240D02*
X1338953Y870814D01*
G01X1343677Y866091D02*
X1342103Y867665D01*
G01X1340527Y866091D02*
X1338953Y867665D01*
G01X1349976Y872390D02*
X1351550Y873964D01*
G01X1346826Y872390D02*
X1345252Y873964D01*
G01X1343677Y872390D02*
X1342103Y873964D01*
G01X1340527Y872390D02*
X1338952Y873965D01*
G01X1353125Y875539D02*
X1351550Y873964D01*
G01X1343677Y875540D02*
Y875539D01*
G01D02*
Y875538D01*
X1342103Y873964D01*
G01X1345252D02*
X1343677Y875539D01*
G01Y869240D02*
X1342103Y870814D01*
G01X1346826Y869240D02*
X1345252Y870814D01*
G01X1346826Y866091D02*
X1345252Y867665D01*
G01X1349976Y869240D02*
X1351550Y870814D01*
G01X1349976Y866091D02*
X1351550Y867665D01*
G01X1340527Y875540D02*
X1338953Y877114D01*
G01X1346826Y875540D02*
X1345252Y877114D01*
G01X1349976Y875540D02*
X1351550Y877114D01*
G01X1343677Y878689D02*
X1342103Y880263D01*
G01X1346826Y891288D02*
X1345252Y892862D01*
G01X1349976Y891288D02*
X1351550Y892862D01*
G01X1362574Y837744D02*
X1364148Y836170D01*
G01X1362574Y840894D02*
X1364148Y839320D01*
G01X1353125Y856642D02*
X1354699Y855068D01*
G01X1356275Y862941D02*
X1357849Y861367D01*
G01X1353125Y862941D02*
X1354699Y861367D01*
G01X1356275Y859792D02*
X1357849Y858218D01*
G01X1356275Y856642D02*
X1357850Y855067D01*
G01X1359425Y853492D02*
X1360999Y851918D01*
G01X1353125Y859792D02*
X1354699Y858218D01*
G01X1359425Y856642D02*
X1360999Y855068D01*
G01X1359425Y859792D02*
X1360999Y858218D01*
G01X1359425Y862941D02*
X1360999Y861367D01*
G01X1353125Y853492D02*
X1354699Y851918D01*
G01X1356275Y853492D02*
X1357849Y851918D01*
G01X1359425Y875540D02*
X1360999Y877114D01*
G01X1356275Y872390D02*
X1357850Y873965D01*
G01X1353125Y872390D02*
X1354699Y873964D01*
G01X1356275Y869240D02*
X1357849Y870814D01*
G01X1356275Y866091D02*
X1357849Y867665D01*
G01X1353125Y866091D02*
X1354699Y867665D01*
G01Y873964D02*
X1353125Y875538D01*
Y875539D01*
G01D02*
Y875540D01*
G01Y869240D02*
X1354699Y870814D01*
G01X1356275Y875540D02*
X1357849Y877114D01*
G01X1353125Y878689D02*
X1354699Y880263D01*
G01X1359425Y866091D02*
X1360999Y867665D01*
G01X1359425Y869240D02*
X1360999Y870814D01*
G01X1359425Y872390D02*
X1360999Y873964D01*
G01X1362574Y894437D02*
X1364148Y896011D01*
G01X1362574Y891288D02*
X1364148Y892862D01*
G01X1367884Y1018825D02*
Y1016325D01*
G01D02*
Y1012325D01*
G01X1359690Y1022766D02*
X1357265D01*
G01X1359690Y1026266D02*
X1357265D01*
G01X1359690Y1030266D02*
X1357265D01*
G01X1359690Y1034266D02*
X1357265D01*
G01X1381472Y831445D02*
X1383046Y829871D01*
G01X1378322Y844044D02*
X1379896Y842470D01*
G01X1375173Y844044D02*
X1376747Y842470D01*
G01X1368873Y862941D02*
X1370447Y861367D01*
G01X1368873Y866091D02*
X1370447Y867665D01*
G01X1378322Y869240D02*
X1379896Y870814D01*
G01X1368873Y884988D02*
X1370447Y886562D01*
G01X1378322Y881839D02*
X1379896Y883413D01*
G01X1375173Y881839D02*
X1376747Y883413D01*
G01X1381472Y897587D02*
X1383046Y899161D01*
G01X1370384Y1004680D02*
Y1007180D01*
G01X1394759Y121934D02*
X1392497Y119672D01*
G01X1393678Y134838D02*
Y129084D01*
X1394759Y128003D01*
Y121934D01*
G01X1399226Y236109D02*
Y238689D01*
G01X1403461Y236134D02*
Y238714D01*
G01X1408666Y324733D02*
X1406962Y326437D01*
X1404362D01*
G01X1431358Y97599D02*
X1435171D01*
X1436123Y98551D01*
X1441837D01*
G01X1418340Y1004766D02*
X1420740D01*
G01X1418340Y1000766D02*
X1420740D01*
G01X1418340Y1008766D02*
X1420740D01*
G01X1426340Y1000766D02*
X1428740D01*
G01X1418340Y996766D02*
X1420740D01*
G01X1418340Y1016266D02*
X1420740D01*
G01X1418340Y1012266D02*
X1420740D01*
G01X1426340Y1016266D02*
X1428740D01*
G01X1418340Y1030766D02*
X1420740D01*
G01X1457424Y108237D02*
X1456906D01*
X1454855Y106186D01*
G01X1452069Y168697D02*
X1455016D01*
G01X1475296Y58013D02*
Y55513D01*
G01X1472146D02*
Y58013D01*
G01D02*
X1471892Y58267D01*
Y64722D01*
G01X1496040Y134838D02*
Y129084D01*
X1497121Y128003D01*
Y121934D01*
G01D02*
X1494859Y119672D01*
G01X1501588Y236109D02*
Y238689D01*
G01X1505823Y236134D02*
Y238714D01*
G01X1519863Y973740D02*
Y969336D01*
X1520460Y968739D01*
G01X1519863Y973740D02*
Y977637D01*
G01X1533720Y97599D02*
X1537533D01*
X1538485Y98551D01*
X1544199D01*
G01X1559786Y108237D02*
X1559268D01*
X1557217Y106186D01*
G01X1554431Y168697D02*
X1557378D01*
G01X1558107Y653161D02*
X1561535D01*
G01X1557480Y1183661D02*
X1555610Y1185531D01*
G01X1577658Y58013D02*
X1579762D01*
X1580327Y57448D01*
G01X1574508Y58013D02*
X1574254Y58267D01*
Y64722D01*
G01X1571895Y58013D02*
X1574508D01*
G01X1566769Y658279D02*
X1568634D01*
X1570757Y660402D01*
X1572141D01*
G01X1570824Y694797D02*
Y692344D01*
X1570331Y691851D01*
G01X1575942Y702277D02*
Y705043D01*
G01X1599483Y121934D02*
X1597221Y119672D01*
G01X1598402Y134838D02*
Y129084D01*
X1599483Y128003D01*
Y121934D01*
G01X1603950Y236109D02*
Y238689D01*
G01X1608185Y236134D02*
Y238714D01*
G01X1636082Y97599D02*
X1639895D01*
X1640847Y98551D01*
X1646561D01*
G01X1662148Y108237D02*
X1661630D01*
X1659579Y106186D01*
G01X1656793Y168697D02*
X1659740D01*
G01X1676870Y58013D02*
X1676616Y58267D01*
Y64722D01*
G01X1674545Y342319D02*
X1678072D01*
G01X1680020Y58013D02*
Y55513D01*
G01X1676870D02*
Y58013D01*
G01X1688593Y350850D02*
X1684853D01*
X1683207Y349204D01*
Y347437D01*
G01X1699583Y119672D02*
X1701845Y121934D01*
G01D02*
Y128003D01*
X1700764Y129084D01*
Y134838D01*
G01X1706312Y236109D02*
Y238689D01*
G01X1710547Y236134D02*
Y238714D01*
G01X1738444Y97599D02*
X1742257D01*
X1743209Y98551D01*
X1748923D01*
G01X1725746Y379573D02*
Y377173D01*
G01X1758753Y380185D02*
Y378373D01*
X1760497Y376629D01*
G01X1755797Y480638D02*
X1757609D01*
X1759353Y482382D01*
G01X1764510Y108237D02*
X1763992D01*
X1761941Y106186D01*
G01X1759155Y168697D02*
X1762102D01*
G01X1760497Y376629D02*
X1762045D01*
X1762997Y377581D01*
G01X1759353Y482382D02*
Y483930D01*
X1758401Y484882D01*
G01X1782382Y58013D02*
Y55513D01*
G01X1779232D02*
Y58013D01*
G01D02*
X1778978Y58267D01*
Y64722D01*
G01X1790373Y91974D02*
Y94663D01*
G01X1796437Y818780D02*
X1791056D01*
X1791041Y818795D01*
G01X1791099Y1257937D02*
Y1260421D01*
G01X1808363Y973235D02*
X1813114D01*
G01X1822306Y1089145D02*
X1824706D01*
G54D93*
X75692Y616665D03*
Y635957D03*
X100833Y271685D03*
Y290977D03*
X203195Y271685D03*
Y290977D03*
X305557Y271685D03*
Y290977D03*
X407919Y271685D03*
Y290977D03*
X412801Y380817D03*
Y400109D03*
X532778Y616665D03*
Y635957D03*
X557920Y271685D03*
Y290977D03*
X660282Y271685D03*
Y290977D03*
X762644Y271685D03*
Y290977D03*
X865006Y271685D03*
Y290977D03*
X908127Y397158D03*
Y416450D03*
X989865Y616665D03*
Y635957D03*
X1015006Y271685D03*
Y290977D03*
X1117368Y271685D03*
Y290977D03*
X1219730Y271685D03*
Y290977D03*
X1322092Y271685D03*
Y290977D03*
X1326974Y380817D03*
Y400109D03*
X1446952Y616665D03*
Y635957D03*
X1472093Y271685D03*
Y290977D03*
X1574455Y271685D03*
Y290977D03*
X1676817Y271685D03*
Y290977D03*
X1779179Y271685D03*
Y290977D03*
X1784061Y380817D03*
Y400109D03*
G54D159*
X414519Y1250868D03*
Y1264254D03*
X512830Y1250868D03*
Y1264254D03*
X1328693Y1250868D03*
Y1264254D03*
X1427004Y1250868D03*
Y1264254D03*
G54D84*
X58504Y880295D03*
Y875295D03*
Y870295D03*
Y885295D03*
Y890295D03*
Y895295D03*
Y905295D03*
Y900295D03*
X96930Y875295D03*
Y880295D03*
Y870295D03*
Y895295D03*
Y890295D03*
Y885295D03*
Y905295D03*
Y900295D03*
X515444Y880295D03*
Y875295D03*
Y870295D03*
Y885295D03*
Y890295D03*
Y895295D03*
Y905295D03*
Y900295D03*
X553870Y875295D03*
Y880295D03*
Y870295D03*
Y895295D03*
Y890295D03*
Y885295D03*
Y905295D03*
Y900295D03*
X972833Y880295D03*
Y875295D03*
Y870295D03*
Y885295D03*
Y890295D03*
Y895295D03*
Y905295D03*
Y900295D03*
X1011259Y875295D03*
Y880295D03*
Y870295D03*
Y895295D03*
Y890295D03*
Y885295D03*
Y905295D03*
Y900295D03*
X1429617Y880295D03*
Y875295D03*
Y870295D03*
Y885295D03*
Y890295D03*
Y895295D03*
Y905295D03*
Y900295D03*
X1468043Y875295D03*
Y880295D03*
Y870295D03*
Y895295D03*
Y890295D03*
Y885295D03*
Y905295D03*
Y900295D03*
G54D57*
X39423Y163264D03*
X48085Y167004D03*
X39423Y170744D03*
G54D258*
X1776778Y818696D03*
G54D195*
X814069Y848569D03*
Y859199D03*
X826165Y848651D03*
X828134D03*
X830102D03*
X819975Y848569D03*
X816038D03*
X818006D03*
X826165Y859281D03*
X828134D03*
X830102D03*
X816038Y859199D03*
X818006D03*
X819975D03*
X832071Y848651D03*
Y859281D03*
G54D177*
X538609Y789327D03*
X536641D03*
X534672D03*
X536641Y834405D03*
X534672D03*
X538609D03*
X550420Y789327D03*
X540578D03*
X544515D03*
X554357D03*
X542546D03*
X548452D03*
X546483D03*
X552389D03*
X546483Y834405D03*
X540578D03*
X542546D03*
X544515D03*
X548452D03*
X550420D03*
X552389D03*
X554357D03*
X556326Y789327D03*
X558294D03*
X560263D03*
X562231D03*
X564200D03*
X556326Y834405D03*
X558294D03*
X560263D03*
X562231D03*
X564200D03*
X1505337Y916678D03*
X1509274D03*
X1503368D03*
X1501400D03*
X1507305D03*
X1499431D03*
X1513211D03*
X1511242D03*
Y961756D03*
X1501400D03*
X1499431D03*
X1503368D03*
X1505337D03*
X1507305D03*
X1509274D03*
X1513211D03*
X1515179Y916678D03*
X1521085D03*
X1523053D03*
X1525022D03*
X1526990D03*
X1519116D03*
X1517148D03*
X1528959D03*
X1521085Y961756D03*
X1523053D03*
X1525022D03*
X1515179D03*
X1517148D03*
X1519116D03*
X1526990D03*
X1528959D03*
G54D186*
X729727Y736204D03*
Y743684D03*
X740357D03*
Y739944D03*
Y736204D03*
X1042925Y1315612D03*
X1032295D03*
Y1319352D03*
X1042925Y1323092D03*
X1032295D03*
X1041602Y1334065D03*
X1032272Y1330325D03*
Y1337805D03*
G54D66*
X45012Y671782D03*
X66862D03*
G54D249*
X1030635Y754546D03*
Y764546D03*
Y774546D03*
Y784546D03*
Y794546D03*
Y804546D03*
Y814546D03*
G54D39*
X11313Y1116633D03*
X28635D03*
X43620Y1110100D03*
X60942D03*
X858003Y1125636D03*
X875325D03*
X890180Y1119103D03*
X907502D03*
X921980Y1125636D03*
X939302D03*
X954287Y1119103D03*
X971609D03*
X1771960Y1126122D03*
X1789282D03*
X1803760Y1119589D03*
X1821082D03*
G54D168*
X468408Y1007854D03*
X473133D03*
X471558D03*
X469983D03*
Y1026752D03*
X471558D03*
X473133D03*
X468408D03*
X479432Y1007854D03*
X477857D03*
X476282D03*
X474708D03*
X481007D03*
X482582D03*
Y1026752D03*
X481007D03*
X479432D03*
X477857D03*
X476282D03*
X474708D03*
X1382582Y1007854D03*
Y1026752D03*
X1393606Y1007854D03*
X1392031D03*
X1390456D03*
X1388882D03*
X1395181D03*
X1396756D03*
X1387307D03*
X1385732D03*
X1384157D03*
X1396756Y1026752D03*
X1395181D03*
X1384157D03*
X1385732D03*
X1387307D03*
X1393606D03*
X1392031D03*
X1390456D03*
X1388882D03*
G54D75*
X51653Y1355533D03*
X97806Y23214D03*
X105562Y826044D03*
X382749Y609811D03*
X520770Y330592D03*
X582703Y1464683D03*
X657531Y943324D03*
X811771Y518798D03*
X899546Y1369736D03*
X908190Y63396D03*
X1244511Y960614D03*
X1308096Y548593D03*
X1344628Y177855D03*
X1679534Y33878D03*
X1773034Y1565233D03*
X1795900Y852600D03*
G54D48*
X34731Y1206917D03*
X427063Y634044D03*
X878421Y1215920D03*
X942398D03*
X1786378Y1216406D03*
G54D277*
G01X148818Y1164960D02*
X147058Y1163200D01*
X143301D01*
X137763Y1168738D01*
Y1188786D01*
X134149Y1192400D01*
X102601D01*
X76774Y1218227D01*
X71422D01*
X67131Y1222518D01*
Y1230324D01*
X89092Y1283344D01*
X96773Y1291025D01*
X110130Y1296557D01*
X339646D01*
X340186Y1297097D01*
X341776D01*
X342316Y1296557D01*
X343906D01*
X344446Y1297097D01*
X346026D01*
X346566Y1296557D01*
X348146D01*
X348686Y1297097D01*
X350266D01*
X350806Y1296557D01*
X352386D01*
X352926Y1297097D01*
X354506D01*
X355046Y1296557D01*
X356626D01*
X357166Y1297097D01*
X358746D01*
X359286Y1296557D01*
X360866D01*
X361406Y1297097D01*
X362986D01*
X363526Y1296557D01*
X365106D01*
X374650Y1306101D01*
Y1310399D01*
X372710Y1312339D01*
X371177D01*
X370202Y1311364D01*
G01Y1314764D02*
X371177Y1313789D01*
X373311D01*
X376100Y1311000D01*
Y1305500D01*
X365707Y1295107D01*
X110419D01*
X97595Y1289795D01*
X90322Y1282522D01*
X85118Y1269956D01*
X85410Y1269250D01*
X84806Y1267790D01*
X84099Y1267497D01*
X83495Y1266038D01*
X83787Y1265332D01*
X83183Y1263872D01*
X82476Y1263579D01*
X81872Y1262120D01*
X82164Y1261414D01*
X81560Y1259954D01*
X80853Y1259661D01*
X80249Y1258202D01*
X80541Y1257496D01*
X79937Y1256035D01*
X79230Y1255743D01*
X78626Y1254284D01*
X78918Y1253578D01*
X78314Y1252117D01*
X77607Y1251825D01*
X77003Y1250366D01*
X77295Y1249660D01*
X76691Y1248199D01*
X75984Y1247907D01*
X75380Y1246448D01*
X75672Y1245742D01*
X75068Y1244281D01*
X74361Y1243989D01*
X73757Y1242530D01*
X74049Y1241824D01*
X73445Y1240363D01*
X72738Y1240071D01*
X72134Y1238612D01*
X72426Y1237906D01*
X71822Y1236445D01*
X71115Y1236153D01*
X70511Y1234694D01*
X70803Y1233989D01*
X70199Y1232528D01*
X69492Y1232236D01*
X68581Y1230035D01*
Y1223119D01*
X72023Y1219677D01*
X77375D01*
X78499Y1218553D01*
X79262D01*
X80388Y1217428D01*
Y1216664D01*
X103202Y1193850D01*
X112610D01*
X113150Y1194390D01*
X114730D01*
X115270Y1193850D01*
X116850D01*
X117390Y1194390D01*
X118970D01*
X119510Y1193850D01*
X121090D01*
X121630Y1194390D01*
X123210D01*
X123750Y1193850D01*
X125330D01*
X125870Y1194390D01*
X127450D01*
X127990Y1193850D01*
X129570D01*
X130110Y1194390D01*
X131690D01*
X132230Y1193850D01*
X134750D01*
X139213Y1189387D01*
Y1169339D01*
X143592Y1164960D01*
X145078D01*
G01X148818Y1172440D02*
X148817D01*
X146947Y1170570D01*
G01X145078Y1172440D02*
X145077D01*
X143207Y1170570D01*
G01X148818Y1179921D02*
X148817D01*
X146947Y1178051D01*
G01X145078Y1179921D02*
X145077D01*
X143207Y1178051D01*
G01X605905Y1164960D02*
X604045Y1163100D01*
X599381D01*
X594870Y1167611D01*
Y1190661D01*
X593031Y1192500D01*
X561399D01*
X553000Y1200899D01*
Y1237237D01*
X545554Y1244683D01*
X539978Y1258145D01*
Y1271397D01*
X486687Y1324688D01*
X449807Y1339964D01*
X438437D01*
X432178Y1346223D01*
Y1399654D01*
X430961Y1402588D01*
X423858Y1409691D01*
X416786Y1412653D01*
X405548D01*
X403500Y1414701D01*
Y1416264D01*
X402489Y1417275D01*
G01X602165Y1164960D02*
X599572D01*
X596320Y1168212D01*
Y1182752D01*
X596860Y1183292D01*
Y1184872D01*
X596320Y1185412D01*
Y1186992D01*
X596860Y1187532D01*
Y1189112D01*
X596320Y1189652D01*
Y1191262D01*
X593632Y1193950D01*
X592052D01*
X591512Y1194490D01*
X589932D01*
X589392Y1193950D01*
X587812D01*
X587272Y1194490D01*
X585692D01*
X585152Y1193950D01*
X583572D01*
X583032Y1194490D01*
X581452D01*
X580912Y1193950D01*
X579332D01*
X578792Y1194490D01*
X577212D01*
X576672Y1193950D01*
X575092D01*
X574552Y1194490D01*
X572972D01*
X572432Y1193950D01*
X570852D01*
X570312Y1194490D01*
X568732D01*
X568192Y1193950D01*
X562000D01*
X554450Y1201500D01*
Y1223365D01*
X554990Y1223905D01*
Y1225495D01*
X554450Y1226035D01*
Y1227625D01*
X554990Y1228165D01*
Y1229755D01*
X554450Y1230295D01*
Y1231885D01*
X554990Y1232425D01*
Y1234015D01*
X554450Y1234555D01*
Y1237838D01*
X546784Y1245505D01*
X541428Y1258434D01*
Y1271998D01*
X487509Y1325918D01*
X450096Y1341414D01*
X439038D01*
X433628Y1346824D01*
Y1374710D01*
X434168Y1375250D01*
Y1376830D01*
X433628Y1377370D01*
Y1378950D01*
X434168Y1379490D01*
Y1381070D01*
X433628Y1381610D01*
Y1383190D01*
X434168Y1383730D01*
Y1385310D01*
X433628Y1385850D01*
Y1387430D01*
X434168Y1387970D01*
Y1389550D01*
X433628Y1390090D01*
Y1391670D01*
X434168Y1392210D01*
Y1393790D01*
X433628Y1394330D01*
Y1399943D01*
X432191Y1403410D01*
X424682Y1410919D01*
X417078Y1414103D01*
X406149D01*
X404950Y1415302D01*
Y1416336D01*
X405889Y1417275D01*
G01X504895Y770457D02*
X503900Y769462D01*
Y747750D01*
X482445Y726295D01*
Y698327D01*
X485072Y695700D01*
X494053D01*
X495359Y697006D01*
G01X501495Y770457D02*
X502450Y769502D01*
Y748351D01*
X480995Y726896D01*
Y697726D01*
X484471Y694250D01*
X494115D01*
X495359Y693006D01*
G01X609133Y941137D02*
X608200Y940204D01*
Y937009D01*
X599745Y928554D01*
X536335D01*
X535795Y928014D01*
X534205D01*
X533665Y928554D01*
X532075D01*
X531535Y928014D01*
X529945D01*
X529405Y928554D01*
X527815D01*
X527275Y928014D01*
X525685D01*
X525145Y928554D01*
X523555D01*
X520258Y925257D01*
Y924493D01*
X519132Y923368D01*
X518369D01*
X517245Y922244D01*
Y921480D01*
X516120Y920355D01*
X515356D01*
X514232Y919231D01*
Y918468D01*
X513107Y917342D01*
X512343D01*
X485424Y890423D01*
Y832504D01*
X498800Y819128D01*
Y750799D01*
X478057Y730056D01*
Y694695D01*
X485002Y687750D01*
X494103D01*
X495359Y689006D01*
G01X605733Y941137D02*
X606750Y940120D01*
Y937610D01*
X599144Y930004D01*
X522954D01*
X483974Y891024D01*
Y831903D01*
X497350Y818527D01*
Y751400D01*
X476607Y730657D01*
Y694094D01*
X484401Y686300D01*
X494065D01*
X495359Y685006D01*
G01X505464Y670078D02*
X506750Y668792D01*
Y661050D01*
X517929Y649871D01*
X561022D01*
X631601Y720450D01*
X718918D01*
X818420Y679236D01*
X831415D01*
X844601Y666050D01*
X866493D01*
X869961Y662582D01*
X938482D01*
X946948Y671048D01*
X967001D01*
X967747Y670302D01*
Y668603D01*
X966797Y667653D01*
G01X513666Y688584D02*
X513925Y687958D01*
X513900Y687898D01*
Y683252D01*
X506714Y676066D01*
Y674478D01*
X505464Y673228D01*
G01X511697Y688584D02*
X511175Y688800D01*
X504600D01*
X502106Y686306D01*
X499809D01*
X498509Y685006D01*
G01X511697Y690553D02*
X510964Y690250D01*
X503999D01*
X501505Y687756D01*
X499759D01*
X498509Y689006D01*
G01X511697Y692521D02*
X510902Y692850D01*
X502861D01*
X501455Y694256D01*
X499759D01*
X498509Y693006D01*
G01X511697Y694490D02*
X511238Y694300D01*
X503462D01*
X502056Y695706D01*
X499809D01*
X498509Y697006D01*
G01X970197Y667653D02*
X969197Y668653D01*
Y670903D01*
X967602Y672498D01*
X946347D01*
X937881Y664032D01*
X870562D01*
X867094Y667500D01*
X845202D01*
X832016Y680686D01*
X818709D01*
X719207Y721900D01*
X631000D01*
X576096Y666996D01*
X575332D01*
X574207Y665870D01*
Y665107D01*
X573083Y663983D01*
X572319D01*
X571194Y662857D01*
Y662094D01*
X570070Y660970D01*
X569306D01*
X568181Y659844D01*
Y659081D01*
X567057Y657957D01*
X566293D01*
X565168Y656831D01*
Y656068D01*
X564044Y654944D01*
X563281D01*
X562156Y653819D01*
Y653056D01*
X560421Y651321D01*
X518530D01*
X508200Y661651D01*
Y668814D01*
X509464Y670078D01*
G01X513464D02*
X514700Y668842D01*
Y660149D01*
X519516Y655333D01*
X554233D01*
X623450Y724550D01*
X720561D01*
X819348Y683631D01*
X834518D01*
X846397Y671752D01*
X941567D01*
X950419Y680604D01*
X1014609D01*
X1014659Y680654D01*
X1015659Y679654D01*
G01Y683054D02*
X1014659Y682054D01*
X949818D01*
X940966Y673202D01*
X846998D01*
X835119Y685081D01*
X819637D01*
X720850Y726000D01*
X622849D01*
X576747Y679898D01*
X575983D01*
X574858Y678772D01*
Y678009D01*
X573734Y676885D01*
X572970D01*
X571845Y675759D01*
Y674996D01*
X570721Y673872D01*
X569957D01*
X568832Y672746D01*
Y671983D01*
X567708Y670859D01*
X566944D01*
X565819Y669733D01*
Y668970D01*
X564695Y667846D01*
X563931D01*
X562806Y666720D01*
Y665957D01*
X561682Y664833D01*
X560918D01*
X559793Y663707D01*
Y662944D01*
X558669Y661820D01*
X557905D01*
X556780Y660695D01*
Y659931D01*
X553632Y656783D01*
X520117D01*
X516150Y660750D01*
Y668764D01*
X517464Y670078D01*
G01Y673228D02*
X516164Y674528D01*
Y675263D01*
X519323Y678422D01*
Y687985D01*
X519571Y688584D01*
G01X509464Y673228D02*
X508164Y674528D01*
Y675465D01*
X515350Y682651D01*
Y687898D01*
X515634Y688584D01*
G01X517603D02*
X517873Y687932D01*
Y679023D01*
X514714Y675864D01*
Y674478D01*
X513464Y673228D01*
G01X605905Y1172440D02*
X605904D01*
X604034Y1170570D01*
G01X602165Y1172440D02*
X602164D01*
X600294Y1170570D01*
G01X605905Y1179921D02*
X605904D01*
X604034Y1178051D01*
G01X602165Y1179921D02*
X602164D01*
X600294Y1178051D01*
G01X617126Y1176180D02*
Y1176181D01*
X615256Y1178051D01*
G01X613386Y1176180D02*
Y1176181D01*
X611516Y1178051D01*
G01X882183Y1728286D02*
Y1732266D01*
X881863Y1732586D01*
X868259D01*
X867859Y1732186D01*
Y1724644D01*
X866639Y1723424D01*
X859869D01*
X858649Y1724644D01*
Y1735535D01*
X858249Y1735935D01*
X852639D01*
X852239Y1735535D01*
Y1724644D01*
X851019Y1723424D01*
X844249D01*
X843029Y1724644D01*
Y1735535D01*
X842629Y1735935D01*
X837019D01*
X836619Y1735535D01*
Y1724644D01*
X835399Y1723424D01*
X828629D01*
X827409Y1724644D01*
Y1735535D01*
X827009Y1735935D01*
X821399D01*
X820999Y1735535D01*
Y1724644D01*
X819779Y1723424D01*
X813009D01*
X811789Y1724644D01*
Y1735535D01*
X811389Y1735935D01*
X805779D01*
X805379Y1735535D01*
Y1724644D01*
X804159Y1723424D01*
X797389D01*
X796169Y1724644D01*
Y1735535D01*
X795769Y1735935D01*
X790159D01*
X789759Y1735535D01*
Y1724644D01*
X788539Y1723424D01*
X781769D01*
X780549Y1724644D01*
Y1735535D01*
X780149Y1735935D01*
X774539D01*
X774139Y1735535D01*
Y1724644D01*
X772919Y1723424D01*
X766149D01*
X764929Y1724644D01*
Y1735535D01*
X764529Y1735935D01*
X758919D01*
X758519Y1735535D01*
Y1724644D01*
X757299Y1723424D01*
X750529D01*
X749309Y1724644D01*
Y1735535D01*
X748909Y1735935D01*
X743299D01*
X742899Y1735535D01*
Y1724644D01*
X741679Y1723424D01*
X734909D01*
X733689Y1724644D01*
Y1735535D01*
X733289Y1735935D01*
X727679D01*
X727279Y1735535D01*
Y1724644D01*
X726059Y1723424D01*
X719289D01*
X718069Y1724644D01*
Y1735535D01*
X717669Y1735935D01*
X712059D01*
X711659Y1735535D01*
Y1724644D01*
X710439Y1723424D01*
X703669D01*
X702449Y1724644D01*
Y1735535D01*
X702049Y1735935D01*
X696439D01*
X696039Y1735535D01*
Y1724644D01*
X694819Y1723424D01*
X688049D01*
X686829Y1724644D01*
Y1735535D01*
X686429Y1735935D01*
X680819D01*
X680419Y1735535D01*
Y1724644D01*
X679199Y1723424D01*
X672429D01*
X671209Y1724644D01*
Y1735535D01*
X670809Y1735935D01*
X665199D01*
X664799Y1735535D01*
Y1724644D01*
X663579Y1723424D01*
X656809D01*
X655589Y1724644D01*
Y1735535D01*
X655189Y1735935D01*
X649579D01*
X649179Y1735535D01*
Y1724644D01*
X647959Y1723424D01*
X641189D01*
X639969Y1724644D01*
Y1731879D01*
X639312Y1732536D01*
X630433D01*
X630083Y1732186D01*
Y1728286D01*
G01X882183Y1738286D02*
Y1734230D01*
X881939Y1733986D01*
X881901D01*
X881851Y1734036D01*
X867658D01*
X866409Y1732787D01*
Y1725245D01*
X866038Y1724874D01*
X860470D01*
X860099Y1725245D01*
Y1736136D01*
X858850Y1737385D01*
X852038D01*
X850789Y1736136D01*
Y1725245D01*
X850418Y1724874D01*
X844850D01*
X844479Y1725245D01*
Y1736136D01*
X843230Y1737385D01*
X836418D01*
X835169Y1736136D01*
Y1725245D01*
X834798Y1724874D01*
X829230D01*
X828859Y1725245D01*
Y1736136D01*
X827610Y1737385D01*
X820798D01*
X819549Y1736136D01*
Y1725245D01*
X819178Y1724874D01*
X813610D01*
X813239Y1725245D01*
Y1736136D01*
X811990Y1737385D01*
X805178D01*
X803929Y1736136D01*
Y1725245D01*
X803558Y1724874D01*
X797990D01*
X797619Y1725245D01*
Y1736136D01*
X796370Y1737385D01*
X789558D01*
X788309Y1736136D01*
Y1725245D01*
X787938Y1724874D01*
X782370D01*
X781999Y1725245D01*
Y1736136D01*
X780750Y1737385D01*
X773938D01*
X772689Y1736136D01*
Y1725245D01*
X772318Y1724874D01*
X766750D01*
X766379Y1725245D01*
Y1736136D01*
X765130Y1737385D01*
X758318D01*
X757069Y1736136D01*
Y1725245D01*
X756698Y1724874D01*
X751130D01*
X750759Y1725245D01*
Y1736136D01*
X749510Y1737385D01*
X742698D01*
X741449Y1736136D01*
Y1725245D01*
X741078Y1724874D01*
X735510D01*
X735139Y1725245D01*
Y1736136D01*
X733890Y1737385D01*
X727078D01*
X725829Y1736136D01*
Y1725245D01*
X725458Y1724874D01*
X719890D01*
X719519Y1725245D01*
Y1736136D01*
X718270Y1737385D01*
X711458D01*
X710209Y1736136D01*
Y1725245D01*
X709838Y1724874D01*
X704270D01*
X703899Y1725245D01*
Y1736136D01*
X702650Y1737385D01*
X695838D01*
X694589Y1736136D01*
Y1725245D01*
X694218Y1724874D01*
X688650D01*
X688279Y1725245D01*
Y1736136D01*
X687030Y1737385D01*
X680218D01*
X678969Y1736136D01*
Y1725245D01*
X678598Y1724874D01*
X673030D01*
X672659Y1725245D01*
Y1736136D01*
X671410Y1737385D01*
X664598D01*
X663349Y1736136D01*
Y1725245D01*
X662978Y1724874D01*
X657410D01*
X657039Y1725245D01*
Y1736136D01*
X655790Y1737385D01*
X648978D01*
X647729Y1736136D01*
Y1725245D01*
X647358Y1724874D01*
X641790D01*
X641419Y1725245D01*
Y1732480D01*
X639913Y1733986D01*
X630483D01*
X630083Y1734386D01*
Y1738286D01*
G01X900376Y612364D02*
X901651Y611089D01*
Y608949D01*
X903200Y607400D01*
Y595600D01*
X902941Y595341D01*
Y594549D01*
G01X904376Y612364D02*
X903101Y611089D01*
Y609550D01*
X904650Y608001D01*
Y595650D01*
X904909Y595391D01*
Y594549D01*
G01X909208Y612444D02*
X910483Y611169D01*
Y604635D01*
X907137Y601289D01*
Y595736D01*
X906878Y595477D01*
Y594549D01*
G01X913208Y612444D02*
X911933Y611169D01*
Y604034D01*
X908587Y600688D01*
Y595712D01*
X908846Y595453D01*
Y594549D01*
G01X900376Y615514D02*
X901650Y616788D01*
Y620562D01*
X900676Y621536D01*
G01X904376Y615514D02*
X903100Y616790D01*
Y620560D01*
X904076Y621536D01*
G01X909208Y615594D02*
X910500Y616886D01*
Y620624D01*
X909508Y621616D01*
G01X913208Y615594D02*
X911950Y616852D01*
Y620658D01*
X912908Y621616D01*
G01X926061Y589578D02*
X924730Y588247D01*
X923148D01*
X920763Y585862D01*
X916834D01*
X916513Y586183D01*
X915244D01*
G01X926061Y585578D02*
X924842Y586797D01*
X923749D01*
X921364Y584412D01*
X916853D01*
X916803Y584462D01*
X916772D01*
X916524Y584214D01*
X915244D01*
G01X917928Y587163D02*
X919080Y587640D01*
G01X926077Y598329D02*
X924815Y597067D01*
X923416D01*
X918203Y591854D01*
X916294D01*
X916060Y592088D01*
X915244D01*
G01X926077Y594329D02*
X924789Y595617D01*
X924017D01*
X918804Y590404D01*
X916268D01*
X915984Y590120D01*
X915244D01*
G01X925463Y838993D02*
Y836336D01*
G01X929211Y585578D02*
X930483Y586850D01*
X932811D01*
X933725Y585936D01*
G01X929227Y598329D02*
X930456Y597100D01*
X932754D01*
X933741Y598087D01*
G01X929227Y594329D02*
X930548Y595650D01*
X932778D01*
X933741Y594687D01*
G01X929211Y589578D02*
X930489Y588300D01*
X932689D01*
X933725Y589336D01*
G01X1062991Y1164960D02*
X1061331Y1163300D01*
X1056267D01*
X1051956Y1167611D01*
Y1188645D01*
X1048101Y1192500D01*
X1020899D01*
X1012722Y1200677D01*
X997250Y1238030D01*
Y1260112D01*
X996908Y1262017D01*
X996918Y1262037D01*
X980600Y1301433D01*
Y1325400D01*
X1000893Y1345693D01*
X1008333D01*
X1009333Y1346693D01*
G01X1059251Y1164960D02*
X1056658D01*
X1053406Y1168212D01*
Y1171570D01*
X1053946Y1172110D01*
Y1173690D01*
X1053406Y1174230D01*
Y1180722D01*
X1053946Y1181262D01*
Y1182842D01*
X1053406Y1183382D01*
Y1184962D01*
X1053946Y1185502D01*
Y1187082D01*
X1053406Y1187622D01*
Y1189246D01*
X1051701Y1190951D01*
Y1191715D01*
X1050582Y1192833D01*
X1049819D01*
X1048702Y1193950D01*
X1047122D01*
X1046582Y1194490D01*
X1045002D01*
X1044462Y1193950D01*
X1042882D01*
X1042342Y1194490D01*
X1040762D01*
X1040222Y1193950D01*
X1038642D01*
X1038102Y1194490D01*
X1036522D01*
X1035982Y1193950D01*
X1034402D01*
X1033862Y1194490D01*
X1032282D01*
X1031742Y1193950D01*
X1030162D01*
X1029622Y1194490D01*
X1028042D01*
X1027502Y1193950D01*
X1025922D01*
X1025382Y1194490D01*
X1023802D01*
X1023262Y1193950D01*
X1021500D01*
X1013952Y1201499D01*
X998700Y1238319D01*
Y1260241D01*
X998336Y1262272D01*
X998230Y1262528D01*
X998258Y1262594D01*
X984773Y1295149D01*
X985065Y1295854D01*
X984461Y1297315D01*
X983754Y1297607D01*
X982050Y1301722D01*
Y1307839D01*
X982590Y1308379D01*
Y1309959D01*
X982050Y1310499D01*
Y1312079D01*
X982590Y1312619D01*
Y1314199D01*
X982050Y1314739D01*
Y1316319D01*
X982590Y1316859D01*
Y1318439D01*
X982050Y1318979D01*
Y1320559D01*
X982590Y1321099D01*
Y1322679D01*
X982050Y1323219D01*
Y1324799D01*
X983500Y1326249D01*
X984264D01*
X985382Y1327368D01*
Y1328131D01*
X986499Y1329248D01*
X987263D01*
X988381Y1330367D01*
Y1331130D01*
X989498Y1332247D01*
X990262D01*
X991380Y1333366D01*
Y1334129D01*
X992497Y1335246D01*
X993261D01*
X994379Y1336365D01*
Y1337128D01*
X995496Y1338245D01*
X996260D01*
X997378Y1339364D01*
Y1340127D01*
X998495Y1341244D01*
X999259D01*
X1000377Y1342363D01*
Y1343126D01*
X1001494Y1344243D01*
X1008383D01*
X1009333Y1343293D01*
G01X1059251Y1172440D02*
X1059250D01*
X1057380Y1170570D01*
G01X1059251Y1179921D02*
X1059250D01*
X1057380Y1178051D01*
G01X1062991Y1172440D02*
X1062990D01*
X1061120Y1170570D01*
G01X1072342Y1178051D02*
X1074212Y1176181D01*
Y1176180D01*
G01X1070472D02*
Y1176181D01*
X1068602Y1178051D01*
G01X1062991Y1179921D02*
X1062990D01*
X1061120Y1178051D01*
G01X1520078Y1164960D02*
X1518418Y1163300D01*
X1513800D01*
X1509043Y1168057D01*
Y1188857D01*
X1505200Y1192700D01*
X1476248D01*
X1467800Y1201148D01*
Y1234649D01*
X1458592Y1243856D01*
X1452250Y1259165D01*
Y1304259D01*
X1451710Y1304799D01*
Y1306379D01*
X1452250Y1306919D01*
Y1308499D01*
X1447994Y1312755D01*
X1443226D01*
X1442650Y1312179D01*
Y1311708D01*
X1443660Y1310698D01*
G01X1516338Y1164960D02*
X1514191D01*
X1510493Y1168658D01*
Y1180270D01*
X1511033Y1180810D01*
Y1182390D01*
X1510493Y1182930D01*
Y1184510D01*
X1511033Y1185050D01*
Y1186630D01*
X1510493Y1187170D01*
Y1189458D01*
X1509426Y1190525D01*
Y1191288D01*
X1508308Y1192407D01*
X1507544D01*
X1505801Y1194150D01*
X1504130D01*
X1503590Y1194690D01*
X1502010D01*
X1501470Y1194150D01*
X1499890D01*
X1499350Y1194690D01*
X1497770D01*
X1497230Y1194150D01*
X1495650D01*
X1495110Y1194690D01*
X1493530D01*
X1492990Y1194150D01*
X1491410D01*
X1490870Y1194690D01*
X1489290D01*
X1488750Y1194150D01*
X1487170D01*
X1486630Y1194690D01*
X1485050D01*
X1484510Y1194150D01*
X1476849D01*
X1469250Y1201749D01*
Y1207870D01*
X1469790Y1208410D01*
Y1209990D01*
X1469250Y1210530D01*
Y1235250D01*
X1459822Y1244678D01*
X1453700Y1259454D01*
Y1309100D01*
X1448595Y1314205D01*
X1442625D01*
X1441200Y1312780D01*
Y1311638D01*
X1440260Y1310698D01*
G01X1520078Y1172440D02*
X1520077D01*
X1518207Y1170570D01*
G01X1516338Y1172440D02*
X1516337D01*
X1514467Y1170570D01*
G01X1520078Y1179921D02*
X1520077D01*
X1518207Y1178051D01*
G01X1516338Y1179921D02*
X1516337D01*
X1514467Y1178051D01*
G54D268*
G01X1091661Y1521648D02*
Y1524164D01*
X1089242Y1526583D01*
X1086108D01*
G01X1099339Y1540152D02*
Y1536261D01*
X1099900Y1535700D01*
G54D67*
X45449Y1074996D03*
X346629Y1218602D03*
X349458Y1221429D03*
X356156Y1215651D03*
X358985Y1218480D03*
X353328Y1212823D03*
X352287Y1224258D03*
X355116Y1227087D03*
X364642Y1224137D03*
X810415Y1212823D03*
X816072Y1218480D03*
X813243Y1215651D03*
X806545Y1221429D03*
X803716Y1218602D03*
X809374Y1224258D03*
X812203Y1227087D03*
X821729Y1224137D03*
X892139Y1083999D03*
X956116D03*
X1263631Y1221429D03*
X1260802Y1218602D03*
X1270329Y1215651D03*
X1267501Y1212823D03*
X1266460Y1224258D03*
X1269289Y1227087D03*
X1273158Y1218480D03*
X1278815Y1224137D03*
X1720718Y1221429D03*
X1717889Y1218602D03*
X1724588Y1212823D03*
X1723547Y1224258D03*
X1727416Y1215651D03*
X1730245Y1218480D03*
X1735902Y1224137D03*
X1726376Y1227087D03*
X1800096Y1084485D03*
G54D169*
X475495Y1017303D03*
X1389669D03*
G54D196*
X814800Y876864D03*
Y885526D03*
X826804Y878504D03*
X831922D03*
X829363D03*
X819918Y876864D03*
X831922Y887166D03*
X826804D03*
X819918Y885526D03*
X817359D03*
X1285941Y913331D03*
Y904669D03*
X1291059Y913331D03*
Y904669D03*
X1288500D03*
X1443428Y1023064D03*
X1438310D03*
Y1014402D03*
X1443428D03*
X1440869D03*
G54D58*
X45643Y454376D03*
Y461462D03*
X246031Y633786D03*
Y640872D03*
X485485Y421374D03*
Y428460D03*
X500729Y451376D03*
Y458462D03*
X703117Y633786D03*
Y640872D03*
X943111Y242721D03*
Y249807D03*
X959816Y454376D03*
Y461462D03*
X1160204Y633786D03*
Y640872D03*
X1292500Y938043D03*
Y930957D03*
X1414903Y451376D03*
Y458462D03*
X1429546Y1508327D03*
Y1515413D03*
X1600410Y1456276D03*
Y1463362D03*
X1617291Y633786D03*
Y640872D03*
G54D259*
X1795453Y812874D03*
Y834922D03*
G54D178*
X553958Y744599D03*
Y747158D03*
Y749717D03*
X561832D03*
Y747158D03*
Y744599D03*
X699789Y697094D03*
Y699653D03*
Y702212D03*
X707663Y699653D03*
Y697094D03*
Y702212D03*
G54D85*
X67191Y1046138D03*
X67163Y1050784D03*
X67209Y1055646D03*
X67273Y1060812D03*
X68999Y111123D03*
X71099D03*
X68999Y114723D03*
X71099D03*
X79401Y118235D03*
X81501D03*
X79401Y121835D03*
X81501D03*
X79401Y132409D03*
X81501D03*
X68999Y125296D03*
X71099D03*
X68999Y128896D03*
X71099D03*
X79401Y136009D03*
X81501D03*
X69291Y1046138D03*
X69263Y1050784D03*
X69309Y1055646D03*
X69373Y1060812D03*
X108138Y1009759D03*
X106038D03*
X147696Y401613D03*
X145596D03*
X147696Y398013D03*
X145596D03*
X145296Y415787D03*
X143196D03*
X145296Y412187D03*
X143196D03*
X145296Y429960D03*
X143196D03*
X145296Y440533D03*
X143196D03*
X145296Y426360D03*
X143196D03*
X145296Y444133D03*
X143196D03*
X145296Y472887D03*
X143196D03*
X145296Y469287D03*
X143196D03*
X145296Y487060D03*
X143196D03*
X145296Y483460D03*
X143196D03*
X145296Y517021D03*
X143196D03*
X145296Y513421D03*
X143196D03*
X145296Y531194D03*
X143196D03*
X145296Y527594D03*
X143196D03*
X155698Y390901D03*
X153598D03*
X155698Y394501D03*
X153598D03*
X155698Y408674D03*
X153598D03*
X155698Y405074D03*
X153598D03*
X155698Y422847D03*
X153598D03*
X155698Y419247D03*
X153598D03*
X155698Y437021D03*
X153598D03*
X155698Y433421D03*
X153598D03*
X155698Y490573D03*
X153598D03*
X155698Y476399D03*
X153598D03*
X155698Y479999D03*
X153598D03*
X155698Y494173D03*
X153598D03*
X155698Y520533D03*
X153598D03*
X155698Y524133D03*
X153598D03*
X155698Y538306D03*
X153598D03*
X155698Y534706D03*
X153598D03*
X171361Y111123D03*
X173461D03*
X171361Y114723D03*
X173461D03*
X181763Y118235D03*
Y132409D03*
Y121835D03*
X171361Y125296D03*
X173461D03*
X171361Y128896D03*
X173461D03*
X181763Y136009D03*
X183863Y118235D03*
Y132409D03*
Y121835D03*
Y136009D03*
X219559Y1447353D03*
X221659D03*
X219559Y1450953D03*
X221659D03*
X219559Y1458353D03*
X221659D03*
X219559Y1461953D03*
X221659D03*
X273723Y111123D03*
X275823D03*
X273723Y114723D03*
X275823D03*
X273723Y125296D03*
X275823D03*
X273723Y128896D03*
X275823D03*
X284125Y118235D03*
X286225D03*
X284125Y121835D03*
X286225D03*
X284125Y132409D03*
X286225D03*
X284125Y136009D03*
X286225D03*
X313987Y467206D03*
X316087D03*
X313987Y470806D03*
X316087D03*
X324389Y474318D03*
X326489D03*
X324389Y488491D03*
X326489D03*
X313987Y484979D03*
X316087D03*
X324389Y477918D03*
X326489D03*
X313987Y481379D03*
X316087D03*
X324389Y492091D03*
X326489D03*
X324389Y518452D03*
X326489D03*
X324389Y522052D03*
X326489D03*
X313987Y511339D03*
X316087D03*
X313987Y514939D03*
X316087D03*
X324389Y536225D03*
X326489D03*
X324389Y532625D03*
X326489D03*
X313987Y525513D03*
X316087D03*
X313987Y529113D03*
X316087D03*
X324389Y568491D03*
X326489D03*
X324389Y572091D03*
X326489D03*
X313987Y564979D03*
X316087D03*
X313987Y561379D03*
X316087D03*
X313987Y579152D03*
X316087D03*
X313987Y575552D03*
X316087D03*
X324389Y582665D03*
X326489D03*
X324389Y586265D03*
X326489D03*
X313987Y593325D03*
X316087D03*
X313987Y589725D03*
X316087D03*
X313987Y603899D03*
X316087D03*
X324389Y600438D03*
X326489D03*
X324389Y596838D03*
X326489D03*
X313987Y607499D03*
X316087D03*
X324389Y611011D03*
X326489D03*
X324389Y614611D03*
X326489D03*
X376085Y111123D03*
Y114723D03*
Y125296D03*
Y128896D03*
X378185Y111123D03*
Y114723D03*
Y125296D03*
Y128896D03*
X386487Y118235D03*
X388587D03*
X386487Y121835D03*
X388587D03*
X386487Y132409D03*
X388587D03*
X386487Y136009D03*
X388587D03*
X526086Y111123D03*
X528186D03*
X526086Y114723D03*
X528186D03*
X536488Y118235D03*
X538588D03*
X536488Y121835D03*
X538588D03*
X526086Y125296D03*
X528186D03*
X526086Y128896D03*
X528186D03*
X536488Y132409D03*
X538588D03*
X536488Y136009D03*
X538588D03*
X565225Y1009759D03*
X563125D03*
X602682Y398013D03*
Y401613D03*
X602382Y412187D03*
X600282D03*
X602382Y415787D03*
X600282D03*
X602382Y429960D03*
X600282D03*
X602382Y426360D03*
X600282D03*
X602382Y440533D03*
X600282D03*
X602382Y444133D03*
X600282D03*
X602382Y469287D03*
X600282D03*
X602382Y472887D03*
X600282D03*
X602382Y487060D03*
X600282D03*
X602382Y483460D03*
X600282D03*
X602382Y517021D03*
X600282D03*
X602382Y513421D03*
X600282D03*
X602382Y527594D03*
X600282D03*
X602382Y531194D03*
X600282D03*
X612784Y390901D03*
X610684D03*
X604782Y398013D03*
Y401613D03*
X612784Y394501D03*
X610684D03*
X612784Y408674D03*
X610684D03*
X612784Y405074D03*
X610684D03*
X612784Y422847D03*
X610684D03*
X612784Y419247D03*
X610684D03*
X612784Y433421D03*
X610684D03*
X612784Y437021D03*
X610684D03*
X612784Y490573D03*
X610684D03*
X612784Y476399D03*
X610684D03*
X612784Y479999D03*
X610684D03*
X612784Y494173D03*
X610684D03*
X612784Y520533D03*
X610684D03*
X612784Y524133D03*
X610684D03*
X612784Y534706D03*
X610684D03*
X612784Y538306D03*
X610684D03*
X628448Y111123D03*
X630548D03*
X628448Y114723D03*
X630548D03*
X628448Y125296D03*
X630548D03*
X628448Y128896D03*
X630548D03*
X638850Y118235D03*
X640950D03*
X638850Y121835D03*
X640950D03*
X638850Y132409D03*
X640950D03*
X638850Y136009D03*
X640950D03*
X730810Y114723D03*
X732910D03*
X730810Y111123D03*
X732910D03*
X730810Y125296D03*
X732910D03*
X730810Y128896D03*
X732910D03*
X741212Y118235D03*
X743312D03*
X741212Y132409D03*
X743312D03*
X741212Y121835D03*
X743312D03*
X741212Y136009D03*
X743312D03*
X771073Y470806D03*
X773173D03*
X771073Y467206D03*
X773173D03*
X781475Y474318D03*
Y488491D03*
Y477918D03*
X771073Y481379D03*
X773173D03*
X771073Y484979D03*
X773173D03*
X781475Y492091D03*
Y518452D03*
Y522052D03*
X771073Y511339D03*
X773173D03*
X771073Y514939D03*
X773173D03*
X771073Y525513D03*
X773173D03*
X781475Y532625D03*
Y536225D03*
X771073Y529113D03*
X773173D03*
X771073Y564979D03*
X773173D03*
X781475Y572091D03*
Y568491D03*
X771073Y561379D03*
X773173D03*
X781475Y582665D03*
Y586265D03*
X771073Y575552D03*
X773173D03*
X771073Y579152D03*
X773173D03*
X771073Y593325D03*
X773173D03*
X771073Y589725D03*
X773173D03*
X781475Y596838D03*
Y600438D03*
X771073Y603899D03*
X773173D03*
X771073Y607499D03*
X773173D03*
X781475Y611011D03*
Y614611D03*
X783575Y474318D03*
Y488491D03*
Y477918D03*
Y492091D03*
Y518452D03*
Y522052D03*
Y532625D03*
Y536225D03*
Y572091D03*
Y568491D03*
Y582665D03*
Y586265D03*
Y596838D03*
Y600438D03*
Y611011D03*
Y614611D03*
X833172Y111123D03*
X835272D03*
X833172Y114723D03*
X835272D03*
X833172Y125296D03*
X835272D03*
X833172Y128896D03*
X835272D03*
X843574Y118235D03*
X845674D03*
X843574Y121835D03*
X845674D03*
X843574Y132409D03*
X845674D03*
X843574Y136009D03*
X845674D03*
X911893Y1022889D03*
X911841Y1028101D03*
X913993Y1022889D03*
X913941Y1028101D03*
X919276Y1088717D03*
X921376D03*
X919304Y1080832D03*
X921404D03*
X983172Y111123D03*
X985272D03*
X983172Y114723D03*
X985272D03*
X993574Y118235D03*
Y121835D03*
X983172Y125296D03*
X985272D03*
X983172Y128896D03*
X985272D03*
X993574Y132409D03*
Y136009D03*
X995674Y118235D03*
Y121835D03*
Y132409D03*
Y136009D03*
X1022311Y1009759D03*
X1020211D03*
X1057369Y412187D03*
Y415787D03*
Y429960D03*
Y426360D03*
Y440533D03*
Y444133D03*
Y472887D03*
Y469287D03*
Y487060D03*
Y483460D03*
Y517021D03*
Y513421D03*
Y531194D03*
Y527594D03*
X1069871Y390901D03*
X1067771D03*
X1061869Y398013D03*
X1059769D03*
X1061869Y401613D03*
X1059769D03*
X1069871Y394501D03*
X1067771D03*
X1069871Y405074D03*
X1067771D03*
X1069871Y408674D03*
X1067771D03*
X1059469Y412187D03*
Y415787D03*
X1069871Y422847D03*
X1067771D03*
X1069871Y419247D03*
X1067771D03*
X1059469Y429960D03*
Y426360D03*
Y440533D03*
X1069871Y437021D03*
X1067771D03*
X1069871Y433421D03*
X1067771D03*
X1059469Y444133D03*
Y472887D03*
Y469287D03*
X1069871Y490573D03*
X1067771D03*
X1059469Y487060D03*
Y483460D03*
X1069871Y476399D03*
X1067771D03*
X1069871Y479999D03*
X1067771D03*
X1069871Y494173D03*
X1067771D03*
X1069871Y520533D03*
X1067771D03*
X1059469Y517021D03*
Y513421D03*
X1069871Y524133D03*
X1067771D03*
X1069871Y534706D03*
X1067771D03*
X1069871Y538306D03*
X1067771D03*
X1059469Y531194D03*
Y527594D03*
X1085534Y114723D03*
X1087634D03*
X1085534Y111123D03*
X1087634D03*
X1085534Y125296D03*
X1087634D03*
X1085534Y128896D03*
X1087634D03*
X1095936Y118235D03*
X1098036D03*
X1095936Y121835D03*
X1098036D03*
X1095936Y132409D03*
X1098036D03*
X1095936Y136009D03*
X1098036D03*
X1187896Y111123D03*
Y114723D03*
Y125296D03*
Y128896D03*
X1189996Y111123D03*
Y114723D03*
Y125296D03*
Y128896D03*
X1198298Y118235D03*
X1200398D03*
X1198298Y121835D03*
X1200398D03*
X1198298Y132409D03*
X1200398D03*
X1198298Y136009D03*
X1200398D03*
X1228160Y467206D03*
X1230260D03*
X1228160Y470806D03*
X1230260D03*
X1228160Y481379D03*
X1230260D03*
X1228160Y484979D03*
X1230260D03*
X1228160Y511339D03*
X1230260D03*
X1228160Y514939D03*
X1230260D03*
X1228160Y525513D03*
X1230260D03*
X1228160Y529113D03*
X1230260D03*
X1228160Y564979D03*
X1230260D03*
X1228160Y561379D03*
X1230260D03*
X1228160Y579152D03*
X1230260D03*
X1228160Y575552D03*
X1230260D03*
X1228160Y593325D03*
X1230260D03*
X1228160Y589725D03*
X1230260D03*
X1228160Y603899D03*
X1230260D03*
X1228160Y607499D03*
X1230260D03*
X1238562Y474318D03*
X1240662D03*
X1238562Y488491D03*
X1240662D03*
X1238562Y477918D03*
X1240662D03*
X1238562Y492091D03*
X1240662D03*
X1238562Y518452D03*
X1240662D03*
X1238562Y522052D03*
X1240662D03*
X1238562Y532625D03*
X1240662D03*
X1238562Y536225D03*
X1240662D03*
X1238562Y572091D03*
X1240662D03*
X1238562Y568491D03*
X1240662D03*
X1238562Y582665D03*
X1240662D03*
X1238562Y586265D03*
X1240662D03*
X1238562Y596838D03*
X1240662D03*
X1238562Y600438D03*
X1240662D03*
X1238562Y611011D03*
X1240662D03*
X1238562Y614611D03*
X1240662D03*
X1290258Y111123D03*
X1292358D03*
X1290258Y114723D03*
X1292358D03*
X1300660Y118235D03*
X1302760D03*
X1290258Y128896D03*
X1292358D03*
X1300660Y132409D03*
X1302760D03*
X1300660Y121835D03*
X1302760D03*
X1290258Y125296D03*
X1292358D03*
X1300660Y136009D03*
X1302760D03*
X1424453Y1491198D03*
X1426553D03*
X1440259Y111123D03*
X1442359D03*
X1440259Y114723D03*
X1442359D03*
X1440259Y125296D03*
X1442359D03*
X1440259Y128896D03*
X1442359D03*
X1450661Y118235D03*
X1452761D03*
X1450661Y132409D03*
X1452761D03*
X1450661Y121835D03*
X1452761D03*
X1450661Y136009D03*
X1452761D03*
X1479398Y1009759D03*
X1477298D03*
X1526958Y390901D03*
X1524858D03*
X1526958Y394501D03*
X1524858D03*
X1518956Y398013D03*
X1516856D03*
X1518956Y401613D03*
X1516856D03*
X1526958Y408674D03*
X1524858D03*
X1526958Y405074D03*
X1524858D03*
X1516556Y415787D03*
X1514456D03*
X1516556Y412187D03*
X1514456D03*
X1526958Y422847D03*
X1524858D03*
X1526958Y419247D03*
X1524858D03*
X1526958Y437021D03*
X1524858D03*
X1526958Y433421D03*
X1524858D03*
X1516556Y429960D03*
X1514456D03*
X1516556Y426360D03*
X1514456D03*
X1516556Y440533D03*
X1514456D03*
X1516556Y444133D03*
X1514456D03*
X1516556Y472887D03*
X1514456D03*
X1516556Y469287D03*
X1514456D03*
X1516556Y487060D03*
X1514456D03*
X1526958Y490573D03*
X1524858D03*
X1526958Y476399D03*
X1524858D03*
X1526958Y479999D03*
X1524858D03*
X1516556Y483460D03*
X1514456D03*
X1526958Y494173D03*
X1524858D03*
X1516556Y517021D03*
X1514456D03*
X1516556Y513421D03*
X1514456D03*
X1526958Y520533D03*
X1524858D03*
X1516556Y531194D03*
X1514456D03*
X1516556Y527594D03*
X1514456D03*
X1526958Y524133D03*
X1524858D03*
X1526958Y534706D03*
X1524858D03*
X1526958Y538306D03*
X1524858D03*
X1542621Y111123D03*
X1544721D03*
X1542621Y114723D03*
X1544721D03*
X1542621Y125296D03*
X1544721D03*
X1542621Y128896D03*
X1544721D03*
X1553023Y118235D03*
X1555123D03*
X1553023Y121835D03*
X1555123D03*
X1553023Y132409D03*
X1555123D03*
X1553023Y136009D03*
X1555123D03*
X1644983Y111123D03*
X1647083D03*
X1644983Y114723D03*
X1647083D03*
X1655385Y118235D03*
X1657485D03*
X1655385Y121835D03*
X1657485D03*
X1655385Y132409D03*
X1657485D03*
X1644983Y125296D03*
X1647083D03*
X1644983Y128896D03*
X1647083D03*
X1655385Y136009D03*
X1657485D03*
X1685247Y467206D03*
X1687347D03*
X1685247Y470806D03*
X1687347D03*
X1685247Y481379D03*
X1687347D03*
X1685247Y484979D03*
X1687347D03*
X1685247Y511339D03*
X1687347D03*
X1685247Y514939D03*
X1687347D03*
X1685247Y525513D03*
X1687347D03*
X1685247Y529113D03*
X1687347D03*
X1685247Y564979D03*
X1687347D03*
X1685247Y561379D03*
X1687347D03*
X1685247Y579152D03*
X1687347D03*
X1685247Y575552D03*
X1687347D03*
X1685247Y593325D03*
X1687347D03*
X1685247Y589725D03*
X1687347D03*
X1685247Y603899D03*
X1687347D03*
X1685247Y607499D03*
X1687347D03*
X1695649Y474318D03*
X1697749D03*
X1695649Y488491D03*
X1697749D03*
X1695649Y477918D03*
X1697749D03*
X1695649Y492091D03*
X1697749D03*
X1695649Y518452D03*
X1697749D03*
X1695649Y522052D03*
X1697749D03*
X1695649Y532625D03*
X1697749D03*
X1695649Y536225D03*
X1697749D03*
X1695649Y568491D03*
X1697749D03*
X1695649Y572091D03*
X1697749D03*
X1695649Y582665D03*
X1697749D03*
X1695649Y586265D03*
X1697749D03*
X1695649Y596838D03*
X1697749D03*
X1695649Y600438D03*
X1697749D03*
X1695649Y614611D03*
X1697749D03*
X1695649Y611011D03*
X1697749D03*
X1747345Y111123D03*
X1749445D03*
X1747345Y114723D03*
X1749445D03*
X1757747Y118235D03*
Y121835D03*
X1747345Y125296D03*
X1749445D03*
X1747345Y128896D03*
X1749445D03*
X1757747Y132409D03*
Y136009D03*
X1759847Y118235D03*
Y121835D03*
Y132409D03*
Y136009D03*
X1818878Y1041550D03*
X1816778D03*
X1819068Y1056783D03*
X1816968D03*
X1818959Y1051219D03*
X1816859D03*
X1818902Y1046756D03*
X1816802D03*
G54D49*
X34731Y1199141D03*
X45755Y1212527D03*
X410938Y870105D03*
X421962Y883491D03*
X427063Y626268D03*
X438087Y639654D03*
X878421Y1208144D03*
X889445Y1221530D03*
X942398Y1208144D03*
X953422Y1221530D03*
X1786378Y1208630D03*
X1797402Y1222016D03*
G54D94*
X76388Y670837D03*
X74419D03*
X78356Y678711D03*
X74419D03*
X76388D03*
X80325D03*
Y670837D03*
X78356D03*
G54D76*
X46348Y1727941D03*
Y1737941D03*
X46248Y1760941D03*
Y1750941D03*
X46348Y1773941D03*
Y1783941D03*
X46248Y1806941D03*
Y1796941D03*
X318448Y1727941D03*
Y1737941D03*
Y1750941D03*
Y1760941D03*
Y1773941D03*
Y1783941D03*
X318348Y1796941D03*
Y1806941D03*
X333286Y1728583D03*
Y1738583D03*
X333112Y1751624D03*
X333212Y1774624D03*
X333112Y1761624D03*
X333212Y1784624D03*
Y1797624D03*
Y1807624D03*
X605386Y1728583D03*
Y1738583D03*
X605312Y1751624D03*
Y1774624D03*
Y1761624D03*
Y1784624D03*
Y1807624D03*
Y1797624D03*
X620083Y1728286D03*
Y1738286D03*
X619861Y1751765D03*
X619711Y1775438D03*
X619861Y1761765D03*
X619711Y1785438D03*
X619475Y1798845D03*
Y1808845D03*
X892183Y1728286D03*
Y1738286D03*
X891911Y1751765D03*
X891761Y1775438D03*
X891911Y1761765D03*
X891761Y1785438D03*
X891525Y1808845D03*
Y1798845D03*
X907279Y1738990D03*
Y1728990D03*
X907163Y1752566D03*
Y1762566D03*
X907073Y1776014D03*
Y1786014D03*
X907166Y1800435D03*
Y1810435D03*
X1179329Y1728990D03*
Y1738990D03*
X1179263Y1752566D03*
Y1762566D03*
X1179123Y1776014D03*
Y1786014D03*
X1179216Y1800435D03*
Y1810435D03*
G54D187*
X736702Y1431659D03*
Y1451659D03*
X747528Y1441659D03*
G54D278*
G01X1020406Y348631D02*
Y350772D01*
G54D269*
G01X204921Y1217322D02*
X203051Y1215452D01*
G01X212401Y1217322D02*
X214271Y1215452D01*
G01X231102Y1213582D02*
X229232Y1211712D01*
G01X227362Y1213582D02*
X225492Y1211712D01*
G01X223622Y1213582D02*
X221752Y1211712D01*
G01X223622Y1217322D02*
X221752Y1215452D01*
G01X261023Y1213582D02*
X259153Y1215452D01*
G01X253543Y1213582D02*
X251673Y1215452D01*
G01X275984Y1213582D02*
X274114Y1215452D01*
G01X279724Y1213582D02*
X277854Y1215452D01*
G01X268503Y1213582D02*
X266633Y1215452D01*
G01X294685Y1168700D02*
X292815Y1170570D01*
G01X287204Y1187401D02*
X285334Y1189271D01*
G01X287204Y1191141D02*
X289074Y1189271D01*
G01X302165Y1172440D02*
X304035Y1174310D01*
G01X298425Y1168700D02*
X296555Y1170570D01*
G01X305905Y1172440D02*
X307775Y1174310D01*
G01X313385Y1172440D02*
X311515Y1170570D01*
G01X302165Y1179921D02*
X304035Y1181791D01*
G01X302165Y1187401D02*
X304035Y1189271D01*
G01X305905Y1179921D02*
X307775Y1181791D01*
G01X305905Y1187401D02*
X307775Y1189271D01*
G01X313385Y1179921D02*
X311515Y1178051D01*
G01X313385Y1187401D02*
X311515Y1185531D01*
G01X313385Y1194881D02*
X311515Y1193011D01*
G01X317125Y1172440D02*
X315255Y1170570D01*
G01X317125Y1179921D02*
X315255Y1178051D01*
G01X317125Y1187401D02*
X315255Y1185531D01*
G01X317125Y1194881D02*
X315255Y1193011D01*
G01X662008Y1217322D02*
X660138Y1215452D01*
G01X676968Y1213582D02*
X675098Y1211712D01*
G01X684449Y1213582D02*
X682579Y1211712D01*
G01X680709Y1213582D02*
X678839Y1211712D01*
G01X680709Y1217322D02*
X678839Y1215452D01*
G01X669488Y1217322D02*
X671358Y1215452D01*
G01X688189Y1213582D02*
X686319Y1211712D01*
G01X718110Y1213582D02*
X716240Y1215452D01*
G01X710630Y1213582D02*
X708760Y1215452D01*
G01X733071Y1213582D02*
X731201Y1215452D01*
G01X725590Y1213582D02*
X723720Y1215452D01*
G01X751772Y1168700D02*
X749902Y1170570D01*
G01X744291Y1187401D02*
X742421Y1189271D01*
G01X744291Y1191141D02*
X746161Y1189271D01*
G01X736811Y1213582D02*
X734941Y1215452D01*
G01X762992Y1172440D02*
X764862Y1174310D01*
G01X755512Y1168700D02*
X753642Y1170570D01*
G01X759252Y1172440D02*
X761122Y1174310D01*
G01X759252Y1179921D02*
X761122Y1181791D01*
G01X762992Y1179921D02*
X764862Y1181791D01*
G01X774212Y1172440D02*
X772342Y1170570D01*
G01X770472Y1172440D02*
X768602Y1170570D01*
G01X770472Y1187401D02*
X768602Y1185531D01*
G01X774212Y1179921D02*
X772342Y1178051D01*
G01X774212Y1187401D02*
X772342Y1185531D01*
G01X770472Y1179921D02*
X768602Y1178051D01*
G01X770472Y1194881D02*
X768602Y1193011D01*
G01X774212Y1194881D02*
X772342Y1193011D01*
G01X925467Y842138D02*
X927995D01*
G01X1119094Y1217322D02*
X1117224Y1215452D01*
G01X1134054Y1213582D02*
X1132184Y1211712D01*
G01X1141535Y1213582D02*
X1139665Y1211712D01*
G01X1137795Y1213582D02*
X1135925Y1211712D01*
G01X1137795Y1217322D02*
X1135925Y1215452D01*
G01X1126574Y1217322D02*
X1128444Y1215452D01*
G01X1145275Y1213582D02*
X1143405Y1211712D01*
G01X1167716Y1213582D02*
X1165846Y1215452D01*
G01X1190157Y1213582D02*
X1188287Y1215452D01*
G01X1175196Y1213582D02*
X1173326Y1215452D01*
G01X1182676Y1213582D02*
X1180806Y1215452D01*
G01X1201377Y1187401D02*
X1199507Y1189271D01*
G01X1201377Y1191141D02*
X1203247Y1189271D01*
G01X1193897Y1213582D02*
X1192027Y1215452D01*
G01X1216338Y1172440D02*
X1218208Y1174310D01*
G01X1212598Y1168700D02*
X1210728Y1170570D01*
G01X1220078Y1172440D02*
X1221948Y1174310D01*
G01X1208858Y1168700D02*
X1206988Y1170570D01*
G01X1216338Y1187401D02*
X1218208Y1189271D01*
G01X1220078Y1179921D02*
X1221948Y1181791D01*
G01X1216338Y1179921D02*
X1218208Y1181791D01*
G01X1220078Y1187401D02*
X1221948Y1189271D01*
G01X1231298Y1172440D02*
X1229428Y1170570D01*
G01X1227558Y1172440D02*
X1225688Y1170570D01*
G01X1227558Y1187401D02*
X1225688Y1185531D01*
G01X1231298Y1179921D02*
X1229428Y1178051D01*
G01X1231298Y1187401D02*
X1229428Y1185531D01*
G01X1227558Y1179921D02*
X1225688Y1178051D01*
G01X1227558Y1194881D02*
X1225688Y1193011D01*
G01X1231298Y1194881D02*
X1229428Y1193011D01*
G01X1576181Y1217322D02*
X1574311Y1215452D01*
G01X1591141Y1213582D02*
X1589271Y1211712D01*
G01X1594882Y1213582D02*
X1593012Y1211712D01*
G01X1594882Y1217322D02*
X1593012Y1215452D01*
G01X1583661Y1217322D02*
X1585531Y1215452D01*
G01X1602362Y1213582D02*
X1600492Y1211712D01*
G01X1598622Y1213582D02*
X1596752Y1211712D01*
G01X1624803Y1213582D02*
X1622933Y1215452D01*
G01X1632283Y1213582D02*
X1630413Y1215452D01*
G01X1639763Y1213582D02*
X1637893Y1215452D01*
G01X1658464Y1187401D02*
X1656594Y1189271D01*
G01X1658464Y1191141D02*
X1660334Y1189271D01*
G01X1647244Y1213582D02*
X1645374Y1215452D01*
G01X1650984Y1213582D02*
X1649114Y1215452D01*
G01X1665945Y1168700D02*
X1664075Y1170570D01*
G01X1669685Y1168700D02*
X1667815Y1170570D01*
G01X1673425Y1172440D02*
X1675295Y1174310D01*
G01X1673425Y1187401D02*
X1675295Y1189271D01*
G01X1673425Y1179921D02*
X1675295Y1181791D01*
G01X1677165Y1172440D02*
X1679035Y1174310D01*
G01X1688385Y1172440D02*
X1686515Y1170570D01*
G01X1684645Y1172440D02*
X1682775Y1170570D01*
G01X1677165Y1179921D02*
X1679035Y1181791D01*
G01X1677165Y1187401D02*
X1679035Y1189271D01*
G01X1688385Y1187401D02*
X1686515Y1185531D01*
G01X1684645Y1179921D02*
X1682775Y1178051D01*
G01X1688385Y1179921D02*
X1686515Y1178051D01*
G01X1684645Y1187401D02*
X1682775Y1185531D01*
G01X1688385Y1194881D02*
X1686515Y1193011D01*
G01X1684645Y1194881D02*
X1682775Y1193011D01*
G54D77*
X59848Y211751D03*
Y227499D03*
X59617Y271043D03*
Y286791D03*
X83374Y480347D03*
Y496095D03*
X73543Y526091D03*
Y541839D03*
X162210Y211751D03*
Y227499D03*
X161979Y271043D03*
Y286791D03*
X264572Y211751D03*
Y227499D03*
X264341Y271043D03*
Y286791D03*
X348329Y476109D03*
Y491857D03*
X366934Y211751D03*
Y227499D03*
X366703Y271043D03*
Y286791D03*
X390521Y437459D03*
Y453207D03*
X419390Y496242D03*
Y511990D03*
X516935Y211751D03*
Y227499D03*
X516704Y271043D03*
Y286791D03*
X540460Y480347D03*
Y496095D03*
X530629Y526091D03*
Y541839D03*
X619297Y211751D03*
Y227499D03*
X619066Y271043D03*
Y286791D03*
X721659Y211751D03*
Y227499D03*
X721428Y271043D03*
Y286791D03*
X805415Y471109D03*
Y486857D03*
X824021Y211751D03*
Y227499D03*
X823790Y271043D03*
Y286791D03*
X885801Y453800D03*
Y469548D03*
X974021Y211751D03*
Y227499D03*
X973790Y271043D03*
Y286791D03*
X987716Y526091D03*
Y541839D03*
X997547Y480347D03*
Y496095D03*
X1076383Y211751D03*
Y227499D03*
X1076152Y271043D03*
Y286791D03*
X1178745Y211751D03*
Y227499D03*
X1178514Y271043D03*
Y286791D03*
X1262502Y476109D03*
Y491857D03*
X1281107Y211751D03*
Y227499D03*
X1280876Y271043D03*
Y286791D03*
X1304748Y437459D03*
Y453207D03*
X1431108Y211751D03*
Y227499D03*
X1430877Y271043D03*
Y286791D03*
X1444803Y526091D03*
Y541839D03*
X1454634Y480347D03*
Y496095D03*
X1533470Y211751D03*
Y227499D03*
X1533239Y271043D03*
Y286791D03*
X1635832Y211751D03*
Y227499D03*
X1635601Y271043D03*
Y286791D03*
X1719589Y476109D03*
Y491857D03*
X1738194Y211751D03*
Y227499D03*
X1737963Y271043D03*
Y286791D03*
X1761835Y437459D03*
Y453207D03*
G54D197*
X812474Y1452587D03*
X864671Y1452589D03*
X906671D03*
G54D95*
X77372Y674774D03*
G54D179*
X650958Y672360D03*
Y682006D03*
X658438Y672360D03*
Y682006D03*
X654698D03*
X767282Y1595014D03*
X763542D03*
X759802D03*
Y1604660D03*
X767282D03*
X806318Y1387865D03*
X813798D03*
Y1397511D03*
X806318D03*
X810058D03*
X924932Y687237D03*
Y696883D03*
X928672D03*
X932412Y687237D03*
Y696883D03*
X954023Y711157D03*
X961503D03*
X954023Y720803D03*
X961503D03*
X957763D03*
X1108045Y672360D03*
Y682006D03*
X1115525Y672360D03*
Y682006D03*
X1111785D03*
X1565132Y672360D03*
X1572612D03*
X1565132Y682006D03*
X1572612D03*
X1568872D03*
G54D86*
X68529Y1201565D03*
Y1205835D03*
X207354Y200864D03*
X204204D03*
X309716D03*
X306566D03*
X390470Y1516448D03*
X393620D03*
X408928Y200864D03*
X404053Y1516556D03*
X400903D03*
X412078Y200864D03*
X485485Y552726D03*
X488635D03*
X562079Y200864D03*
X558929D03*
X664441D03*
X661291D03*
X869165D03*
X866015D03*
X912085Y323302D03*
Y329602D03*
X912220Y1214838D03*
Y1210568D03*
X915235Y323302D03*
X923902D03*
X920752D03*
X915235Y329602D03*
X923902D03*
X920752D03*
X943787Y336817D03*
X935137D03*
X938287D03*
X943787Y330517D03*
X935137D03*
X938287D03*
X942572Y552726D03*
X945722D03*
X946937Y336817D03*
Y330517D03*
X976197Y1214838D03*
Y1210568D03*
X1399659Y552726D03*
X1402809D03*
X1820177Y1215324D03*
Y1211054D03*
G54D188*
X733058Y1614451D03*
X739358Y1611892D03*
Y1617010D03*
G54D59*
X54060Y492696D03*
X44229Y539440D03*
X89162Y214150D03*
X191524D03*
X293886D03*
X375084Y477527D03*
X396248Y214150D03*
X448704Y498641D03*
X501315Y539440D03*
X511146Y492696D03*
X546249Y214150D03*
X648611D03*
X750973D03*
X832170Y472527D03*
X853335Y214150D03*
X958402Y539440D03*
X968233Y492696D03*
X1003335Y214150D03*
X1105697D03*
X1208059D03*
X1289257Y477527D03*
X1310421Y214150D03*
X1415489Y539440D03*
X1425320Y492696D03*
X1460422Y214150D03*
X1562784D03*
X1665146D03*
X1746344Y477527D03*
X1767508Y214150D03*
G54D68*
X49754Y1079154D03*
X51723D03*
X49754Y1090178D03*
X51723D03*
X55660D03*
Y1079154D03*
X53691D03*
Y1090178D03*
X76452Y582336D03*
X70546D03*
X74483D03*
X72515D03*
X70546Y593360D03*
X72515D03*
X76452D03*
X74483D03*
X86992Y177338D03*
X92898D03*
X90929D03*
X88961D03*
X92898Y188362D03*
X86992D03*
X88961D03*
X90929D03*
X189354Y177338D03*
X195260D03*
X193291D03*
X191323D03*
X195260Y188362D03*
X189354D03*
X191323D03*
X193291D03*
X291716Y177338D03*
X295653D03*
X293685D03*
X291716Y188362D03*
X293685D03*
X295653D03*
X297622Y177338D03*
Y188362D03*
X360480Y389013D03*
X356543D03*
X358512D03*
X356543Y400037D03*
X358512D03*
X360480D03*
X362449Y389013D03*
Y400037D03*
X384856Y952115D03*
X390762D03*
X388793D03*
X386825D03*
X390762Y963139D03*
X384856D03*
X386825D03*
X388793D03*
X394078Y177338D03*
X399984D03*
X398015D03*
X396047D03*
X399984Y188362D03*
X394078D03*
X396047D03*
X398015D03*
X409101Y1110233D03*
X419731D03*
X425046D03*
X416187D03*
X412644D03*
X421502D03*
X423274D03*
X417959D03*
X410872D03*
X414416D03*
X441229D03*
X451859D03*
X457174D03*
X448315D03*
X444772D03*
X453630D03*
X455402D03*
X450087D03*
X443000D03*
X446544D03*
X474688D03*
X485318D03*
X490633D03*
X481774D03*
X478231D03*
X487089D03*
X488861D03*
X483546D03*
X476459D03*
X480003D03*
X506816D03*
X517446D03*
X522761D03*
X513902D03*
X510359D03*
X519217D03*
X520989D03*
X515674D03*
X508587D03*
X512131D03*
X533538Y582336D03*
X527632D03*
X531569D03*
X529601D03*
X527632Y593360D03*
X529601D03*
X533538D03*
X531569D03*
X544079Y177338D03*
X549985D03*
X548016D03*
X546048D03*
X549985Y188362D03*
X544079D03*
X546048D03*
X548016D03*
X646441Y177338D03*
X652347D03*
X650378D03*
X648410D03*
X652347Y188362D03*
X646441D03*
X648410D03*
X650378D03*
X748803Y177338D03*
Y188362D03*
X754709Y177338D03*
X752740D03*
X750772D03*
X754709Y188362D03*
X750772D03*
X752740D03*
X851165Y177338D03*
X857071D03*
X855102D03*
X853134D03*
X857071Y188362D03*
X851165D03*
X853134D03*
X855102D03*
X857298Y408038D03*
X863204D03*
X859267D03*
X863204Y397014D03*
X861235Y408038D03*
Y397014D03*
X857298D03*
X859267D03*
X896444Y1088157D03*
Y1099181D03*
X902350Y1088157D03*
X900381D03*
X898413D03*
Y1099181D03*
X900381D03*
X902350D03*
X960421Y1088157D03*
Y1099181D03*
X966327Y1088157D03*
X964358D03*
X962390D03*
Y1099181D03*
X964358D03*
X966327D03*
X990625Y582336D03*
X984719D03*
X988656D03*
X986688D03*
X984719Y593360D03*
X986688D03*
X990625D03*
X988656D03*
X1001165Y177338D03*
X1007071D03*
X1005102D03*
X1003134D03*
X1007071Y188362D03*
X1001165D03*
X1003134D03*
X1005102D03*
X1103527Y177338D03*
X1107464D03*
X1105496D03*
X1103527Y188362D03*
X1105496D03*
X1107464D03*
X1109433Y177338D03*
Y188362D03*
X1205889Y177338D03*
X1211795D03*
X1209826D03*
X1207858D03*
X1211795Y188362D03*
X1205889D03*
X1207858D03*
X1209826D03*
X1276622Y389013D03*
X1274653D03*
X1270716D03*
X1272685D03*
X1270716Y400037D03*
X1276622D03*
X1272685D03*
X1274653D03*
X1308251Y177338D03*
X1314157D03*
X1312188D03*
X1310220D03*
X1314157Y188362D03*
X1308251D03*
X1310220D03*
X1312188D03*
X1323275Y1110233D03*
X1333905D03*
X1330361D03*
X1326818D03*
X1332133D03*
X1325046D03*
X1328590D03*
X1339220D03*
X1335676D03*
X1337448D03*
X1355403D03*
X1366033D03*
X1362489D03*
X1358946D03*
X1367804D03*
X1364261D03*
X1357174D03*
X1360718D03*
X1371348D03*
X1369576D03*
X1388862D03*
X1399492D03*
X1395948D03*
X1392405D03*
X1397720D03*
X1390633D03*
X1394177D03*
X1404807D03*
X1401263D03*
X1403035D03*
X1420990D03*
X1431620D03*
X1428076D03*
X1424533D03*
X1429848D03*
X1422761D03*
X1426305D03*
X1447712Y582336D03*
X1441806D03*
X1445743D03*
X1443775D03*
X1441806Y593360D03*
X1443775D03*
X1447712D03*
X1445743D03*
X1436935Y1110233D03*
X1433391D03*
X1435163D03*
X1458252Y177338D03*
X1464158D03*
X1462189D03*
X1460221D03*
X1464158Y188362D03*
X1458252D03*
X1460221D03*
X1462189D03*
X1560614Y177338D03*
X1562583D03*
X1560614Y188362D03*
X1562583D03*
X1566520Y177338D03*
X1564551D03*
X1566520Y188362D03*
X1564551D03*
X1662976Y177338D03*
X1668882D03*
X1666913D03*
X1664945D03*
X1668882Y188362D03*
X1662976D03*
X1664945D03*
X1666913D03*
X1733709Y389013D03*
X1731740D03*
X1727803D03*
X1729772D03*
X1727803Y400037D03*
X1733709D03*
X1729772D03*
X1731740D03*
X1765338Y177338D03*
X1771244D03*
X1769275D03*
X1767307D03*
X1771244Y188362D03*
X1765338D03*
X1767307D03*
X1769275D03*
X1804401Y1088643D03*
X1806370D03*
X1804401Y1099667D03*
X1806370D03*
X1810307Y1088643D03*
X1808338D03*
X1810307Y1099667D03*
X1808338D03*
G54D279*
G01X238582Y1112598D02*
X240452Y1114468D01*
G01X242322Y1112598D02*
X244192Y1114468D01*
G01X234842Y1116338D02*
X236712Y1118208D01*
G01X242322Y1116338D02*
X244192Y1118208D01*
G01X234842Y1112598D02*
X236712Y1114468D01*
G01X238582Y1116338D02*
X240452Y1118208D01*
G01X249803Y1112598D02*
X251673Y1114468D01*
G01X249803Y1116338D02*
X251673Y1118208D01*
G01X691929Y1112598D02*
X693799Y1114468D01*
G01X691929Y1116338D02*
X693799Y1118208D01*
G01X699409Y1112598D02*
X701279Y1114468D01*
G01X695669Y1116338D02*
X697539Y1118208D01*
G01X695669Y1112598D02*
X697539Y1114468D01*
G01X699409Y1116338D02*
X701279Y1118208D01*
G01X706890Y1112598D02*
X708760Y1114468D01*
G01X706890Y1116338D02*
X708760Y1118208D01*
G01X1152755Y1116338D02*
X1154625Y1118208D01*
G01X1149015Y1116338D02*
X1150885Y1118208D01*
G01X1152755Y1112598D02*
X1154625Y1114468D01*
G01X1156495Y1116338D02*
X1158365Y1118208D01*
G01X1156495Y1112598D02*
X1158365Y1114468D01*
G01X1149015Y1112598D02*
X1150885Y1114468D01*
G01X1163976Y1112598D02*
X1165846Y1114468D01*
G01X1163976Y1116338D02*
X1165846Y1118208D01*
G01X1606102Y1112598D02*
X1607972Y1114468D01*
G01X1609842Y1116338D02*
X1611712Y1118208D01*
G01X1606102Y1116338D02*
X1607972Y1118208D01*
G01X1609842Y1112598D02*
X1611712Y1114468D01*
G01X1613582Y1116338D02*
X1615452Y1118208D01*
G01X1613582Y1112598D02*
X1615452Y1114468D01*
G01X1621063Y1112598D02*
X1622933Y1114468D01*
G01X1621063Y1116338D02*
X1622933Y1118208D01*
G54D189*
X742224Y1594417D03*
X749704D03*
X745964D03*
Y1604731D03*
X742224D03*
X749704D03*
G54D78*
X67159Y560848D03*
X85663D03*
X346698Y422440D03*
X365202D03*
X524245Y560848D03*
X542749D03*
X839129Y429363D03*
X857633D03*
X981332Y560848D03*
X999836D03*
X1260871Y422440D03*
X1279375D03*
X1438419Y560848D03*
X1456923D03*
X1717958Y422440D03*
X1736462D03*
G54D87*
X66479Y1201565D03*
Y1205835D03*
X910170Y1214838D03*
Y1210568D03*
X974147Y1214838D03*
Y1210568D03*
X1818127Y1215324D03*
Y1211054D03*
G54D198*
X832961Y308900D03*
Y337836D03*
X855993Y308900D03*
Y337836D03*
X1298246Y748010D03*
Y776946D03*
X1321278Y748010D03*
Y776946D03*
X1350984Y561032D03*
Y589968D03*
Y607532D03*
Y636468D03*
Y652032D03*
Y680968D03*
Y699032D03*
Y727968D03*
X1374016Y561032D03*
Y589968D03*
Y607532D03*
Y636468D03*
Y652032D03*
Y680968D03*
Y699032D03*
Y727968D03*
X1441984Y683532D03*
Y712468D03*
Y727532D03*
Y756468D03*
X1465016Y683532D03*
Y712468D03*
Y727532D03*
Y756468D03*
X1458984Y769032D03*
Y797968D03*
Y813032D03*
Y841968D03*
X1482016Y769032D03*
Y797968D03*
Y813032D03*
Y841968D03*
G54D96*
G01X14751Y66681D02*
Y62381D01*
G01X16728Y111710D02*
Y107910D01*
G01X6499Y135789D02*
Y134001D01*
X8460Y132040D01*
Y128836D01*
G01X6499Y138939D02*
X9057D01*
G01X19184Y147228D02*
Y144728D01*
G01X15184Y147228D02*
Y144728D01*
G01X9082Y135789D02*
X6499D01*
G01X19855Y138962D02*
Y141362D01*
G01X12709Y173377D02*
Y175777D01*
G01X9745Y248371D02*
Y245784D01*
G01X18826Y236052D02*
X18564Y238589D01*
G01X18463Y253198D02*
X21449D01*
G01X18463Y273198D02*
X21386D01*
G01X19075Y281129D02*
Y278429D01*
G01X9745Y268371D02*
X7036D01*
G01X6385Y997697D02*
Y994722D01*
X8788Y992319D01*
G01X14513D02*
Y994605D01*
X11449Y997669D01*
G01X6811Y1002546D02*
Y1000909D01*
X6385Y1000483D01*
Y997697D01*
G01X20006Y992319D02*
Y994311D01*
X16647Y997670D01*
G01D02*
X14645Y999672D01*
Y1002546D01*
G01X11449Y997669D02*
X10891Y998227D01*
Y1002356D01*
X10701Y1002546D01*
G01X11768Y1522198D02*
Y1519761D01*
X12327Y1519202D01*
G01X11781Y1532462D02*
Y1534920D01*
X11995Y1535134D01*
G01X18409Y1554202D02*
Y1551782D01*
X18434Y1551757D01*
G01X14375Y1550648D02*
Y1553121D01*
G01X6560Y1550686D02*
X6567Y1550693D01*
Y1554215D01*
G01X10367Y1550655D02*
Y1553080D01*
G01X9607Y1556883D02*
X10367Y1556123D01*
Y1553080D01*
G01X29023Y97667D02*
X26588D01*
G01X24839Y106495D02*
X22439D01*
G01X24839Y102495D02*
X22439D01*
G01X23184Y147228D02*
Y144728D01*
G01X20709Y173377D02*
Y175777D01*
G01X36201Y236134D02*
Y238714D01*
G01X24091Y236121D02*
X21530D01*
G01X25549Y247292D02*
X28740D01*
G01X23844Y242078D02*
Y239299D01*
G01X24091Y232971D02*
X21556D01*
G01X33506Y250599D02*
Y248698D01*
X31682Y246874D01*
G01X23844Y262078D02*
X26325D01*
G01X25549Y267292D02*
X28740D01*
G01X33506Y270599D02*
Y268698D01*
X31682Y266874D01*
G01X23479Y292608D02*
Y295619D01*
G01X34845Y285272D02*
X37284D01*
G01X26629Y292608D02*
Y295619D01*
G01X26161Y287035D02*
X26629Y287503D01*
Y292608D01*
G01X30117Y621311D02*
X27686D01*
G01X30117Y629311D02*
X27686D01*
G01X36293Y992319D02*
X36297Y992323D01*
Y996414D01*
X34987Y997724D01*
G01X29275Y997737D02*
X30841Y996171D01*
Y992381D01*
X30903Y992319D01*
G01X22792Y997712D02*
X25331Y995173D01*
Y992450D01*
X25462Y992319D01*
G01X34987Y997724D02*
X33659Y999052D01*
Y1002546D01*
G01X27556D02*
Y999456D01*
X29275Y997737D01*
G01X21506Y1002546D02*
Y998998D01*
X22792Y997712D01*
G01X27222Y1438552D02*
X29860D01*
G01X20041Y1449735D02*
X23603D01*
G01X25674Y1488716D02*
Y1486291D01*
G01X35850Y1553305D02*
Y1556096D01*
G01X22381Y1551752D02*
Y1554152D01*
G01X26231Y1551734D02*
Y1554167D01*
G01X39423Y163264D02*
X45984D01*
G01X48476Y177606D02*
Y180812D01*
G01X42690Y454376D02*
Y451466D01*
G01X48596Y461462D02*
Y458466D01*
G01X48643Y445344D02*
Y442919D01*
G01X45643Y470494D02*
Y472905D01*
G01X49643Y470494D02*
Y472905D01*
G01X36692Y639386D02*
Y641817D01*
G01X42192Y639386D02*
Y641817D01*
G01X50602Y978296D02*
X51946Y979640D01*
Y997678D01*
G01X47234Y992319D02*
X47154Y992399D01*
Y996618D01*
X46108Y997664D01*
G01X40334Y997805D02*
X41792Y996347D01*
Y992319D01*
G01X51946Y997678D02*
Y1002546D01*
G01X46108Y997664D02*
X45858Y997914D01*
Y1002546D01*
G01X39549D02*
Y998590D01*
X40334Y997805D01*
G01X40700Y1089721D02*
X38200D01*
G01X40616Y1093757D02*
X38216D01*
G01X46166D02*
X43766D01*
G01X44960Y1193263D02*
Y1190619D01*
G01X47621Y1335419D02*
Y1343672D01*
G01X52048Y1553271D02*
Y1556062D01*
G01X47074Y1553296D02*
Y1555923D01*
G01X40951Y1553305D02*
Y1555932D01*
G01X61759Y439919D02*
Y437508D01*
G01X65759Y439919D02*
Y437508D01*
G01X57759Y439919D02*
Y437508D01*
G01X54936Y451763D02*
Y449352D01*
G01X66224Y470634D02*
Y473045D01*
G01X58224Y470634D02*
Y473045D01*
G01X53643Y470494D02*
Y472905D01*
G01X60267Y608311D02*
X62789D01*
G01X63988Y628242D02*
X66510D01*
G01X52599Y688473D02*
X55307D01*
G01X58504Y900295D02*
X52922D01*
G01X61555Y978296D02*
X62211Y978952D01*
Y997892D01*
G01X68342Y992014D02*
Y997687D01*
X68448Y997793D01*
G01X57909Y992176D02*
Y997189D01*
X57214Y997884D01*
G01X65774Y1002546D02*
X68448Y999872D01*
Y997793D01*
G01X61779Y1002546D02*
X62211Y1002114D01*
Y997892D01*
G01X57834Y1002546D02*
X57214Y1001926D01*
Y997884D01*
G01X67659Y1071656D02*
X70059D01*
G01X67659Y1075656D02*
X70059D01*
G01X67659Y1067656D02*
X70302D01*
G01X53299Y1072761D02*
X55699D01*
G01X62109Y1087656D02*
X64509D01*
G01X54351Y1480808D02*
X57185D01*
G01X65478Y1544571D02*
Y1541980D01*
G01X56114Y1553270D02*
Y1556061D01*
G01X64747Y1553263D02*
Y1555890D01*
G01X63090Y1612002D02*
X60554D01*
G01X63090Y1615152D02*
Y1620601D01*
X64881Y1622392D01*
X67024D01*
X68689Y1620727D01*
Y1618721D01*
G01X63090Y1615152D02*
X60554D01*
G01X66291Y1631377D02*
Y1633801D01*
G01X73110Y98551D02*
X70577D01*
G01Y101701D02*
X73110D01*
G01X84808Y103603D02*
X88080D01*
G01X80660Y101348D02*
Y103783D01*
G01X76660Y101348D02*
Y103783D01*
G01X78170Y141247D02*
X75194D01*
G01X74200Y147540D02*
X71422D01*
G01X82918Y152367D02*
X85904D01*
G01X74200Y151540D02*
X71422D01*
G01X76766Y259535D02*
Y256535D01*
G01X84766Y259535D02*
Y256535D01*
G01X75819Y288058D02*
Y290755D01*
G01X79819Y288058D02*
Y290755D01*
G01X83819Y288058D02*
Y290755D01*
G01X84699Y1001391D02*
Y999514D01*
X85706Y998507D01*
G01X84679Y1015166D02*
Y1018368D01*
G01X102761Y1096233D02*
X97561D01*
X83353Y1082025D01*
Y1040639D01*
X90450Y1033542D01*
G01X71020Y1224323D02*
X84215D01*
X101509Y1207029D01*
X103027D01*
G01X83689Y1597855D02*
X87000D01*
G01X74291Y1631377D02*
Y1633801D01*
G01X82291Y1631377D02*
Y1633801D01*
G01X78291Y1631377D02*
Y1633801D01*
G01X70291Y1631377D02*
Y1633801D01*
G01X90004Y146461D02*
X87002D01*
G01X97961Y149768D02*
Y152562D01*
G01X127235Y445506D02*
X90257D01*
G01X93456Y652250D02*
Y649838D01*
G01X102355Y874267D02*
X101327Y875295D01*
X96930D01*
G01X99836Y982956D02*
Y980330D01*
G01X95836Y982956D02*
X99836D01*
G01D02*
X103836D01*
G01X91765Y1009260D02*
Y1007124D01*
X91128Y1006487D01*
G01X99836Y995106D02*
Y997860D01*
G01X95836Y995106D02*
Y997860D01*
G01X94586Y1021177D02*
Y1023900D01*
G01X97609Y1018469D02*
Y1013972D01*
G01X86291Y1631377D02*
Y1633801D01*
G01X111582Y104749D02*
Y102249D01*
G01X115582Y104749D02*
Y102249D01*
G01X110152Y130898D02*
X107607D01*
G01X111754Y134579D02*
X111303Y135030D01*
X111270D01*
X109558Y136742D01*
X108643D01*
G01X121840Y142862D02*
X119259D01*
X119045Y142648D01*
X115729D01*
G01X106796Y158015D02*
Y160715D01*
X106205Y161306D01*
G01X104989Y225719D02*
Y221867D01*
X104992Y221864D01*
G01X112107Y252371D02*
X109329D01*
G01X103836Y982956D02*
Y980330D01*
G01X115836Y982956D02*
X119836D01*
G01X103836D02*
X107836D01*
G01D02*
X111836D01*
G01D02*
X115836D01*
G01X103836Y995106D02*
Y997860D01*
G01X111836Y995106D02*
Y997860D01*
G01X107836Y995106D02*
Y997860D01*
G01X115836Y995106D02*
Y997860D01*
G01X109415Y1202103D02*
Y1202787D01*
X111681Y1205053D01*
X112365D01*
G01X109536Y1207882D02*
X106586Y1204932D01*
G01X115193Y1202225D02*
X115207D01*
X117012Y1200420D01*
X119558D01*
X121290Y1202152D01*
Y1211541D01*
G01X103027Y1207029D02*
Y1203125D01*
X107506Y1198646D01*
X111614D01*
X115193Y1202225D01*
G01X115624Y1220921D02*
Y1217207D01*
X121290Y1211541D01*
G01X118027Y1223324D02*
X115624Y1220921D01*
G01X103526Y1213892D02*
X101685Y1215733D01*
Y1219535D01*
X105601Y1223451D01*
G01X115624Y1220921D02*
X111884D01*
X109601Y1223204D01*
Y1223451D01*
G01X106708Y1210710D02*
X103526Y1213892D01*
G01X106708Y1210710D02*
X103027Y1207029D01*
G01X115200Y1226152D02*
X115198D01*
X112795Y1223749D01*
G01X105601Y1223451D02*
X109601D01*
G01X131385Y97667D02*
X128950D01*
G01X119582Y104749D02*
Y102249D01*
G01X127201Y106495D02*
X124606D01*
G01X127201Y102495D02*
X124606D01*
G01X117607Y130898D02*
Y133298D01*
G01X124780Y138838D02*
Y139762D01*
X126246Y141228D01*
G01X121840Y146012D02*
X124340D01*
G01Y142862D02*
X121840D01*
G01X125188Y153296D02*
X128089D01*
X129134Y152251D01*
Y150847D01*
G01X127911Y247292D02*
X131102D01*
G01X126453Y236121D02*
X123892D01*
G01X120926Y236009D02*
Y238589D01*
G01X126206Y242078D02*
X128687D01*
G01X126453Y232971D02*
X123918D01*
G01X120825Y253198D02*
X123811D01*
G01X135868Y250599D02*
Y248698D01*
X134044Y246874D01*
G01X131836Y982956D02*
X135836D01*
G01X119836D02*
X123836D01*
G01D02*
X127836D01*
G01D02*
X131836D01*
G01X119836Y995106D02*
Y997860D01*
G01X131836Y995106D02*
Y997860D01*
G01X127836Y995106D02*
Y997860D01*
G01X123836Y995106D02*
Y997860D01*
G01X123684Y1217668D02*
X121211Y1215195D01*
G01X132170Y1209183D02*
X131035Y1208048D01*
X128496D01*
X126937Y1209607D01*
G01X121290Y1211541D02*
X123214D01*
X126512Y1214839D01*
G01X129341Y1212011D02*
X126513Y1214839D01*
X126512D01*
G01X120854Y1220496D02*
Y1220497D01*
X118027Y1223324D01*
G01X138563Y236134D02*
Y238714D01*
G01X140575Y450750D02*
X136604D01*
G01X142961Y538775D02*
Y538640D01*
X140703Y536382D01*
G01D02*
X138971Y538114D01*
Y538816D01*
G01X135836Y982956D02*
X139836D01*
G01D02*
X143836D01*
G01D02*
X147836D01*
G01D02*
X151836D01*
G01X139836Y995106D02*
Y997860D01*
G01X147836Y995106D02*
Y997860D01*
G01X143836Y995106D02*
Y997860D01*
G01X135836Y995106D02*
Y997860D01*
G01X154263Y558555D02*
Y554555D01*
G01D02*
X155720D01*
X156399Y555234D01*
X157375D01*
G01X154295Y562567D02*
X156526D01*
X157090Y562003D01*
G01X150425Y637969D02*
X150982Y637412D01*
Y636350D01*
X152386Y634946D01*
G01D02*
X153575Y633757D01*
Y631421D01*
G01X155836Y984611D02*
X154181Y982956D01*
X151836D01*
G01X155836Y984611D02*
X157491Y982956D01*
X159836D01*
G01X155836Y991956D02*
Y984611D01*
G01X151836Y995106D02*
Y997860D01*
G01X159836Y995106D02*
Y997860D01*
G01X175472Y98551D02*
X172939D01*
G01Y101701D02*
X175472D01*
G01X179022Y101348D02*
Y103783D01*
G01X176562Y147540D02*
X173784D01*
G01X180532Y141247D02*
X177556D01*
G01X176562Y151540D02*
X173784D01*
G01X179128Y259535D02*
Y256535D01*
G01X182181Y288058D02*
Y290755D01*
G01X178181Y288058D02*
Y290755D01*
G01X183022Y101348D02*
Y103783D01*
G01X194189Y107921D02*
Y103621D01*
G01X192366Y146461D02*
X189364D01*
G01X185280Y152367D02*
X188266D01*
G01X187128Y259535D02*
Y256535D01*
G01X186181Y288058D02*
Y290755D01*
G01X211262Y64722D02*
Y60922D01*
G01X201033Y88801D02*
Y87013D01*
X202994Y85052D01*
Y81848D01*
G01X201033Y91951D02*
X203591D01*
G01X203616Y88801D02*
X201033D01*
G01X214389Y91974D02*
Y94374D01*
G01X202195Y117261D02*
X202616Y116840D01*
Y114488D01*
G01X213944Y104749D02*
Y102249D01*
G01X211969Y130898D02*
Y133298D01*
G01X211005Y136742D02*
X211920D01*
X213632Y135030D01*
X213665D01*
X214116Y134579D01*
G01X200323Y149768D02*
Y152562D01*
G01X209158Y158015D02*
Y160715D01*
X208567Y161306D01*
G01X207351Y225719D02*
Y221867D01*
X207354Y221864D01*
G01X214469Y252371D02*
X211691D01*
G01X199380Y424587D02*
X203279D01*
X203280Y424586D01*
G01X221944Y104749D02*
Y102249D01*
G01X229563Y106495D02*
X226968D01*
G01X217944Y104749D02*
Y102249D01*
G01X229563Y102495D02*
X226968D01*
G01X219969Y130898D02*
Y133298D01*
G01X227142Y138838D02*
Y139762D01*
X228608Y141228D01*
G01X224202Y146012D02*
X226702D01*
G01Y142862D02*
X224202D01*
G01X218091Y142648D02*
X221407D01*
X221621Y142862D01*
X224202D01*
G01X227550Y153296D02*
X230451D01*
X231496Y152251D01*
Y150847D01*
G01X230273Y247292D02*
X233464D01*
G01X228815Y236121D02*
X226254D01*
G01X223288Y236009D02*
Y238589D01*
G01X228568Y242078D02*
X231049D01*
G01X228815Y232971D02*
X226280D01*
G01X223187Y253198D02*
X226173D01*
G01X227025Y553700D02*
X225725Y555000D01*
X224500D01*
G01X221575Y549800D02*
X224200D01*
G01X227025Y557700D02*
X225140D01*
X224040Y558800D01*
G01X230619Y1474522D02*
Y1470946D01*
X229260Y1469587D01*
G01X218171Y1474460D02*
X221084Y1477373D01*
Y1479905D01*
G01X224176Y1492816D02*
X225721Y1494361D01*
X227462D01*
G01X229468Y1510442D02*
X226957D01*
G01X219640Y1522542D02*
Y1515942D01*
X219940Y1515642D01*
G01D02*
X216342D01*
G01X217519Y1537172D02*
Y1545228D01*
X221751Y1549460D01*
X229942D01*
G01X233942D02*
X229942D01*
G01X233747Y97667D02*
X231312D01*
G01X240925Y236134D02*
Y238714D01*
G01X238230Y250599D02*
Y248698D01*
X236406Y246874D01*
G01X243078Y633786D02*
Y636486D01*
G01X246583Y661113D02*
Y665140D01*
G01X242583Y669913D02*
X245000Y672330D01*
Y675832D01*
G01X241850D02*
Y678462D01*
G01X245000Y675832D02*
Y678462D01*
G01X238062Y846900D02*
X246000D01*
X247600Y848500D01*
G01X238062Y914200D02*
X269900D01*
G01X236498Y1475565D02*
Y1470624D01*
X232675Y1466801D01*
G01X249460Y1506058D02*
X249146Y1505744D01*
Y1503301D01*
X247748Y1501903D01*
X243268D01*
G01X240466Y1503857D02*
X242420Y1501903D01*
X243268D01*
G01X240842Y1530460D02*
Y1530658D01*
X239900Y1531600D01*
X237700D01*
G01X244942Y1549460D02*
X237942D01*
G01D02*
X233942D01*
G01X252275Y449873D02*
X254678D01*
G01X249125Y458859D02*
Y457597D01*
X250336Y456386D01*
G01X252275Y445873D02*
X254678D01*
G01X248984Y640872D02*
Y638125D01*
G01X248690Y675889D02*
Y678519D01*
G01X249641Y1514169D02*
Y1510142D01*
G01X249460Y1506058D02*
X249641Y1506239D01*
Y1510142D01*
G01X251760Y1517958D02*
Y1516060D01*
X249869Y1514169D01*
X249641D01*
G01X248042Y1530460D02*
Y1532900D01*
G01X275301Y98551D02*
X277834D01*
G01X275301Y101701D02*
X277834D01*
G01X278924Y147540D02*
X276146D01*
G01X278924Y151540D02*
X276146D01*
G01X270305Y580925D02*
X266406D01*
X266405Y580926D01*
G01X318462Y878900D02*
X275400D01*
X269700Y884600D01*
G01X319462Y949400D02*
X273000D01*
X270100Y946500D01*
G01X294959Y14408D02*
Y11097D01*
G01X285384Y101348D02*
Y103783D01*
G01X281384Y101348D02*
Y103783D01*
G01X294728Y146461D02*
X291726D01*
G01X282894Y141247D02*
X279918D01*
G01X287642Y152367D02*
X290628D01*
G01X281490Y259535D02*
Y256535D01*
G01X289490Y259535D02*
Y256535D01*
G01X284543Y288058D02*
Y290755D01*
G01X280543Y288058D02*
Y290755D01*
G01X288543Y288058D02*
Y290755D01*
G01X286940Y317873D02*
Y315039D01*
G01X309106Y35007D02*
Y37543D01*
G01X312256Y35007D02*
Y37543D01*
G01X315825Y29408D02*
X313534D01*
X312256Y30686D01*
Y35007D01*
G01X305356Y81848D02*
Y85052D01*
X303395Y87013D01*
Y88801D01*
G01Y91951D02*
X305953D01*
G01X303395Y88801D02*
X305978D01*
G01X296551Y107921D02*
Y103621D01*
G01X304557Y117261D02*
X304978Y116840D01*
Y114488D01*
G01X314854Y130898D02*
X312331D01*
G01X302685Y149768D02*
Y152562D01*
G01X311520Y158015D02*
Y160715D01*
X310929Y161306D01*
G01X309713Y225719D02*
Y221867D01*
X309716Y221864D01*
G01X312263Y311740D02*
X314855D01*
G01X328481Y11806D02*
X330905D01*
G01X328481Y15806D02*
X330905D01*
G01X328481Y19806D02*
X330905D01*
G01X328481Y23806D02*
X330905D01*
G01X328481Y31806D02*
X330905D01*
G01X328481Y27806D02*
X330905D01*
G01X313624Y64722D02*
Y60922D01*
G01X316751Y91974D02*
Y94374D01*
G01X324306Y104749D02*
Y102249D01*
G01X320306Y104749D02*
Y102249D01*
G01X316306Y104749D02*
Y102249D01*
G01X322331Y130898D02*
Y133298D01*
G01X326564Y146012D02*
X329064D01*
G01X316478Y134579D02*
X316027Y135030D01*
X315994D01*
X314282Y136742D01*
X313367D01*
G01X326564Y142862D02*
X323983D01*
X323769Y142648D01*
X320453D01*
G01X329064Y142862D02*
X326564D01*
G01X325650Y236009D02*
Y238589D01*
G01X325549Y253198D02*
X328535D01*
G01X316831Y252371D02*
X314053D01*
G01X316831Y248371D02*
X314053D01*
G01X323882Y306652D02*
Y303839D01*
G01X327032Y306652D02*
X327427Y307047D01*
Y312849D01*
G01X327032Y303962D02*
Y306652D01*
G01X320274Y336324D02*
X315904D01*
G01X320483Y350850D02*
Y353506D01*
G01X317333Y353470D02*
Y350850D01*
G01X342285Y565287D02*
X334189D01*
X328945Y560043D01*
G01X336109Y97667D02*
X333674D01*
G01X331925Y106495D02*
X329330D01*
G01X331925Y102495D02*
X329330D01*
G01X329504Y138838D02*
Y139762D01*
X330970Y141228D01*
G01X329912Y153296D02*
X332813D01*
X333858Y152251D01*
Y150847D01*
G01X331177Y236121D02*
X328616D01*
G01X332635Y247292D02*
X335826D01*
G01X343287Y236134D02*
Y238714D01*
G01X330930Y242078D02*
X333411D01*
G01X331177Y232971D02*
X328642D01*
G01X340592Y250599D02*
Y248698D01*
X338768Y246874D01*
G01X351136Y372334D02*
X348253D01*
X342486Y378101D01*
Y379573D01*
G01X337629Y1178900D02*
Y1186071D01*
G01Y1175750D02*
X332050D01*
X330800Y1174500D01*
G01X347295Y1223592D02*
X347293D01*
X344466Y1220765D01*
G01D02*
X343950Y1220249D01*
Y1216063D01*
X350402Y1209611D01*
Y1206593D01*
G01X346486Y379573D02*
Y377637D01*
X348737Y375386D01*
G01X350486Y379573D02*
Y377173D01*
G01X347591Y393933D02*
Y391533D01*
G01X347450Y447486D02*
Y450334D01*
G01Y458334D02*
X345050D01*
G01X345748Y1137129D02*
Y1135347D01*
X346366Y1134729D01*
G01X346385Y1153242D02*
Y1146686D01*
X347000Y1146071D01*
G01D02*
X349071D01*
X349700Y1146700D01*
Y1148000D01*
G01X366157Y1150087D02*
X362665D01*
X360982Y1148404D01*
Y1146842D01*
G01X352714Y1163968D02*
Y1160346D01*
X352536Y1160168D01*
G01X360982Y1163968D02*
Y1166002D01*
X363347Y1168367D01*
X366133D01*
G01X354414Y1178240D02*
X355755D01*
X357057Y1179542D01*
G01D02*
X358443Y1178156D01*
Y1177261D01*
G01X354400Y1195419D02*
X358400D01*
G01X354400D02*
X350400D01*
G01X358400D02*
Y1193812D01*
X357297Y1192709D01*
G01X354402Y1206593D02*
X358402D01*
G01D02*
X362402D01*
G01X350402D02*
X354402D01*
G01X350124Y1226421D02*
X347295Y1223592D01*
G01X362332Y1230265D02*
X361739Y1230858D01*
X354561D01*
X352953Y1229250D01*
G01D02*
X350124Y1226421D01*
G01X373264Y372604D02*
Y370010D01*
G01X377237Y373680D02*
Y371060D01*
G01X362486Y385123D02*
Y382723D01*
G01X368587Y406616D02*
Y409016D01*
G01X364551Y406532D02*
Y409032D01*
G01X368587Y401066D02*
Y403466D01*
G01X373599Y458309D02*
X376099D01*
G01X373599Y454309D02*
X376099D01*
G01X373599Y462309D02*
X376099D01*
G01X374714Y793344D02*
X373592D01*
X371436Y791188D01*
G01X365748Y1137129D02*
Y1134325D01*
G01X366157Y1146937D02*
X368657D01*
G01Y1150087D02*
X366157D01*
G01X366133Y1165217D02*
Y1162817D01*
G01Y1170767D02*
Y1168367D01*
G01X366400Y1195419D02*
X368917D01*
G01X362400D02*
X366400D01*
G01X369839Y1218940D02*
X364707Y1224072D01*
G01X366521Y1208993D02*
X367764Y1210236D01*
Y1216189D01*
X363962Y1219991D01*
X363132D01*
X361879Y1221244D01*
G01X366402Y1206593D02*
X366521Y1206712D01*
Y1208993D01*
G01X362402Y1206593D02*
X366402D01*
G01X392821Y25754D02*
X390860D01*
X389175Y24069D01*
X388487D01*
G01X380196Y98551D02*
X377663D01*
G01Y101701D02*
X380196D01*
G01X387746Y101348D02*
Y103783D01*
G01X383746Y101348D02*
Y103783D01*
G01X391852Y259535D02*
Y256535D01*
G01X383852Y259535D02*
Y256535D01*
G01X386905Y288058D02*
Y290755D01*
G01X382905Y288058D02*
Y290755D01*
G01X390905Y288058D02*
Y290755D01*
G01X391243Y466409D02*
X393837D01*
G01X391243Y470382D02*
X393662D01*
G01X391243Y487382D02*
X393823D01*
G01X394000Y1508100D02*
X392653D01*
X390470Y1510283D01*
Y1516448D01*
G01X384442Y1543700D02*
X383000D01*
X381900Y1544800D01*
G01X389700Y1536900D02*
X386200D01*
X384442Y1538658D01*
Y1539700D01*
G01Y1555700D02*
X382017D01*
G01X384442Y1547700D02*
X382017D01*
G01X384442Y1551700D02*
X382017D01*
G01X384442Y1559700D02*
X382017D01*
G01X407340Y114488D02*
Y116424D01*
X408493Y117577D01*
G01X398913Y107921D02*
Y103621D01*
G01X394237Y373481D02*
Y370899D01*
G01X408758Y474513D02*
X411754D01*
G01X399726Y471560D02*
X397315D01*
G01X399726Y479560D02*
X397315D01*
G01X399726Y475560D02*
X397315D01*
G01X406415Y874840D02*
X405387D01*
X404384Y875843D01*
X403478D01*
G01X404390Y1446807D02*
X401990D01*
G01X404540Y1442942D02*
Y1446657D01*
X404390Y1446807D01*
G01X404053Y1516556D02*
Y1513673D01*
G01X409461Y1566584D02*
Y1569560D01*
G01X405461Y1566584D02*
Y1569560D01*
G01X397461Y1566584D02*
Y1569560D01*
G01X401461Y1566584D02*
Y1569560D01*
G01X420050Y35983D02*
Y33425D01*
G01X416900Y35983D02*
Y33400D01*
G01X409947Y34022D02*
X410991D01*
X412952Y35983D01*
X416900D01*
G01X420073Y22627D02*
X422473D01*
G01X412075Y225719D02*
Y221867D01*
X412078Y221864D01*
G01X416318Y365224D02*
Y367903D01*
G01X424479Y365232D02*
Y367859D01*
G01X412318Y365224D02*
Y367903D01*
G01X420422Y365232D02*
Y367859D01*
G01X411847Y429262D02*
Y426740D01*
G01X415844Y468607D02*
X418754D01*
G01X425673Y459176D02*
Y461607D01*
G01X424876Y474560D02*
Y471334D01*
G01X411214Y889551D02*
Y892109D01*
G01X420279Y1523296D02*
Y1525978D01*
G01X410626Y1523296D02*
Y1525991D01*
G01X427191Y1537088D02*
Y1535082D01*
X426196Y1534087D01*
G01X413461Y1566584D02*
Y1569560D01*
G01X417461Y1566584D02*
Y1569584D01*
G01X444729Y146461D02*
X441727D01*
G01X432895Y141247D02*
X429919D01*
G01X428925Y147540D02*
X426147D01*
G01X428925Y151540D02*
X426147D01*
G01X437643Y152367D02*
X440629D01*
G01X433673Y459176D02*
Y461607D01*
G01X434799Y1550158D02*
X437675D01*
G01X452686Y149768D02*
Y152562D01*
G01X443748Y452601D02*
X446179D01*
G01X443748Y447101D02*
X446179D01*
G01X453544Y461961D02*
Y464809D01*
G01Y472809D02*
X451144D01*
G01X447279Y633881D02*
X444779D01*
G01X449745Y625485D02*
X445745D01*
G01X452594Y1043140D02*
X450063D01*
G01X452517Y1047047D02*
X449767D01*
G01X456025Y1217913D02*
Y1212134D01*
X455968Y1212077D01*
G01X455592Y1265971D02*
Y1268026D01*
X454120Y1269498D01*
G01X461101Y1265971D02*
X455592D01*
G01Y1260171D02*
Y1255597D01*
X455619Y1255570D01*
G01X474307Y104749D02*
Y102249D01*
G01X470307Y104749D02*
Y102249D01*
G01X466307Y104749D02*
Y102249D01*
G01X472332Y130898D02*
Y133298D01*
G01X464332Y130898D02*
Y133298D01*
G01X466479Y134579D02*
X466028Y135030D01*
X465995D01*
X464283Y136742D01*
X463368D01*
G01X476565Y142862D02*
X473984D01*
X473770Y142648D01*
X470454D01*
G01X461521Y158015D02*
Y160715D01*
X460930Y161306D01*
G01X466832Y252371D02*
X464054D01*
G01X466832Y248371D02*
X464054D01*
G01X475232Y347995D02*
X472810D01*
G01X475335Y360089D02*
X472913D01*
G01X475232Y352495D02*
X472608D01*
G01X475335Y369089D02*
X472913D01*
G01X475335Y373589D02*
X472913D01*
G01X475335Y387089D02*
X472913D01*
G01X475335Y391589D02*
X472913D01*
G01X475335Y382589D02*
X472913D01*
G01X475335Y378089D02*
X472913D01*
G01X461319Y1217913D02*
Y1212076D01*
G01X461101Y1260171D02*
Y1257735D01*
X460574Y1257208D01*
Y1255571D01*
G01X486110Y97667D02*
X483675D01*
G01X481926Y106495D02*
X479331D01*
G01X481926Y102495D02*
X479331D01*
G01X476565Y146012D02*
X479065D01*
G01X479505Y138838D02*
Y139762D01*
X480971Y141228D01*
G01X479065Y142862D02*
X476565D01*
G01X479913Y153296D02*
X482814D01*
X483859Y152251D01*
Y150847D01*
G01X482636Y247292D02*
X485827D01*
G01X481178Y236121D02*
X478617D01*
G01X475651Y236009D02*
Y238589D01*
G01X480931Y242078D02*
X483412D01*
G01X481178Y232971D02*
X478643D01*
G01X490593Y250599D02*
Y248698D01*
X488769Y246874D01*
G01X475550Y253198D02*
X478536D01*
G01X475335Y364589D02*
Y360089D01*
G01X485335Y391589D02*
X481724D01*
G01X485335Y387089D02*
X481724D01*
G01X488438Y428460D02*
Y425464D01*
G01X482532Y421374D02*
Y418464D01*
G01X488485Y412342D02*
X490985D01*
G01X485485Y437492D02*
Y439903D01*
G01X489485Y437492D02*
Y439903D01*
G01X479693Y472784D02*
X482193D01*
G01X479693Y468784D02*
X482193D01*
G01X479693Y476784D02*
X482193D01*
G01X487203Y621311D02*
X484772D01*
G01X487203Y629311D02*
X484772D01*
G01X481981Y648968D02*
Y646852D01*
X481165Y646036D01*
G01X493914Y680510D02*
X488763D01*
X488745Y680492D01*
G01D02*
X486652D01*
X485303Y681841D01*
G01X493288Y236134D02*
Y238714D01*
G01X493485Y437492D02*
Y439903D01*
G01X503729Y442344D02*
Y439919D01*
G01X503682Y458462D02*
Y455466D01*
G01X497776Y451376D02*
Y448466D01*
G01X500729Y467494D02*
Y469905D01*
G01X504729Y467494D02*
Y469905D01*
G01X499278Y639386D02*
Y641817D01*
G01X493778Y639386D02*
Y641817D01*
G01X491373Y654622D02*
X494632D01*
G01X491373Y657772D02*
X494465D01*
G01X502755Y655149D02*
Y657694D01*
G01X502832Y720491D02*
X504797Y722456D01*
Y742044D01*
X509096Y746343D01*
Y753072D01*
G01X506166Y844649D02*
X505922D01*
X503741Y846830D01*
G01X504033Y1020258D02*
X504166Y1020125D01*
Y1016266D01*
G01X520845Y436919D02*
Y434508D01*
G01X516845Y436919D02*
Y434508D01*
G01X512845Y436919D02*
Y434508D01*
G01X510022Y448763D02*
Y446352D01*
G01X508729Y467494D02*
Y469905D01*
G01X521310Y467634D02*
Y470045D01*
G01X513310Y467634D02*
Y470045D01*
G01X517353Y608311D02*
X519875D01*
G01X521074Y628242D02*
X523596D01*
G01X515632Y749443D02*
X515422Y749653D01*
Y753455D01*
G01X517412Y758832D02*
X520159D01*
G01X517412Y761982D02*
X520549D01*
G01X509096Y755715D02*
Y753072D01*
G01D02*
X515039D01*
X515422Y753455D01*
G01X514576Y789378D02*
X519690D01*
X519763Y789305D01*
G01D02*
Y791021D01*
X522316Y793574D01*
G01X509316Y844649D02*
X509741D01*
X511741Y846649D01*
G01X515444Y900295D02*
X509673D01*
G01X527664Y98551D02*
X530197D01*
G01X527664Y101701D02*
X530197D01*
G01X537747Y101348D02*
Y103783D01*
G01X533747Y101348D02*
Y103783D01*
G01X535257Y141247D02*
X532281D01*
G01X531287Y147540D02*
X528509D01*
G01X531287Y151540D02*
X528509D01*
G01X533853Y259535D02*
Y256535D01*
G01X532906Y288058D02*
Y290755D01*
G01X536906Y288058D02*
Y290755D01*
G01X538761Y381723D02*
X541706D01*
G01X527200Y387763D02*
Y389635D01*
X529730Y392165D01*
X529848D01*
X531992Y394309D01*
G01X535142D02*
Y397552D01*
G01X531992Y394309D02*
Y397552D01*
G01X532450Y767474D02*
X537944D01*
G01X532868Y972854D02*
Y969045D01*
X528674Y964851D01*
G01X536715Y1006246D02*
Y1004585D01*
X542793Y998507D01*
G01X555758Y91951D02*
X558316D01*
G01X555758Y88801D02*
X558341D01*
G01X557719Y81848D02*
Y85052D01*
X555758Y87013D01*
Y88801D01*
G01X548914Y107921D02*
Y103621D01*
G01X547091Y146461D02*
X544089D01*
G01X555048Y149768D02*
Y152562D01*
G01X540005Y152367D02*
X542991D01*
G01X541853Y259535D02*
Y256535D01*
G01X540906Y288058D02*
Y290755D01*
G01X548761Y359223D02*
X551536D01*
G01X548761Y354723D02*
X551536D01*
G01X548761Y345723D02*
X551536D01*
G01X548761Y377223D02*
X551536D01*
G01X548761Y372723D02*
X551536D01*
G01X548761Y368223D02*
X551536D01*
G01X548761Y363723D02*
X551536D01*
G01X548761Y381723D02*
X551536D01*
G01X584321Y445506D02*
X567582D01*
X552905Y430829D01*
G01X555756Y738558D02*
X558574D01*
X559625Y739609D01*
G01X546606Y760782D02*
X542275D01*
G01X549304Y846389D02*
X545981D01*
G01X552551Y841388D02*
X552039Y841900D01*
X549753D01*
X549241Y841388D01*
G01X552923Y982956D02*
X556923D01*
G01X548215Y1006560D02*
Y1006573D01*
X548852Y1007210D01*
Y1009260D01*
G01X552923Y995106D02*
Y997860D01*
G01X541766Y1015166D02*
Y1018368D01*
G01X551673Y1021177D02*
Y1023900D01*
G01X554696Y1018469D02*
Y1013972D01*
G01X565987Y64722D02*
X566287Y64422D01*
Y60922D01*
G01X569114Y91974D02*
Y94374D01*
G01X556920Y117261D02*
X557341Y116840D01*
Y114488D01*
G01X568669Y104749D02*
Y102249D01*
G01X567290Y130898D02*
X564694D01*
G01X568841Y134579D02*
X568390Y135030D01*
X568357D01*
X566645Y136742D01*
X565730D01*
G01X563883Y158015D02*
Y160715D01*
X563292Y161306D01*
G01X562076Y225719D02*
Y221867D01*
X562079Y221864D01*
G01X569194Y252371D02*
X566416D01*
G01X569194Y248371D02*
X566416D01*
G01X570578Y747079D02*
Y749800D01*
G01X567428Y747079D02*
Y750145D01*
G01X568464Y754899D02*
Y753913D01*
X570038Y752339D01*
G01X574504Y753459D02*
X573094D01*
X571974Y752339D01*
X570038D01*
G01X556923Y980523D02*
Y982956D01*
G01X560923D02*
Y980443D01*
G01X556923Y982956D02*
X560923D01*
G01D02*
X564923D01*
G01D02*
X568923D01*
G01D02*
X572923D01*
G01X564923Y995106D02*
Y997860D01*
G01X560923Y995106D02*
Y997860D01*
G01X568923Y995106D02*
Y997860D01*
G01X556923Y995106D02*
Y997860D01*
G01X566623Y1207882D02*
X563673Y1204932D01*
G01X566502Y1202103D02*
Y1202787D01*
X568768Y1205053D01*
X569452D01*
G01X572280Y1202225D02*
X572294D01*
X574099Y1200420D01*
X576645D01*
X578377Y1202152D01*
Y1211541D01*
G01X563795Y1210710D02*
X560114Y1207029D01*
Y1203125D01*
X564593Y1198646D01*
X567177D01*
X568532Y1200001D01*
G01D02*
X570056D01*
X572280Y1202225D01*
G01X560613Y1213892D02*
X559631Y1214874D01*
Y1220394D01*
X562688Y1223451D01*
G01X563795Y1210710D02*
X560613Y1213892D01*
G01X572711Y1220921D02*
X568971D01*
X566688Y1223204D01*
Y1223451D01*
G01X572287Y1226152D02*
X572285D01*
X569882Y1223749D01*
G01X562688Y1223451D02*
X566688D01*
G01X567958Y1532240D02*
X567040D01*
X565600Y1530800D01*
G01X564242Y1528260D02*
Y1529442D01*
X565600Y1530800D01*
G01X566800Y1541800D02*
X566600Y1542000D01*
Y1545200D01*
X568760Y1547360D01*
X571942D01*
G01X588472Y97667D02*
X586037D01*
G01X572669Y104749D02*
Y102249D01*
G01X576669Y104749D02*
Y102249D01*
G01X584288Y106495D02*
X581693D01*
G01X584288Y102495D02*
X581693D01*
G01X574694Y130898D02*
Y133298D01*
G01X578927Y146012D02*
X581427D01*
G01X581867Y138838D02*
Y139762D01*
X583333Y141228D01*
G01X581427Y142862D02*
X578927D01*
G01D02*
X576346D01*
X576132Y142648D01*
X572816D01*
G01X582275Y153296D02*
X585176D01*
X586221Y152251D01*
Y150847D01*
G01X584998Y247292D02*
X588189D01*
G01X583540Y236121D02*
X580979D01*
G01X578013Y236009D02*
Y238589D01*
G01X583293Y242078D02*
X585774D01*
G01X583540Y232971D02*
X581005D01*
G01X577912Y253198D02*
X580898D01*
G01X576923Y982956D02*
X580923D01*
G01X584923D02*
X588923D01*
G01X580923D02*
X584923D01*
G01X572923D02*
X576923D01*
G01X580923Y995106D02*
Y997860D01*
G01X576923Y995106D02*
Y997860D01*
G01X572923Y995106D02*
Y997860D01*
G01X584923Y995106D02*
Y997860D01*
G01X580771Y1217668D02*
X578298Y1215195D01*
G01X589257Y1209183D02*
X588122Y1208048D01*
X585583D01*
X584024Y1209607D01*
G01X586428Y1212011D02*
X583600Y1214839D01*
X583599D01*
G01X577941Y1220496D02*
Y1220497D01*
X575114Y1223324D01*
G01D02*
X572711Y1220921D01*
G01X578377Y1211541D02*
X580301D01*
X583599Y1214839D01*
G01X572711Y1220921D02*
Y1217207D01*
X578377Y1211541D01*
G01X582140Y1514042D02*
Y1516340D01*
X583800Y1518000D01*
G01X584541Y1505724D02*
X587689D01*
G01X575332Y1526224D02*
Y1523740D01*
G01X579758Y1520640D02*
X583740D01*
G01X587858Y1520740D02*
Y1517942D01*
G01X580700Y1544100D02*
Y1546300D01*
X582260Y1547860D01*
X583742D01*
G01X595650Y236134D02*
Y238714D01*
G01X592955Y250599D02*
Y248698D01*
X591131Y246874D01*
G01X597661Y450750D02*
X593690D01*
G01X600047Y538775D02*
Y538640D01*
X597789Y536382D01*
G01D02*
X596057Y538114D01*
Y538816D01*
G01X592923Y982956D02*
X596923D01*
G01D02*
X600923D01*
G01D02*
X604923D01*
G01X588923D02*
X592923D01*
G01X588923Y995106D02*
Y997860D01*
G01X596923Y995106D02*
Y997860D01*
G01X592923Y995106D02*
Y997860D01*
G01X600923Y995106D02*
Y997860D01*
G01X598060Y1493658D02*
Y1497558D01*
G01D02*
Y1501358D01*
X598160Y1501458D01*
G01X592978Y1514812D02*
X593935D01*
X598160Y1510587D01*
Y1501458D01*
G01X591858Y1526840D02*
Y1523542D01*
G01X600242Y1541660D02*
Y1544958D01*
X598800Y1546400D01*
G01X611349Y558555D02*
Y554555D01*
G01D02*
X612806D01*
X613485Y555234D01*
X614461D01*
G01X611381Y562567D02*
X613612D01*
X614176Y562003D01*
G01X607511Y637969D02*
Y635867D01*
X608432Y634946D01*
X609472D01*
G01D02*
X610661Y633757D01*
Y631421D01*
G01X612923Y984288D02*
Y991956D01*
G01Y984288D02*
X611591Y982956D01*
X608923D01*
G01X616923D02*
X614255D01*
X612923Y984288D01*
G01X604923Y982956D02*
X608923D01*
G01X604923Y995106D02*
Y997860D01*
G01X616923Y995106D02*
Y997860D01*
G01X608923Y995106D02*
Y997860D01*
G01X630026Y98551D02*
X632559D01*
G01X630026Y101701D02*
X632559D01*
G01X636109Y101348D02*
Y103783D01*
G01X633649Y147540D02*
X630871D01*
G01X637619Y141247D02*
X634643D01*
G01X633649Y151540D02*
X630871D01*
G01X636215Y259535D02*
Y256535D01*
G01X635268Y288058D02*
Y290755D01*
G01X651276Y107921D02*
Y103621D01*
G01X640109Y101348D02*
Y103783D01*
G01X649453Y146461D02*
X646451D01*
G01X642367Y152367D02*
X645353D01*
G01X644215Y259535D02*
Y256535D01*
G01X639268Y288058D02*
Y290755D01*
G01X643268Y288058D02*
Y290755D01*
G01X650958Y682006D02*
Y677843D01*
G01X668349Y64722D02*
X668649Y64422D01*
Y60922D01*
G01X660081Y81848D02*
Y85052D01*
X658120Y87013D01*
Y88801D01*
G01Y91951D02*
X660678D01*
G01X658120Y88801D02*
X660703D01*
G01X659282Y117261D02*
X659703Y116840D01*
Y114488D01*
G01X669056Y130898D02*
Y133298D01*
G01X671203Y134579D02*
X670752Y135030D01*
X670719D01*
X669007Y136742D01*
X668092D01*
G01X657410Y149768D02*
Y152562D01*
G01X666245Y158015D02*
Y160715D01*
X665654Y161306D01*
G01X664438Y225719D02*
Y221867D01*
X664441Y221864D01*
G01X671556Y252371D02*
X668778D01*
G01X671556Y248371D02*
X668886D01*
G01X656466Y424587D02*
X660365D01*
X660366Y424586D01*
G01X655752Y666275D02*
Y668885D01*
G01X661117Y660402D02*
Y662322D01*
X661776Y662981D01*
G01X657967D02*
Y660402D01*
G01X662092Y666275D02*
X658902D01*
G01D02*
X658438Y666739D01*
Y672360D01*
G01X661018Y710129D02*
Y707592D01*
G01X671476Y91974D02*
Y94374D01*
G01X675031Y104749D02*
Y102249D01*
G01X671031Y104749D02*
Y102249D01*
G01X679031Y104749D02*
Y102249D01*
G01X686650Y106495D02*
X684055D01*
G01X686650Y102495D02*
X684055D01*
G01X677056Y130898D02*
Y133298D01*
G01X681289Y146012D02*
X683789D01*
G01X684229Y138838D02*
Y139762D01*
X685695Y141228D01*
G01X683789Y142862D02*
X681289D01*
G01D02*
X678708D01*
X678494Y142648D01*
X675178D01*
G01X684637Y153296D02*
X687538D01*
X688583Y152251D01*
Y150847D01*
G01X680375Y236009D02*
Y238589D01*
G01X685902Y236121D02*
X683341D01*
G01X685655Y242078D02*
X688136D01*
G01X685902Y232971D02*
X683367D01*
G01X680274Y253198D02*
X683260D01*
G01X684111Y553700D02*
X682811Y555000D01*
X681586D01*
G01X678661Y549800D02*
X681286D01*
G01X681126Y558800D02*
X682226Y557700D01*
X684111D01*
G01X690834Y97667D02*
X688399D01*
G01X698012Y236134D02*
Y238714D01*
G01X687360Y247292D02*
X690551D01*
G01X695317Y250599D02*
Y248698D01*
X693493Y246874D01*
G01X700164Y633786D02*
Y636842D01*
G01X699669Y669913D02*
X702086Y672330D01*
Y675832D01*
G01X698936D02*
Y678462D01*
G01X702086Y675832D02*
Y678462D01*
G01X709361Y449873D02*
X711764D01*
G01X709361Y445873D02*
X711764D01*
G01X706070Y640872D02*
Y638125D01*
G01X703669Y661113D02*
Y665140D01*
G01X705776Y675889D02*
Y678519D01*
G01X716350Y696718D02*
Y699477D01*
G01X713200Y696718D02*
Y699676D01*
G01X720260Y699697D02*
X717494Y702463D01*
X716623D01*
G01X721141Y730734D02*
X712849D01*
X710165Y728050D01*
G01X714937Y741912D02*
X720999D01*
X721218Y742131D01*
G01X717121Y779958D02*
X717434Y780271D01*
Y782500D01*
G01X715994Y776663D02*
X717121Y777790D01*
Y779958D01*
G01X712692Y780141D02*
X710275Y782558D01*
Y783453D01*
G01X713425D02*
Y786029D01*
G01X710275Y783453D02*
Y786131D01*
G01X732388Y98551D02*
X734921D01*
G01X732388Y101701D02*
X734921D01*
G01X736011Y147540D02*
X733233D01*
G01X736011Y151540D02*
X733233D01*
G01X727391Y580925D02*
X723492D01*
X723491Y580926D01*
G01X725667Y732161D02*
X724240Y730734D01*
X721141D01*
G01X723811Y742131D02*
X721218D01*
G01X721163Y738981D02*
X723811D01*
G01X720271Y779958D02*
Y782481D01*
G01X816648Y1380758D02*
X819879Y1383989D01*
Y1401533D01*
X810685Y1410727D01*
X800176D01*
X796546Y1407097D01*
X793068D01*
X774504Y1425661D01*
Y1438769D01*
X771986Y1441287D01*
X765830D01*
X761185Y1445932D01*
Y1452088D01*
X732825Y1480448D01*
Y1604100D01*
G01Y1606600D02*
Y1604100D01*
G01X742471Y101348D02*
Y103783D01*
G01X738471Y101348D02*
Y103783D01*
G01X751815Y146461D02*
X748813D01*
G01X739981Y141247D02*
X737005D01*
G01X744729Y152367D02*
X747715D01*
G01X738577Y259535D02*
Y256535D01*
G01X746577Y259535D02*
Y256535D01*
G01X741630Y288058D02*
Y290755D01*
G01X737630Y288058D02*
Y290755D01*
G01X745630Y288058D02*
Y290755D01*
G01X744026Y317873D02*
X742542Y316389D01*
X741051D01*
G01X740357Y743684D02*
X741136D01*
X744069Y746617D01*
G01X736702Y1451659D02*
Y1448259D01*
X739228Y1445733D01*
X742655D01*
G01X747140Y1583735D02*
Y1581335D01*
G01X735392Y1602340D02*
X737892D01*
G01X747590Y1630634D02*
Y1627871D01*
G01X743331Y1630644D02*
Y1627871D01*
G01X744924Y1614943D02*
Y1617709D01*
G01X739305Y1622015D02*
X741705D01*
G01X735326Y1634485D02*
X738325D01*
G01X762443Y81848D02*
Y85052D01*
X760482Y87013D01*
Y88801D01*
G01Y91951D02*
X763040D01*
G01X760482Y88801D02*
X763065D01*
G01X762065Y114488D02*
Y117040D01*
G01X753638Y107921D02*
Y103621D01*
G01X759772Y149768D02*
Y152562D01*
G01X759169Y1583760D02*
X763098D01*
X763145Y1583713D01*
G01D02*
X766433D01*
G01X755187Y1583749D02*
Y1580821D01*
G01X767282Y1595014D02*
Y1599136D01*
X767310Y1599164D01*
G01X759802Y1604660D02*
Y1613417D01*
X759452Y1613767D01*
G01Y1616917D02*
X756358D01*
G01X752150Y1630659D02*
Y1627871D01*
G01X766516Y1622460D02*
X770303D01*
X773368Y1619395D01*
X774844D01*
G01X763452Y1616917D02*
Y1618586D01*
X762671Y1619367D01*
G01X756358Y1613767D02*
X759452D01*
G01X762776Y1633090D02*
Y1629415D01*
G01X770711Y64722D02*
X771011Y64422D01*
Y60922D01*
G01X773838Y91974D02*
Y94374D01*
G01X781393Y104749D02*
Y102249D01*
G01X777393Y104749D02*
Y102249D01*
G01X773393Y104749D02*
Y102249D01*
G01X779418Y130898D02*
Y133298D01*
G01X771960Y130898D02*
X769418D01*
G01X773565Y134579D02*
X773114Y135030D01*
X773081D01*
X771369Y136742D01*
X770454D01*
G01X783651Y142862D02*
X781070D01*
X780856Y142648D01*
X777540D01*
G01X768607Y158015D02*
Y160715D01*
X768016Y161306D01*
G01X782737Y236009D02*
Y238589D01*
G01X782636Y253198D02*
X785622D01*
G01X773918Y252371D02*
X771140D01*
G01X773918Y248371D02*
X771140D01*
G01X780968Y306652D02*
Y303839D01*
G01X769349Y311740D02*
X771941D01*
G01X777360Y336324D02*
X772990D01*
G01X777569Y350850D02*
Y353506D01*
G01X774419Y353470D02*
Y350850D01*
G01X777033Y1592572D02*
Y1595215D01*
G01X781059Y1605740D02*
Y1603321D01*
X781545Y1602835D01*
G01X775941Y1598260D02*
Y1599729D01*
X774658Y1601012D01*
G01X774844Y1622545D02*
X778045D01*
G01X782289Y1623876D02*
Y1620109D01*
G01X773822Y1630150D02*
Y1627418D01*
G01X774844Y1619395D02*
X778045D01*
G01X778358Y1630126D02*
Y1627418D01*
G01X793196Y97667D02*
X790761D01*
G01X789012Y106495D02*
X786417D01*
G01X789012Y102495D02*
X786417D01*
G01X786591Y138838D02*
Y139762D01*
X788057Y141228D01*
G01X783651Y146012D02*
X786151D01*
G01Y142862D02*
X783651D01*
G01X786999Y153296D02*
X789900D01*
X790945Y152251D01*
Y150847D01*
G01X789722Y247292D02*
X792913D01*
G01X788264Y236121D02*
X785703D01*
G01X788017Y242078D02*
X790498D01*
G01X788264Y232971D02*
X785729D01*
G01X797679Y250599D02*
Y248698D01*
X795855Y246874D01*
G01X784118Y306652D02*
X784513Y307047D01*
Y312849D01*
G01X784118Y303962D02*
Y306652D01*
G01X815052Y346368D02*
Y344938D01*
X813827Y343713D01*
X801164D01*
X799937Y344940D01*
Y347340D01*
G01X803902Y346368D02*
Y348714D01*
X802248Y350368D01*
X797141D01*
G01D02*
X790294Y357215D01*
Y360341D01*
X792034Y362081D01*
X801175D01*
X808515Y354741D01*
X811899D01*
G01X799371Y565287D02*
X791275D01*
X786031Y560043D01*
G01X799631Y1025440D02*
Y1018310D01*
X810858Y1007083D01*
X828568D01*
X842309Y993342D01*
Y967107D01*
X845420Y963996D01*
Y937848D01*
X856628Y926640D01*
Y918042D01*
G01X794716Y1178900D02*
Y1186071D01*
G01Y1175750D02*
X789137D01*
X787887Y1174500D01*
G01X796972Y1394603D02*
X798772D01*
X800627Y1392748D01*
G01X799901Y1472676D02*
X799314Y1473263D01*
Y1475693D01*
G01X787447Y1596461D02*
Y1593586D01*
G01X791610Y1596438D02*
Y1593708D01*
G01X800374Y236134D02*
Y238714D01*
G01X803902Y313368D02*
Y309368D01*
G01Y305368D02*
Y303725D01*
X805952Y301675D01*
G01X803902Y309368D02*
Y305368D01*
G01Y325368D02*
Y321368D01*
G01Y317368D02*
Y313368D01*
G01Y321368D02*
Y317368D01*
G01X801097Y325858D02*
X801587Y325368D01*
X803902D01*
G01Y337368D02*
X800155D01*
G01X803902Y333368D02*
X800029D01*
G01X803902Y329368D02*
Y333368D01*
G01X804536Y441486D02*
Y444334D01*
G01Y452334D02*
X802136D01*
G01X833112Y826638D02*
X814111D01*
X811625Y829124D01*
G01D02*
X808749Y832000D01*
Y836919D01*
G01X813009Y819734D02*
X808749Y823994D01*
Y826248D01*
X811625Y829124D01*
G01X808749Y840919D02*
Y848367D01*
X813182Y852800D01*
G01X814731Y889365D02*
X814800Y889296D01*
Y885526D01*
G01X815399Y893419D02*
Y894627D01*
X817152Y896380D01*
G01X819899Y900919D02*
Y901817D01*
X813554Y908162D01*
X812811D01*
G01X802835Y1137129D02*
Y1135347D01*
X803453Y1134729D01*
G01X804087Y1146071D02*
X806158D01*
X806787Y1146700D01*
Y1148000D01*
G01X803472Y1153242D02*
Y1146686D01*
X804087Y1146071D01*
G01X809801Y1163968D02*
Y1160346D01*
X809623Y1160168D01*
G01X811501Y1178240D02*
X814160D01*
G01D02*
X816778D01*
X816826Y1178288D01*
G01X807487Y1195419D02*
Y1193019D01*
G01X815487Y1195419D02*
Y1193019D01*
G01X811487Y1195419D02*
Y1193019D01*
G01X815489Y1206593D02*
X819489D01*
G01X811489D02*
X815489D01*
G01X807489D02*
X811489D01*
G01X804382Y1223592D02*
X804380D01*
X801553Y1220765D01*
G01X807489Y1206593D02*
Y1210617D01*
X801037Y1217069D01*
Y1220249D01*
X801553Y1220765D01*
G01X810040Y1229250D02*
X807211Y1226421D01*
G01D02*
X804382Y1223592D01*
G01X819419Y1230265D02*
X818826Y1230858D01*
X811648D01*
X810040Y1229250D01*
G01X814148Y1377608D02*
X816648D01*
G01X814148Y1380758D02*
Y1383590D01*
X813798Y1383940D01*
Y1387865D01*
G01X816648Y1380758D02*
X814148D01*
G01X810148Y1377608D02*
Y1374884D01*
G01X806318Y1397511D02*
Y1401661D01*
G01X832961Y308900D02*
X829467D01*
X825792Y305225D01*
G01X830685Y456309D02*
X833185D01*
G01X830685Y452309D02*
X833185D01*
G01X830685Y448309D02*
X833185D01*
G01X832284Y713439D02*
X830284D01*
X829784Y713939D01*
G01X832284Y716589D02*
X829784D01*
G01X827284Y706489D02*
X828284Y705489D01*
X829784D01*
G01X839290Y706469D02*
X838310Y705489D01*
X829784D01*
G01X834484Y744301D02*
X830484D01*
G01D02*
Y746701D01*
G01X826484Y744301D02*
Y747127D01*
G01X826925Y766500D02*
Y769000D01*
G01X830075Y766500D02*
Y769000D01*
G01X826925Y784500D02*
Y787000D01*
G01X830075Y784500D02*
Y787000D01*
G01X826925Y802500D02*
Y805000D01*
G01X830075Y802500D02*
Y805000D01*
G01X822309Y830038D02*
Y836144D01*
X822831Y836666D01*
G01X826925Y820500D02*
Y823000D01*
G01X830075Y820500D02*
Y823000D01*
G01X822831Y836666D02*
X825721D01*
G01X832726Y840479D02*
X831250D01*
X829791Y839020D01*
G01X822831Y839816D02*
Y844357D01*
X821764Y845424D01*
G01X822831Y839816D02*
X825721D01*
G01X823234Y867680D02*
X820027D01*
G01X831922Y878504D02*
X832622Y879204D01*
Y880612D01*
X833870Y881860D01*
G01X828880Y867289D02*
X827446D01*
X826209Y866052D01*
G01X820027Y870830D02*
X819918Y870939D01*
Y876864D01*
G01X823234Y870830D02*
X820027D01*
G01X825774Y895553D02*
X826385Y896164D01*
X828643D01*
G01Y893014D02*
X826070D01*
G01X819629Y895705D02*
X817827D01*
X817152Y896380D01*
G01X828524Y890386D02*
X828643Y890505D01*
Y893014D01*
G01X818347Y939610D02*
X819347Y938610D01*
Y934626D01*
X820402Y933571D01*
G01X823552D02*
Y930700D01*
G01X830829Y935779D02*
X828621Y933571D01*
X823552D01*
G01X828423Y959119D02*
Y956519D01*
X830829Y954113D01*
Y952905D01*
G01X825670Y964671D02*
Y959744D01*
X826295Y959119D01*
X828423D01*
G01Y962269D02*
Y964731D01*
G01X825335Y1137129D02*
X822835D01*
G01X823244Y1146937D02*
X825744D01*
G01X823244Y1150087D02*
X825744D01*
G01X823244D02*
X819588D01*
X818069Y1148568D01*
Y1146842D01*
G01X823220Y1165217D02*
Y1162817D01*
G01X818069Y1163968D02*
Y1167546D01*
X818890Y1168367D01*
X823220D01*
G01D02*
Y1170767D01*
G01X823487Y1195419D02*
Y1193019D01*
G01X819487Y1195419D02*
Y1193019D01*
G01X826612Y1219254D02*
X821794Y1224072D01*
G01X819489Y1206593D02*
X823489D01*
G01D02*
X823608Y1206712D01*
Y1208993D01*
G01D02*
X824851Y1210236D01*
Y1216189D01*
X821049Y1219991D01*
X820219D01*
X818966Y1221244D01*
G01X828985Y1462461D02*
X830695D01*
X832084Y1461072D01*
G01X834750Y98551D02*
X837283D01*
G01X834750Y101701D02*
X837283D01*
G01X844833Y101348D02*
Y103783D01*
G01X840833Y101348D02*
Y103783D01*
G01X840939Y259535D02*
Y256535D01*
G01X843992Y288058D02*
Y290755D01*
G01X839992Y288058D02*
Y290755D01*
G01X847992Y288058D02*
Y290755D01*
G01X848284Y713439D02*
X846284D01*
X845784Y713939D01*
G01X843284Y706489D02*
X844284Y705489D01*
X845784D01*
G01X852284Y706489D02*
X851284Y705489D01*
X845784D01*
G01X848284Y716589D02*
X845784D01*
G01X850484Y744301D02*
X846484D01*
G01D02*
Y746701D01*
G01X842484Y744301D02*
X838484D01*
G01D02*
Y746701D01*
G01X838267Y827459D02*
Y829034D01*
X840136Y830903D01*
G01X836241Y839953D02*
X835715Y840479D01*
X832726D01*
G01X835626Y843629D02*
X832726D01*
G01X840689Y847490D02*
X838189D01*
G01X840689Y843790D02*
Y847490D01*
G01X842734Y851459D02*
X840234D01*
G01X840162Y867413D02*
Y863413D01*
G01X837183Y855459D02*
Y855367D01*
X837184Y855366D01*
X840260D01*
X840289Y855395D01*
G01D02*
Y851514D01*
X840234Y851459D01*
G01X839883Y883459D02*
Y879459D01*
G01X836311Y877163D02*
Y878458D01*
X837383Y879530D01*
G01X840162Y867413D02*
X836999D01*
G01X846000Y898425D02*
Y895783D01*
X845654Y895437D01*
G01X842000Y898425D02*
Y896270D01*
X842827Y895443D01*
G01X849600Y915266D02*
Y913636D01*
X848628Y912664D01*
G01X834829Y926602D02*
X838829D01*
G01D02*
X841329D01*
G01X839097Y935779D02*
Y939630D01*
X839122Y939655D01*
G01X862844Y91951D02*
X865402D01*
G01X864805Y81848D02*
Y85052D01*
X862844Y87013D01*
Y88801D01*
G01D02*
X865427D01*
G01X864006Y117261D02*
X864427Y116840D01*
Y114488D01*
G01X856000Y107921D02*
Y103621D01*
G01X848939Y259535D02*
Y256535D01*
G01X865320Y340454D02*
Y342768D01*
X864920Y343168D01*
G01X862170Y340454D02*
X859552Y337836D01*
X855993D01*
G01X861770Y343006D02*
Y340854D01*
X862170Y340454D01*
G01X854086Y376925D02*
Y374500D01*
G01X858586Y376925D02*
Y374500D01*
G01X863086Y376925D02*
Y374500D01*
G01X854086Y387425D02*
Y385000D01*
G01X863879Y483303D02*
X861468D01*
G01X863879Y487303D02*
X861468D01*
G01X863879Y491303D02*
X861468D01*
G01X859838Y685230D02*
X855646D01*
G01X849680Y692189D02*
Y694789D01*
G01X860686Y701170D02*
X858186D01*
G01X860686Y713170D02*
X858186D01*
G01X854484Y744301D02*
Y746701D01*
G01X864575Y770500D02*
Y768000D01*
G01X861425Y770500D02*
Y768000D01*
G01X864575Y788500D02*
Y786000D01*
G01X861425Y788500D02*
Y786000D01*
G01X864575Y804000D02*
Y806500D01*
G01X861425Y804000D02*
Y806500D01*
G01X864575Y822000D02*
Y824500D01*
G01X861425Y822000D02*
Y824500D01*
G01X856628Y912664D02*
Y915242D01*
G01X864628Y912664D02*
X864253Y913039D01*
Y915242D01*
G01X860628Y912664D02*
Y916230D01*
X862440Y918042D01*
X864253D01*
G01X852628Y912664D02*
Y916258D01*
X854412Y918042D01*
X856628D01*
G01X852117Y992334D02*
X852774Y992991D01*
Y1001027D01*
G01X860514Y1000691D02*
Y997955D01*
X866135Y992334D01*
G01X859900Y1008686D02*
Y1005846D01*
X857095Y1003041D01*
Y994481D01*
X859242Y992334D01*
G01X852488Y1014078D02*
X856088Y1010478D01*
Y1005737D01*
X852774Y1002423D01*
Y1001027D01*
G01X864007Y1014078D02*
X865868Y1012217D01*
Y1008070D01*
X860514Y1002716D01*
Y1000691D01*
G01X859900Y1008686D02*
X859242Y1009344D01*
Y1012720D01*
X857884Y1014078D01*
G01X873073Y64722D02*
X873373Y64422D01*
Y60922D01*
G01X876200Y91974D02*
Y94374D01*
G01X874531Y200500D02*
Y202078D01*
X871745Y204864D01*
G01X869165D02*
X871745D01*
G01X872509Y337342D02*
Y339516D01*
X873885Y340892D01*
G01X879997Y480350D02*
X882907D01*
G01X872911Y486256D02*
X875907D01*
G01X869493Y554703D02*
X867093D01*
G01X869338Y549771D02*
X866938D01*
G01X869493Y570703D02*
X867093D01*
G01X869493Y558703D02*
X867093D01*
G01X869493Y562703D02*
X867093D01*
G01X869493Y566703D02*
X867093D01*
G01X869493Y582828D02*
X867093D01*
G01X869493Y578703D02*
X867093D01*
G01X869493Y586828D02*
X867093D01*
G01X869493Y574703D02*
X867093D01*
G01X872069Y698388D02*
Y700894D01*
G01X878686Y686970D02*
X876286D01*
G01Y690970D02*
X878686D01*
G01X869484Y692710D02*
Y696166D01*
X868919Y696731D01*
Y698388D01*
G01D02*
Y700894D01*
G01X876286Y694970D02*
X878686D01*
G01X881157Y749148D02*
X882319Y750310D01*
X884045D01*
G01D02*
Y754297D01*
G01X873153Y794227D02*
Y798653D01*
X873250Y798750D01*
G01X875916Y803315D02*
X874925Y802324D01*
Y800746D01*
G01X875916Y816615D02*
X872700D01*
G01X872628Y912664D02*
Y915242D01*
G01X880628Y912664D02*
Y915242D01*
G01X868628Y912664D02*
Y916698D01*
X869972Y918042D01*
X872628D01*
G01X876628Y912664D02*
Y915242D01*
G01X879740Y941126D02*
X876481D01*
G01X886428Y940895D02*
X879971D01*
X879740Y941126D01*
G01X875954Y1014078D02*
X874002Y1012126D01*
Y1009399D01*
G01D02*
X871889Y1007286D01*
Y1004130D01*
X871389Y1003630D01*
G01X870401Y1014078D02*
X868934Y1012611D01*
Y1009274D01*
G01D02*
Y1006716D01*
X866448Y1004230D01*
Y1003630D01*
G01X876279D02*
Y1005496D01*
X879086Y1008303D01*
Y1009110D01*
G01D02*
Y1011710D01*
X881454Y1014078D01*
G01X886011Y147540D02*
X883233D01*
G01X889981Y141247D02*
X887005D01*
G01X894729Y152367D02*
X897715D01*
G01X886011Y151540D02*
Y154100D01*
G01X883552Y309368D02*
X885989D01*
G01X883552Y305368D02*
X885989D01*
G01X883552Y317368D02*
X885989D01*
G01X883552Y325368D02*
X885953D01*
G01X883552Y313368D02*
X885989D01*
G01X883552Y321368D02*
X885953D01*
G01X883552Y329368D02*
X885953D01*
G01X883552Y333368D02*
X885953D01*
G01X883552Y337342D02*
Y333368D01*
G01X888736Y388855D02*
X889880D01*
X891251Y387484D01*
G01X886131Y392113D02*
X888274Y389970D01*
X888736Y388855D01*
G01X889029Y486303D02*
X891454D01*
G01X896431Y536493D02*
Y534093D01*
G01X892931Y536493D02*
Y534093D01*
G01X895933Y615743D02*
Y618143D01*
G01X891933Y615743D02*
Y618143D01*
G01X906886Y699770D02*
X901462D01*
X899573Y697881D01*
G01X893324Y715230D02*
X890176D01*
X889436Y715970D01*
G01X886836D02*
Y718570D01*
G01Y727178D02*
Y729778D01*
G01X883686D02*
Y727178D01*
G01X887916Y803315D02*
Y800815D01*
G01X884628Y912664D02*
Y915242D01*
G01X903759Y948607D02*
X903527Y948375D01*
X896074D01*
G01X881278Y1003630D02*
Y1005332D01*
X884110Y1008164D01*
Y1009264D01*
G01D02*
X885210Y1010364D01*
Y1014078D01*
G01X886220Y1003630D02*
Y1005302D01*
X889202Y1008284D01*
Y1009184D01*
G01D02*
Y1013965D01*
X889089Y1014078D01*
G01X895989Y1003630D02*
Y1005250D01*
X899313Y1008574D01*
Y1009197D01*
G01X891068Y1003630D02*
Y1005193D01*
X894225Y1008350D01*
Y1009250D01*
G01D02*
Y1013609D01*
X893613Y1014221D01*
G01X887306Y1102760D02*
X884906D01*
G01X887390Y1098724D02*
X884890D01*
G01X892856Y1102760D02*
X890456D01*
G01X888650Y1199622D02*
Y1202266D01*
G01X893190Y1208069D02*
X895426Y1205833D01*
X897427D01*
G01X901392Y1204673D02*
X898587D01*
X897427Y1205833D01*
G01X901815Y146461D02*
X898813D01*
G01X909772Y149768D02*
Y152562D01*
G01X912085Y323302D02*
X909417D01*
G01X912085Y329602D02*
Y332335D01*
G01X907173Y445603D02*
Y443081D01*
G01X903431Y536493D02*
Y534093D01*
G01X899931Y536493D02*
Y534093D01*
G01X910036Y695770D02*
X912462D01*
G01X910036Y691770D02*
Y695770D01*
G01Y699770D02*
Y702285D01*
G01X906886D02*
Y699770D01*
G01X910036Y687770D02*
X912462D01*
G01X910036Y702285D02*
Y703318D01*
X907324Y706030D01*
G01X910836Y718970D02*
Y721570D01*
G01X903916Y810809D02*
Y813465D01*
G01X909416D02*
X909785Y813096D01*
Y810778D01*
G01X912628Y925701D02*
Y928101D01*
G01X906909Y948607D02*
Y951494D01*
G01X906128Y956015D02*
X905236D01*
X903759Y954538D01*
Y951358D01*
G01D02*
Y948607D01*
G01X899313Y1009197D02*
Y1010397D01*
X898046Y1011664D01*
Y1014165D01*
G01X911352Y1012137D02*
X911424Y1012065D01*
Y1008181D01*
X908534Y1005291D01*
X907953D01*
G01X904484Y1011004D02*
Y1008829D01*
X900721Y1005066D01*
Y1003630D01*
G01X902225Y1015653D02*
Y1013263D01*
X904484Y1011004D01*
G01X906255Y1015706D02*
Y1014066D01*
X908184Y1012137D01*
X911352D01*
G01X899989Y1081764D02*
X902389D01*
G01X908799Y1096659D02*
X911199D01*
G01X923393Y104749D02*
Y102249D01*
G01X927393Y104749D02*
Y102249D01*
G01X921418Y130898D02*
Y133298D01*
G01X929418Y130898D02*
Y133298D01*
G01X923565Y134579D02*
X923114Y135030D01*
X923081D01*
X921369Y136742D01*
X920454D01*
G01X933651Y142862D02*
X931070D01*
X930856Y142648D01*
X927540D01*
G01X918607Y158015D02*
Y160715D01*
X918016Y161306D01*
G01X920142Y310985D02*
Y308501D01*
G01X923902Y323302D02*
X926801D01*
G01X923902Y329602D02*
Y332411D01*
G01X928999Y475517D02*
Y477948D01*
G01X920999Y475517D02*
Y477948D01*
G01X929227Y561578D02*
X931627D01*
G01X929227Y565578D02*
X931627D01*
G01X929227Y557641D02*
X931627D01*
G01X929227Y569578D02*
X931627D01*
G01X929227Y577578D02*
X931627D01*
G01X929227Y573578D02*
X931627D01*
G01X925418Y677795D02*
X928043D01*
G01X924932Y696883D02*
Y701051D01*
G01X921061Y712920D02*
Y715386D01*
G01X921790Y813465D02*
Y810965D01*
G01X919664Y803315D02*
X915716D01*
G01X923790D02*
Y802247D01*
X922352Y800809D01*
G01X920628Y925701D02*
Y928101D01*
G01X928628Y925701D02*
Y928101D01*
G01X916628Y925701D02*
Y928101D01*
G01X924628Y925701D02*
Y928101D01*
G01X918503Y1009401D02*
X918318D01*
X913751Y1004834D01*
Y1004630D01*
G01X916465Y1014078D02*
X918503Y1012040D01*
Y1009401D01*
G01X927984Y1014078D02*
X929069Y1012993D01*
Y1009103D01*
G01D02*
X925969Y1006003D01*
Y1003630D01*
G01X921861Y1014078D02*
X923576Y1012363D01*
Y1009292D01*
G01D02*
X920476Y1006192D01*
Y1003630D01*
G01X914349Y1080659D02*
X916749D01*
G01X914349Y1084659D02*
X916749D01*
G01X914349Y1076659D02*
X916992D01*
G01X943196Y97667D02*
X940761D01*
G01X931393Y104749D02*
Y102249D01*
G01X939012Y106495D02*
X936417D01*
G01X939012Y102495D02*
X936417D01*
G01X933651Y146012D02*
X936151D01*
G01X936591Y138838D02*
Y139762D01*
X938057Y141228D01*
G01X936151Y142862D02*
X933651D01*
G01X936999Y153296D02*
X939900D01*
X940945Y152251D01*
Y150847D01*
G01X938125Y233669D02*
Y230891D01*
G01X938930Y221292D02*
X936369D01*
G01X938930Y218142D02*
X936395D01*
G01X940158Y242721D02*
Y245707D01*
G01X942757Y257764D02*
X944658D01*
X946482Y255940D01*
G01X930727Y305255D02*
Y302571D01*
G01X944514Y316739D02*
Y318667D01*
X945527Y319680D01*
X947733D01*
G01X935137Y330517D02*
X932388D01*
G01X935137Y336817D02*
X932622D01*
G01X941752Y351281D02*
X943783D01*
X944694Y352192D01*
G01X939074Y468942D02*
X941505D01*
G01X939074Y463442D02*
X941505D01*
G01X944290Y621311D02*
X941859D01*
G01X944290Y629311D02*
X941859D01*
G01X935281Y677795D02*
X932412D01*
G01X935281Y680945D02*
X932412D01*
G01D02*
Y687237D01*
G01X939314Y712147D02*
Y707847D01*
G01X938526Y730600D02*
X936026D01*
G01X938526Y727450D02*
Y719903D01*
G01X936026Y727450D02*
X938526D01*
G01X943661Y792330D02*
X945626Y790365D01*
Y789761D01*
G01X940511Y792330D02*
X938357Y794484D01*
Y798194D01*
G01X940511Y792330D02*
Y791451D01*
X942676Y789286D01*
G01X939916Y811465D02*
Y810965D01*
X941916Y808965D01*
G01X935916Y811465D02*
X939916D01*
G01X941916Y808965D02*
Y807745D01*
X943475Y806186D01*
Y804886D01*
G01X943916Y811465D02*
X944916Y810465D01*
Y808965D01*
G01X931916Y814615D02*
Y817015D01*
G01X937635Y823482D02*
X941535D01*
G01D02*
X946296D01*
X947735Y824921D01*
G01X948935Y833332D02*
X945035D01*
G01X943735Y847732D02*
X945203Y849200D01*
X946700D01*
G01X933700Y887508D02*
X936297D01*
G01D02*
Y883792D01*
X936295Y883790D01*
G01X936253Y891216D02*
X935237Y890200D01*
X932300D01*
G01X932716Y898179D02*
X936616D01*
G01D02*
Y899281D01*
X938188Y900853D01*
G01X944839Y899890D02*
Y902400D01*
G01X940516Y898180D02*
X941592Y899256D01*
Y900908D01*
G01X944628Y925701D02*
Y928101D01*
G01X932628Y925701D02*
Y928101D01*
G01X936628Y925701D02*
Y928101D01*
G01X940628Y925701D02*
X940497Y925832D01*
Y928101D01*
G01X933810Y967455D02*
Y972433D01*
G01X934378Y1014078D02*
X934525Y1013931D01*
Y1009346D01*
G01D02*
X931425Y1006246D01*
Y1003630D01*
G01X939931Y1014078D02*
X939966Y1014043D01*
Y1009184D01*
G01D02*
X936866Y1006084D01*
Y1003630D01*
G01X942256D02*
Y1006279D01*
X945166Y1009189D01*
G01D02*
Y1013813D01*
X945431Y1014078D01*
G01X951040Y221305D02*
Y223885D01*
G01X946064Y249807D02*
Y252998D01*
G01X951278Y248102D02*
Y250583D01*
G01X946937Y330517D02*
X949579D01*
G01X946937Y336817D02*
X949813D01*
G01X956863Y454376D02*
Y451466D01*
G01X959816Y470494D02*
Y472905D01*
G01X956365Y639386D02*
Y641817D01*
G01X950865Y639386D02*
Y641817D01*
G01X961503Y701257D02*
X957551D01*
G01D02*
Y698251D01*
G01X947556Y702050D02*
Y699550D01*
G01X961503Y711157D02*
Y704407D01*
G01D02*
X963274D01*
X965774Y706907D01*
G01X954023Y720803D02*
Y725336D01*
G01X955076Y784861D02*
X952682Y782467D01*
X952603D01*
G01X952528Y786366D02*
X953571D01*
X955076Y784861D01*
G01X952759Y792505D02*
Y791645D01*
X950475Y789361D01*
G01X952759Y799233D02*
Y792505D01*
G01X954760Y826734D02*
X954850Y826644D01*
Y825309D01*
X952923Y823382D01*
X950435D01*
X950335Y823282D01*
G01X951100Y838525D02*
X947200D01*
G01X948935Y833332D02*
Y835800D01*
G01X947568Y846635D02*
Y848332D01*
X946700Y849200D01*
G01X954700Y842700D02*
Y841400D01*
X951825Y838525D01*
X951100D01*
G01X957632Y846665D02*
X960100D01*
G01X954700Y837700D02*
X952835Y835835D01*
Y835710D01*
X952783Y835658D01*
Y833358D01*
G01X958200Y838525D02*
X961175D01*
G01X954000Y853575D02*
X950100D01*
G01D02*
X949095D01*
X947735Y854935D01*
G01X947702Y864862D02*
X949080Y866240D01*
X950291D01*
G01X957900Y853575D02*
Y856300D01*
G01X953123Y870278D02*
X953085Y870240D01*
X950291D01*
G01X954124Y879995D02*
X955295D01*
X955806Y879484D01*
Y875048D01*
X954998Y874240D01*
X953145D01*
G01X947845Y878216D02*
X949884D01*
X950300Y877800D01*
G01X955139Y899890D02*
Y901262D01*
X953587Y902814D01*
G01X950567Y930244D02*
Y927654D01*
G01X954567Y930244D02*
Y927654D01*
G01X957671Y988818D02*
Y991564D01*
G01X961671Y988818D02*
Y991564D01*
G01X953671Y988818D02*
Y991564D01*
G01X955165Y1003486D02*
X955576Y1003897D01*
Y1009333D01*
G01D02*
Y1013368D01*
X954866Y1014078D01*
G01X960845Y1008941D02*
Y1011187D01*
X963823Y1014165D01*
G01X961110Y1003283D02*
Y1005619D01*
X960845Y1005884D01*
Y1008941D01*
G01X950987Y1014078D02*
X950389Y1013480D01*
Y1009350D01*
G01D02*
X948285Y1007246D01*
Y1003437D01*
G01X951283Y1102760D02*
X948883D01*
G01X951367Y1098724D02*
X948867D01*
G01X956833Y1102760D02*
X954433D01*
G01X965369Y1204673D02*
X962564D01*
X961404Y1205833D01*
G01X957167Y1208069D02*
X959403Y1205833D01*
X961404D01*
G01X952627Y1202122D02*
Y1199622D01*
G01X958968Y1367717D02*
X952070D01*
G01X949070D02*
X952070D01*
G01X948832Y1371654D02*
X951832D01*
G01X958968D02*
X951832D01*
G01X958968Y1407087D02*
X952180D01*
G01X979550Y328472D02*
X977150D01*
G01X979550Y335472D02*
X977150D01*
G01X979550Y331972D02*
X977150D01*
G01X979550Y338972D02*
X977150D01*
G01X975932Y439919D02*
Y437508D01*
G01X971932Y439919D02*
Y437508D01*
G01X962769Y461462D02*
Y458466D01*
G01X969109Y451763D02*
Y449352D01*
G01X962816Y445344D02*
Y442919D01*
G01X967816Y470494D02*
Y472905D01*
G01X972397Y470554D02*
Y472954D01*
G01X963816Y470494D02*
Y472905D01*
G01X974440Y608311D02*
X976962D01*
G01X978161Y628242D02*
X980683D01*
G01X973712Y719664D02*
Y722064D01*
G01X976666Y827907D02*
X976660Y827913D01*
Y831799D01*
G01D02*
Y834993D01*
X976635Y835018D01*
G01X982787Y899757D02*
X982248D01*
X981710Y900295D01*
X972833D01*
G01X972278Y934429D02*
Y932420D01*
X970075Y930217D01*
X966746D01*
G01Y933367D02*
X965077Y935036D01*
Y939620D01*
X962746Y941951D01*
Y944423D01*
G01X968507Y937615D02*
X968882Y937240D01*
Y933878D01*
X968127Y933123D01*
X966990D01*
X966746Y933367D01*
G01X965671Y988818D02*
Y991564D01*
G01X966466Y1009238D02*
Y1013150D01*
X967625Y1014309D01*
G01X966466Y1009238D02*
Y1004097D01*
X967028Y1003535D01*
G01X971798Y1009319D02*
Y1014291D01*
X971760Y1014329D01*
G01X973080Y1003456D02*
Y1008037D01*
X971798Y1009319D01*
G01X975659Y1014350D02*
Y1013992D01*
X979660Y1009991D01*
X980018D01*
G01X963966Y1081764D02*
X966366D01*
G01X972776Y1096659D02*
X975176D01*
G01X965740Y1360945D02*
X978857D01*
G01X972512Y1369685D02*
X980501D01*
G01X965740Y1413859D02*
X978944D01*
G01X972512Y1405119D02*
X980653D01*
X984136Y1401636D01*
G01X984750Y98551D02*
X987283D01*
G01X984750Y101701D02*
X987283D01*
G01X990833Y101348D02*
Y103783D01*
G01X988373Y147540D02*
X985595D01*
G01X992343Y141247D02*
X989367D01*
G01X988373Y151540D02*
X985595D01*
G01X990939Y259535D02*
Y256535D01*
G01X993992Y288058D02*
Y290755D01*
G01X989992Y288058D02*
Y290755D01*
G01X992045Y364159D02*
Y366559D01*
G01X984045Y364159D02*
Y366559D01*
G01X988045Y364159D02*
Y366559D01*
G01X996045Y364159D02*
X992045D01*
G01X980045D02*
Y366559D01*
G01X979932Y439919D02*
Y437508D01*
G01X980397Y470634D02*
Y473045D01*
G01X983712Y719664D02*
Y722064D01*
G01X991990Y771549D02*
Y773974D01*
G01X990051Y813768D02*
X988696D01*
X987501Y812573D01*
G01X990051Y816918D02*
X989573Y816975D01*
X987903Y818645D01*
G01X981628Y829159D02*
X979203D01*
G01X981628Y833159D02*
X979203D01*
G01X980018Y1009991D02*
Y1005148D01*
X979129Y1004259D01*
G01X978326Y1080659D02*
X980726D01*
G01X978326Y1076659D02*
X980969D01*
G01X978326Y1084659D02*
X980726D01*
G01X978857Y1360945D02*
X981857D01*
G01X980501Y1369685D02*
X983501D01*
G01X981944Y1413859D02*
X978944D01*
G01X984136Y1401636D02*
X987136D01*
G01X994833Y101348D02*
Y103783D01*
G01X1006000Y107921D02*
Y103621D01*
G01X1004177Y146461D02*
X1001175D01*
G01X997091Y152367D02*
X1000077D01*
G01X998939Y259535D02*
Y256535D01*
G01X997992Y288058D02*
Y290755D01*
G01X1004635Y302676D02*
Y300276D01*
G01X1008635Y302676D02*
Y300276D01*
G01X1000698Y302676D02*
Y300276D01*
G01X1003990Y768399D02*
Y765899D01*
G01X1006699Y816975D02*
X1002699D01*
G01D02*
Y819475D01*
G01X1010009Y982956D02*
X1014009D01*
G01X1005301Y1006560D02*
Y1006573D01*
X1005938Y1007210D01*
Y1009260D01*
G01X1010009Y995106D02*
Y998100D01*
G01X998872Y1001391D02*
Y999514D01*
X999879Y998507D01*
G01X998852Y1015166D02*
X999700Y1016014D01*
Y1018400D01*
G01X1008759Y1021177D02*
Y1023900D01*
G01X1020049Y1333911D02*
X1003076D01*
X996213Y1327048D01*
G01X1010886Y1363533D02*
X1008312D01*
G01D02*
X1007527Y1362748D01*
Y1356626D01*
X1010439Y1353714D01*
X1010933D01*
G01X1013991Y1360842D02*
X1011572D01*
X1010929Y1360199D01*
Y1357938D01*
G01X1010908Y1372734D02*
X1008483D01*
G01X1010903Y1376752D02*
X1008452D01*
G01X1010912Y1380797D02*
X1008387D01*
G01X1002052Y1397662D02*
X1006211D01*
G01X1023073Y64722D02*
X1023373Y64422D01*
Y60922D01*
G01X1014805Y81848D02*
Y85052D01*
X1012844Y87013D01*
Y88801D01*
G01Y91951D02*
X1015402D01*
G01X1026200Y91974D02*
Y94374D01*
G01X1012844Y88801D02*
X1015427D01*
G01X1014006Y117261D02*
X1014427Y116840D01*
Y114488D01*
G01X1025755Y104749D02*
Y102249D01*
G01X1024289Y130898D02*
X1021780D01*
G01X1025927Y134579D02*
X1025476Y135030D01*
X1025443D01*
X1023731Y136742D01*
X1022816D01*
G01X1012134Y149768D02*
Y152562D01*
G01X1020969Y158015D02*
Y160715D01*
X1020378Y161306D01*
G01X1019162Y225719D02*
Y221867D01*
X1019165Y221864D01*
G01X1026280Y252371D02*
X1023502D01*
G01X1026280Y248371D02*
X1023502D01*
G01X1016635Y302676D02*
Y300276D01*
G01X1012635Y302676D02*
Y300276D01*
G01X1025749Y302676D02*
Y300276D01*
G01X1020635Y302676D02*
Y300276D01*
G01X1015195Y428305D02*
X1032396Y445506D01*
X1041408D01*
G01X1019470Y771974D02*
X1021895D01*
G01X1016320Y825981D02*
Y828481D01*
G01X1019470Y818974D02*
X1021895D01*
G01X1018278Y837659D02*
X1020703D01*
G01X1015628Y848680D02*
Y850420D01*
X1014742Y851306D01*
X1013918D01*
G01X1037709Y886209D02*
X1036194Y887724D01*
X1019373D01*
X1016798Y890299D01*
G01X1026009Y982956D02*
X1022009D01*
G01D02*
X1018009D01*
G01D02*
X1014009D01*
G01X1030009D02*
X1026009D01*
G01X1018009Y980356D02*
Y982956D01*
G01X1014009D02*
Y980356D01*
G01X1022009Y995106D02*
Y997860D01*
G01X1018009Y995106D02*
Y997860D01*
G01X1026009Y995106D02*
Y997860D01*
G01X1014009Y995106D02*
Y997860D01*
G01X1023709Y1207882D02*
X1021406Y1205579D01*
X1020434D01*
G01X1022420Y1203204D02*
X1024689D01*
X1026538Y1205053D01*
G01X1029366Y1202225D02*
X1027845Y1200704D01*
X1021383D01*
X1017934Y1204153D01*
Y1207763D01*
X1020881Y1210710D01*
G01X1017699Y1213892D02*
X1016278Y1215313D01*
Y1219955D01*
X1019774Y1223451D01*
G01X1023774D02*
Y1223204D01*
X1026057Y1220921D01*
X1029797D01*
G01X1020881Y1210710D02*
X1017699Y1213892D01*
G01X1029373Y1226152D02*
X1029371D01*
X1026968Y1223749D01*
G01X1019774Y1223451D02*
X1023774D01*
G01X1021259Y1316597D02*
X1025378D01*
X1025399Y1316576D01*
G01X1025434Y1320606D02*
X1026688Y1319352D01*
X1032295D01*
G01X1025399Y1316576D02*
Y1320571D01*
X1025434Y1320606D01*
G01X1024115Y1333964D02*
X1025709D01*
X1029348Y1330325D01*
X1032272D01*
G01X1019671Y1344924D02*
X1015286D01*
G01X1035865Y1357372D02*
X1029907D01*
X1023358Y1363921D01*
G01X1025466Y1373216D02*
X1021623D01*
G01X1045558Y97667D02*
X1043123D01*
G01X1033755Y104749D02*
Y102249D01*
G01X1041374Y106495D02*
X1038779D01*
G01X1029755Y104749D02*
Y102249D01*
G01X1041374Y102495D02*
X1038779D01*
G01X1031780Y130898D02*
Y133298D01*
G01X1036013Y146012D02*
X1038513D01*
G01X1038953Y138838D02*
Y139762D01*
X1040419Y141228D01*
G01X1038513Y142862D02*
X1036013D01*
G01D02*
X1033432D01*
X1033218Y142648D01*
X1029902D01*
G01X1039361Y153296D02*
X1042262D01*
X1043307Y152251D01*
Y150847D01*
G01X1042084Y247292D02*
X1045275D01*
G01X1040626Y236121D02*
X1038065D01*
G01X1035099Y236009D02*
Y238589D01*
G01X1040379Y242078D02*
X1042860D01*
G01X1040626Y232971D02*
X1038091D01*
G01X1034998Y253198D02*
X1037984D01*
G01X1041496Y302676D02*
Y300276D01*
G01X1029639Y302676D02*
Y300141D01*
G01X1045145Y812262D02*
X1039349D01*
Y812340D01*
X1039251D01*
G01X1046009Y982956D02*
X1042009D01*
G01X1034009D02*
X1030009D01*
G01X1038009D02*
X1034009D01*
G01X1042009D02*
X1038009D01*
G01X1030009Y995106D02*
Y997860D01*
G01X1034009Y995106D02*
Y997860D01*
G01X1042009Y995106D02*
Y997860D01*
G01X1038009Y995106D02*
Y997860D01*
G01X1035463Y1211541D02*
Y1202152D01*
X1033731Y1200420D01*
X1031185D01*
X1029380Y1202225D01*
X1029366D01*
G01X1037857Y1217668D02*
X1035384Y1215195D01*
G01X1040600Y1210600D02*
Y1210117D01*
X1042669Y1208048D01*
X1045208D01*
X1046343Y1209183D01*
G01X1029797Y1220921D02*
Y1217207D01*
X1035463Y1211541D01*
G01X1043514Y1212011D02*
X1040686Y1214839D01*
X1040685D01*
G01D02*
X1037387Y1211541D01*
X1035463D01*
G01X1032200Y1223324D02*
X1029797Y1220921D01*
G01X1035027Y1220496D02*
Y1220497D01*
X1032200Y1223324D01*
G01X1034513Y1333665D02*
Y1331705D01*
X1033133Y1330325D01*
X1032272D01*
G01X1042925Y1323092D02*
X1047842D01*
X1048361Y1323611D01*
G01X1037883Y1348200D02*
X1040210D01*
X1042586Y1345824D01*
G01X1052736Y236134D02*
Y238714D01*
G01X1050041Y250599D02*
Y248698D01*
X1048217Y246874D01*
G01X1045650Y302676D02*
Y300093D01*
G01X1058800Y310574D02*
X1076571D01*
G01X1058800Y314539D02*
X1077123D01*
X1077602Y314060D01*
G01X1058687Y339509D02*
X1061325D01*
G01X1058687Y343509D02*
X1061387D01*
G01X1058279Y360151D02*
X1060679D01*
G01X1058279Y356151D02*
X1060679D01*
G01X1058279Y364276D02*
X1060679D01*
G01X1058279Y368276D02*
X1060679D01*
G01X1054748Y450750D02*
X1050777D01*
G01X1053144Y538816D02*
Y538114D01*
X1054876Y536382D01*
G01D02*
X1057134Y538640D01*
Y538775D01*
G01X1048328Y808166D02*
X1048796D01*
X1052289Y811659D01*
X1053227D01*
G01X1062009Y982956D02*
X1058009D01*
G01X1050009D02*
X1046009D01*
G01X1054009D02*
X1050009D01*
G01X1058009D02*
X1054009D01*
G01X1046009Y995106D02*
Y997860D01*
G01X1054009Y995106D02*
Y997860D01*
G01X1050009Y995106D02*
Y997860D01*
G01X1058009Y995106D02*
Y997860D01*
G01X1051511Y1323611D02*
Y1336274D01*
X1052221Y1336984D01*
G01X1048361Y1323611D02*
Y1336534D01*
X1049204Y1337377D01*
G01X1068436Y558555D02*
Y554555D01*
G01D02*
X1069893D01*
X1070572Y555234D01*
X1071548D01*
G01X1068468Y562567D02*
X1070699D01*
X1071263Y562003D01*
G01X1064598Y637969D02*
X1064954Y637613D01*
Y636551D01*
X1066559Y634946D01*
G01D02*
X1067748Y633757D01*
Y631421D01*
G01X1070009Y991956D02*
Y988813D01*
G01X1066009Y982956D02*
X1074009D01*
G01X1069607Y980131D02*
X1073509D01*
X1074009Y980631D01*
Y982956D01*
G01X1066009D02*
X1062009D01*
G01X1066009D02*
Y980330D01*
G01Y995106D02*
Y997860D01*
G01X1062009Y995106D02*
Y997860D01*
G01X1074009Y995106D02*
Y997860D01*
G01X1087112Y98551D02*
X1089645D01*
G01X1087112Y101701D02*
X1089645D01*
G01X1090735Y147540D02*
X1087957D01*
G01X1094705Y141247D02*
X1091729D01*
G01X1090735Y151540D02*
X1087957D01*
G01X1086108Y1523433D02*
X1083483D01*
G01X1086108Y1526583D02*
X1083283D01*
G01X1093376Y1554183D02*
X1090876D01*
G01X1086469Y1585560D02*
Y1588435D01*
G01X1083735Y1603623D02*
X1082176Y1602064D01*
Y1600598D01*
G01X1090904Y1596356D02*
Y1599047D01*
G01X1091168Y1621515D02*
Y1617836D01*
X1090747Y1617415D01*
G01X1085474Y1631850D02*
Y1629028D01*
G01X1097195Y101348D02*
Y103783D01*
G01X1093195Y101348D02*
Y103783D01*
G01X1106539Y146461D02*
X1103537D01*
G01X1099453Y152367D02*
X1102439D01*
G01X1101301Y259535D02*
Y256535D01*
G01X1093301Y259535D02*
Y256535D01*
G01X1092354Y288058D02*
Y290755D01*
G01X1096354Y288058D02*
Y290755D01*
G01X1100354Y288058D02*
Y290755D01*
G01X1108045Y682006D02*
Y677843D01*
G01X1096264Y1566933D02*
Y1562285D01*
G01X1098376Y1554183D02*
X1100876D01*
G01X1096233Y1582433D02*
X1096264Y1582402D01*
Y1574807D01*
G01X1093713Y1585583D02*
X1096233D01*
G01X1093682Y1582433D02*
X1096233D01*
G01X1104233Y1585583D02*
Y1587983D01*
G01X1098904Y1593206D02*
Y1590841D01*
X1098498Y1590435D01*
G01X1104612Y1606752D02*
X1107620D01*
G01Y1603602D02*
X1104612D01*
G01X1098846Y1606949D02*
X1100920D01*
X1101737Y1606132D01*
Y1604784D01*
X1102919Y1603602D01*
X1104612D01*
G01X1101474Y1635000D02*
Y1637820D01*
G01X1093474Y1635000D02*
Y1638213D01*
G01X1117167Y81848D02*
Y85052D01*
X1115206Y87013D01*
Y88801D01*
G01Y91951D02*
X1117764D01*
G01X1115206Y88801D02*
X1117789D01*
G01X1108362Y107921D02*
Y103621D01*
G01X1116368Y117261D02*
X1116789Y116840D01*
Y114488D01*
G01X1114496Y149768D02*
Y152562D01*
G01X1123331Y158015D02*
Y160715D01*
X1122740Y161306D01*
G01X1121524Y225719D02*
Y221867D01*
X1121527Y221864D01*
G01X1125925Y329000D02*
X1123500D01*
G01X1125925Y339000D02*
X1123500D01*
G01X1125925Y334000D02*
X1123500D01*
G01X1117425Y329000D02*
X1115000D01*
G01X1117425Y334000D02*
X1115000D01*
G01X1117425Y339000D02*
X1115000D01*
G01X1113553Y424587D02*
X1117452D01*
X1117453Y424586D01*
G01X1118204Y660402D02*
Y662322D01*
X1118863Y662981D01*
G01X1112839Y666275D02*
Y668885D01*
G01X1115054Y662981D02*
Y660402D01*
G01X1115989Y666275D02*
X1115525Y666739D01*
Y672360D01*
G01X1115989Y666275D02*
Y663916D01*
X1115054Y662981D01*
G01X1118105Y710129D02*
Y707592D01*
G01X1125435Y64722D02*
X1125735Y64422D01*
Y60922D01*
G01X1128562Y91974D02*
Y94374D01*
G01X1136117Y104749D02*
Y102249D01*
G01X1132117Y104749D02*
Y102249D01*
G01X1128117Y104749D02*
Y102249D01*
G01X1134142Y130898D02*
Y133298D01*
G01X1126142Y130898D02*
Y133298D01*
G01X1138375Y146012D02*
X1140875D01*
G01X1128289Y134579D02*
X1127838Y135030D01*
X1127805D01*
X1126093Y136742D01*
X1125178D01*
G01X1140875Y142862D02*
X1138375D01*
G01D02*
X1135794D01*
X1135580Y142648D01*
X1132264D01*
G01X1137461Y236009D02*
Y238589D01*
G01X1142988Y236121D02*
X1140427D01*
G01X1142988Y232971D02*
X1140453D01*
G01X1137360Y253198D02*
X1140346D01*
G01X1128642Y252371D02*
X1125864D01*
G01X1128642Y248371D02*
X1125864D01*
G01X1141198Y553700D02*
X1139898Y555000D01*
X1138673D01*
G01X1135748Y549800D02*
X1138373D01*
G01X1138213Y558800D02*
X1139313Y557700D01*
X1141198D01*
G01X1147920Y97667D02*
X1145485D01*
G01X1143736Y106495D02*
X1141141D01*
G01X1143736Y102495D02*
X1141141D01*
G01X1141315Y138838D02*
Y139762D01*
X1142781Y141228D01*
G01X1141723Y153296D02*
X1144624D01*
X1145669Y152251D01*
Y150847D01*
G01X1155098Y236134D02*
Y238714D01*
G01X1144446Y247292D02*
X1147637D01*
G01X1142741Y242078D02*
X1145222D01*
G01X1152403Y250599D02*
Y248698D01*
X1150579Y246874D01*
G01X1150912Y324148D02*
X1145761D01*
G01X1156023Y678462D02*
Y675832D01*
G01X1156756Y669913D02*
X1159173Y672330D01*
Y675832D01*
G01X1171712Y334148D02*
X1177036D01*
G01X1179761Y339103D02*
X1179716Y339148D01*
X1171712D01*
G01X1166448Y449873D02*
X1168851D01*
G01X1168398Y456309D02*
X1164586D01*
X1163298Y457597D01*
Y458859D01*
G01X1166448Y445873D02*
X1168851D01*
G01X1157251Y633786D02*
Y636842D01*
G01X1163157Y640872D02*
Y638125D01*
G01X1160756Y661113D02*
Y665140D01*
G01X1162863Y678519D02*
Y675889D01*
G01X1159173Y678462D02*
Y675832D01*
G01X1174595Y774434D02*
Y777910D01*
X1173011Y779494D01*
G01X1189474Y98551D02*
X1192007D01*
G01X1189474Y101701D02*
X1192007D01*
G01X1182911Y339103D02*
Y336516D01*
G01X1179761Y336380D02*
Y339103D01*
G01X1184478Y580925D02*
X1180579D01*
X1180578Y580926D01*
G01X1177745Y774434D02*
Y771744D01*
G01X1177566Y778539D02*
X1177920Y778893D01*
X1180715D01*
G01X1174595Y771744D02*
Y774434D01*
G01X1176500Y784933D02*
X1179420D01*
X1180715Y783638D01*
Y782043D01*
G01X1199557Y101348D02*
Y103783D01*
G01X1195557Y101348D02*
Y103783D01*
G01X1193097Y147540D02*
X1190319D01*
G01X1197067Y141247D02*
X1194091D01*
G01X1201815Y152367D02*
X1204801D01*
G01X1193097Y151540D02*
X1190319D01*
G01X1203663Y259535D02*
Y256535D01*
G01X1195663Y259535D02*
Y256535D01*
G01X1194716Y288058D02*
Y290755D01*
G01X1202716Y288058D02*
Y290755D01*
G01X1198716Y288058D02*
Y290755D01*
G01X1201113Y317873D02*
Y315039D01*
G01X1219529Y81848D02*
Y85052D01*
X1217568Y87013D01*
Y88801D01*
G01Y91951D02*
X1220126D01*
G01X1217568Y88801D02*
X1220151D01*
G01X1218730Y117261D02*
X1219151Y116840D01*
Y114488D01*
G01X1210724Y107921D02*
Y103621D01*
G01X1208901Y146461D02*
X1205899D01*
G01X1216858Y149768D02*
Y152562D01*
G01X1227797Y64722D02*
X1228097Y64422D01*
Y60922D01*
G01X1230924Y91974D02*
Y94374D01*
G01X1230479Y104749D02*
Y102249D01*
G01X1234479Y104749D02*
Y102249D01*
G01X1229195Y130898D02*
X1226504D01*
G01X1236504D02*
Y133298D01*
G01X1230651Y134579D02*
X1230200Y135030D01*
X1230167D01*
X1228455Y136742D01*
X1227540D01*
G01X1240737Y142862D02*
X1238156D01*
X1237942Y142648D01*
X1234626D01*
G01X1225693Y158015D02*
Y160715D01*
X1225102Y161306D01*
G01X1223886Y225719D02*
Y221867D01*
X1223889Y221864D01*
G01X1231004Y252371D02*
X1228226D01*
G01X1231004Y248371D02*
X1228226D01*
G01X1238055Y306652D02*
Y303839D01*
G01X1226436Y311740D02*
X1229028D01*
G01X1234447Y336324D02*
X1230077D01*
G01X1234656Y350850D02*
Y353506D01*
G01X1231506Y353470D02*
Y350850D01*
G01X1250282Y97667D02*
X1247847D01*
G01X1238479Y104749D02*
Y102249D01*
G01X1246098Y106495D02*
X1243503D01*
G01X1246098Y102495D02*
X1243503D01*
G01X1240737Y146012D02*
X1243237D01*
G01X1243677Y138838D02*
Y139762D01*
X1245143Y141228D01*
G01X1243237Y142862D02*
X1240737D01*
G01X1244085Y153296D02*
X1246986D01*
X1248031Y152251D01*
Y150847D01*
G01X1246808Y247292D02*
X1249999D01*
G01X1239823Y236009D02*
Y238589D01*
G01X1245350Y236121D02*
X1242789D01*
G01X1249225Y236109D02*
X1245362D01*
X1245350Y236121D01*
G01X1245103Y242078D02*
X1247584D01*
G01X1254765Y250599D02*
Y248698D01*
X1252941Y246874D01*
G01X1245350Y232971D02*
X1242815D01*
G01X1239722Y253198D02*
X1242708D01*
G01X1241205Y303962D02*
Y306652D01*
G01D02*
X1241600Y307047D01*
Y312849D01*
G01X1256458Y565287D02*
X1248362D01*
X1243118Y560043D01*
G01X1251802Y1175750D02*
X1250150D01*
X1249363Y1174963D01*
Y1173065D01*
G01X1251802Y1178900D02*
Y1186071D01*
G01X1247540Y1531342D02*
Y1529640D01*
X1245900Y1528000D01*
G01X1257460Y236134D02*
Y238714D01*
G01X1258925Y327000D02*
Y324075D01*
G01X1268294Y327801D02*
X1262876D01*
X1262075Y327000D01*
G01D02*
Y324075D01*
G01X1257925Y336000D02*
Y334425D01*
X1257000Y333500D01*
G01X1260659Y379573D02*
Y376225D01*
X1262584Y374300D01*
X1266219D01*
G01X1264659Y379573D02*
Y377173D01*
G01X1267944Y371767D02*
X1266879Y370702D01*
X1260458D01*
X1256659Y374501D01*
Y379573D01*
G01X1261764Y393933D02*
Y391533D01*
G01X1261623Y447486D02*
Y450334D01*
G01Y458334D02*
X1259223D01*
G01X1267792Y908277D02*
X1270515D01*
G01X1259921Y1137129D02*
Y1135347D01*
X1260539Y1134729D01*
G01X1261173Y1146071D02*
X1263244D01*
X1263873Y1146700D01*
Y1148000D01*
G01X1260558Y1153242D02*
Y1146686D01*
X1261173Y1146071D01*
G01X1266887Y1163968D02*
Y1160346D01*
X1266709Y1160168D01*
G01X1268587Y1178240D02*
X1271246D01*
G01X1268573Y1195419D02*
Y1193019D01*
G01X1264573Y1195419D02*
Y1193019D01*
G01X1268575Y1206593D02*
X1272575D01*
G01X1264575D02*
X1268575D01*
G01X1258639Y1220765D02*
X1258123Y1220249D01*
Y1216063D01*
X1264575Y1209611D01*
Y1206593D01*
G01X1261468Y1223592D02*
X1261466D01*
X1258639Y1220765D01*
G01X1264297Y1226421D02*
X1261468Y1223592D01*
G01X1267126Y1229250D02*
X1264297Y1226421D01*
G01X1260260Y1523458D02*
X1263242D01*
G01X1260208Y1519459D02*
X1262985D01*
G01X1260260Y1543558D02*
Y1546500D01*
G01X1285420Y327801D02*
X1288274D01*
X1291500Y324575D01*
G01X1283494Y339495D02*
Y337995D01*
X1285420Y336069D01*
G01X1276659Y385123D02*
Y382723D01*
G01X1282760Y406616D02*
Y409016D01*
G01X1278724Y406532D02*
Y409032D01*
G01X1282760Y401066D02*
Y403466D01*
G01X1281939Y772576D02*
X1279539D01*
G01X1281939Y776576D02*
X1279539D01*
G01X1281939Y768576D02*
X1279539D01*
G01X1281939Y780576D02*
X1279539D01*
G01X1281939Y784576D02*
X1279539D01*
G01X1287925Y819500D02*
X1285092D01*
G01X1287920Y889767D02*
X1286669D01*
X1285493Y890943D01*
Y892175D01*
G01D02*
X1284655Y893013D01*
Y894925D01*
G01X1281075Y914000D02*
Y911075D01*
G01X1285941Y913331D02*
Y914559D01*
X1284500Y916000D01*
X1281954D01*
X1281075Y915121D01*
Y914000D01*
G01X1280042Y905223D02*
X1281541D01*
X1283494Y907176D01*
G01X1277925Y914000D02*
Y915598D01*
X1277039Y916484D01*
G01X1282421Y1137129D02*
X1279921D01*
G01X1282830Y1146937D02*
X1280330D01*
G01X1275155Y1146842D02*
Y1148404D01*
X1276838Y1150087D01*
X1280330D01*
G01X1282830D02*
X1280330D01*
G01X1280306Y1165217D02*
Y1162817D01*
G01X1275155Y1163968D02*
Y1167546D01*
X1275976Y1168367D01*
X1280306D01*
G01Y1170767D02*
Y1168367D01*
G01X1271246Y1178240D02*
X1273864D01*
X1273912Y1178288D01*
G01X1276573Y1195419D02*
Y1193019D01*
G01X1280573Y1195419D02*
Y1193019D01*
G01X1272573Y1195419D02*
Y1193019D01*
G01X1284198Y1218754D02*
X1278880Y1224072D01*
G01X1272575Y1206593D02*
X1276575D01*
G01D02*
X1280575D01*
G01D02*
X1280694Y1206712D01*
Y1208993D01*
G01D02*
X1281937Y1210236D01*
Y1216189D01*
X1278135Y1219991D01*
X1277305D01*
X1276052Y1221244D01*
G01X1306994Y25754D02*
X1305709D01*
X1303229Y23274D01*
G01X1291836Y98551D02*
X1294369D01*
G01X1291836Y101701D02*
X1294369D01*
G01X1301919Y101348D02*
Y103783D01*
G01X1297919Y101348D02*
Y103783D01*
G01X1298025Y259535D02*
Y256535D01*
G01X1297078Y288058D02*
Y290755D01*
G01X1301078Y288058D02*
Y290755D01*
G01X1291500Y321425D02*
X1294425D01*
G01X1291500Y324575D02*
X1293425D01*
X1294000Y324000D01*
G01D02*
X1295425Y325425D01*
Y326500D01*
G01X1287437Y372604D02*
Y370010D01*
G01X1291410Y373680D02*
Y371060D01*
G01X1287772Y458309D02*
X1290272D01*
G01X1287772Y454309D02*
X1290272D01*
G01X1287772Y462309D02*
X1290272D01*
G01X1303520Y748403D02*
X1303127Y748010D01*
X1298246D01*
G01X1295491Y796321D02*
Y798821D01*
G01X1292566Y804246D02*
X1290066D01*
G01X1292566Y807396D02*
X1290281D01*
X1289730Y806845D01*
G01X1298720Y807880D02*
X1295126D01*
X1294642Y807396D01*
X1292566D01*
G01X1288155Y894925D02*
Y892363D01*
X1288164Y892354D01*
G01X1289547Y930957D02*
Y928047D01*
G01X1298000Y919925D02*
Y917000D01*
G01X1294075Y919500D02*
Y917000D01*
G01X1300925Y942500D02*
X1299277Y940852D01*
X1298090D01*
G01X1295453Y938043D02*
Y940953D01*
G01X1302500Y939500D02*
X1304075Y941075D01*
Y942500D01*
G01X1296500Y961500D02*
Y963925D01*
G01X1289500Y947075D02*
Y949500D01*
G01X1300500Y967075D02*
Y970187D01*
G01X1298819Y989634D02*
X1306900D01*
X1307580Y990314D01*
G01X1313086Y107921D02*
Y103621D01*
G01X1306025Y259535D02*
Y256535D01*
G01X1305078Y288058D02*
Y290755D01*
G01X1308410Y373481D02*
Y370899D01*
G01X1310172Y367956D02*
X1316543D01*
X1316903Y368316D01*
G01X1305416Y466409D02*
X1308010D01*
G01X1313899Y471560D02*
X1311488D01*
G01X1305416Y470382D02*
X1307835D01*
G01X1305416Y487382D02*
X1307996D01*
G01X1313899Y479560D02*
X1311488D01*
G01X1313899Y475560D02*
X1311488D01*
G01X1321425Y566500D02*
X1319000D01*
G01X1321425Y562500D02*
X1319000D01*
G01X1321425Y558500D02*
X1319000D01*
G01X1321425Y582500D02*
X1319000D01*
G01X1321425Y586500D02*
X1319000D01*
G01X1321425Y574500D02*
X1319000D01*
G01X1321425Y578500D02*
X1319000D01*
G01X1321425Y590500D02*
X1319000D01*
G01X1321425Y613000D02*
X1319000D01*
G01X1321425Y605000D02*
X1319000D01*
G01X1321425Y609000D02*
X1319000D01*
G01X1321425Y629000D02*
X1319000D01*
G01X1321425Y621000D02*
X1319000D01*
G01X1321425Y633000D02*
X1319000D01*
G01X1321425Y625000D02*
X1319000D01*
G01X1321425Y637000D02*
X1319000D01*
G01X1321425Y649500D02*
X1319000D01*
G01X1321425Y657500D02*
X1319000D01*
G01X1321425Y653500D02*
X1319000D01*
G01X1321425Y669500D02*
X1319000D01*
G01X1321425Y665500D02*
X1319000D01*
G01X1321425Y673500D02*
X1319000D01*
G01X1321425Y681500D02*
X1319000D01*
G01X1321425Y677500D02*
X1319000D01*
G01X1321425Y696500D02*
X1319000D01*
G01X1321425Y700500D02*
X1319000D01*
G01X1321425Y704500D02*
X1319000D01*
G01X1321425Y712500D02*
X1319000D01*
G01X1321425Y716500D02*
X1319000D01*
G01X1321425Y720500D02*
X1319000D01*
G01X1321425Y724500D02*
X1319000D01*
G01X1321425Y728500D02*
X1319000D01*
G01X1305412Y802762D02*
Y799061D01*
G01X1309103Y934139D02*
Y936559D01*
G01X1304949Y934139D02*
Y934949D01*
X1306500Y936500D01*
G01X1317000Y941075D02*
X1315779Y942296D01*
Y943743D01*
G01X1321028Y961749D02*
X1318676D01*
X1318500Y961925D01*
G01X1311000Y963925D02*
Y961500D01*
G01X1318500Y965075D02*
X1320427D01*
X1321104Y964398D01*
G01X1307000Y967075D02*
Y970000D01*
G01X1317437Y1155184D02*
Y1152684D01*
G01X1334223Y35983D02*
Y33425D01*
G01X1331073Y35983D02*
Y33400D01*
G01X1324120Y34022D02*
X1324960D01*
X1326921Y35983D01*
X1331073D01*
G01X1334246Y22627D02*
X1336646D01*
G01X1321092Y117261D02*
X1321513Y116840D01*
Y114488D01*
G01X1326248Y225719D02*
Y221867D01*
X1326251Y221864D01*
G01X1320903Y370995D02*
Y368316D01*
G01X1329064Y370951D02*
Y368324D01*
G01X1325007Y370951D02*
Y368324D01*
G01X1326020Y429262D02*
Y426740D01*
G01X1330017Y468607D02*
X1332927D01*
G01X1322931Y474513D02*
X1325927D01*
G01X1332575Y586500D02*
X1335000D01*
G01X1332575Y590500D02*
X1335000D01*
G01X1332575Y594500D02*
X1335000D01*
G01X1332575Y633000D02*
X1335000D01*
G01X1332575Y637000D02*
X1335000D01*
G01X1332575Y641000D02*
X1335000D01*
G01X1332575Y677500D02*
X1335000D01*
G01X1332575Y681500D02*
X1335000D01*
G01X1332575Y685500D02*
X1335000D01*
G01X1332575Y724500D02*
X1335000D01*
G01X1332575Y728500D02*
X1335000D01*
G01X1332575Y732500D02*
X1335000D01*
G01X1324217Y780595D02*
X1325802Y782180D01*
X1327584D01*
G01Y779030D02*
X1330324D01*
G01X1324000Y930925D02*
X1323300Y930225D01*
Y923875D01*
X1322500Y923075D01*
G01X1336000Y930925D02*
X1333425D01*
G01X1326500D02*
X1324000D01*
G01X1332000Y967075D02*
Y969500D01*
G01X1327000Y967075D02*
Y969500D01*
G01X1343098Y147540D02*
X1340320D01*
G01X1347068Y141247D02*
X1344092D01*
G01X1343098Y151540D02*
X1340320D01*
G01X1351816Y152367D02*
X1354802D01*
G01X1347846Y459176D02*
Y461607D01*
G01X1339846Y459176D02*
Y461607D01*
G01X1339049Y474560D02*
Y471334D01*
G01X1350984Y561032D02*
X1355255D01*
G01X1350984Y607532D02*
X1355255D01*
G01X1350984Y652032D02*
X1355255D01*
G01X1350984Y699032D02*
X1345451D01*
G01X1342368Y737675D02*
X1344768D01*
G01X1342368Y741675D02*
X1344768D01*
G01X1342368Y745675D02*
X1344768D01*
G01X1342368Y749675D02*
X1344768D01*
G01X1342368Y753675D02*
X1344768D01*
G01X1342368Y761675D02*
X1344768D01*
G01X1342368Y765675D02*
Y761675D01*
G01Y757675D02*
X1344768D01*
G01X1342368Y769675D02*
X1344768D01*
G01X1342368Y773675D02*
X1344768D01*
G01X1358902Y146461D02*
X1355900D01*
G01X1366859Y149768D02*
Y152562D01*
G01X1357921Y452601D02*
X1360352D01*
G01X1357921Y447101D02*
X1360352D01*
G01X1366768Y1043140D02*
X1364237D01*
G01X1366691Y1047047D02*
X1363941D01*
G01X1380480Y104749D02*
Y102249D01*
G01X1378505Y130898D02*
Y133298D01*
G01X1380652Y134579D02*
X1380201Y135030D01*
X1380168D01*
X1378456Y136742D01*
X1377541D01*
G01X1375694Y158015D02*
Y160715D01*
X1375103Y161306D01*
G01X1381005Y252371D02*
X1378227D01*
G01X1381005Y248371D02*
X1378227D01*
G01X1377876Y356871D02*
X1375073D01*
G01X1387876Y361371D02*
X1385444D01*
X1384174Y362641D01*
G01X1377876Y361371D02*
X1375073D01*
G01X1380500Y593575D02*
X1383425D01*
G01X1374016Y589968D02*
X1377967D01*
X1378424Y590425D01*
X1380500D01*
G01D02*
X1383425D01*
G01X1380500Y636925D02*
X1378424D01*
X1377967Y636468D01*
X1374016D01*
G01X1383425Y636925D02*
X1380500D01*
G01Y640075D02*
X1383425D01*
G01Y684140D02*
Y684375D01*
X1383225Y684575D01*
X1380500D01*
G01X1374016Y680968D02*
X1377967D01*
X1378424Y681425D01*
X1380500D01*
G01D02*
X1383425D01*
G01X1380500Y731575D02*
X1383425D01*
G01X1374016Y727968D02*
X1377967D01*
X1378424Y728425D01*
X1380500D01*
G01D02*
X1383425D01*
G01X1378503Y937395D02*
X1382559D01*
X1382560Y937396D01*
G01D02*
X1387112D01*
X1398247Y926261D01*
G01X1400283Y97667D02*
X1397848D01*
G01X1388480Y104749D02*
Y102249D01*
G01X1384480Y104749D02*
Y102249D01*
G01X1396099Y106495D02*
X1393504D01*
G01X1396099Y102495D02*
X1393504D01*
G01X1386505Y130898D02*
Y133298D01*
G01X1390738Y146012D02*
X1393238D01*
G01X1393678Y138838D02*
Y139762D01*
X1395144Y141228D01*
G01X1393238Y142862D02*
X1390738D01*
G01D02*
X1388157D01*
X1387943Y142648D01*
X1384627D01*
G01X1394086Y153296D02*
X1396987D01*
X1398032Y152251D01*
Y150847D01*
G01X1396809Y247292D02*
X1400000D01*
G01X1395351Y236121D02*
X1392790D01*
G01X1389824Y236009D02*
Y238589D01*
G01X1395104Y242078D02*
X1397585D01*
G01X1395351Y232971D02*
X1392816D01*
G01X1389723Y253198D02*
X1392709D01*
G01X1387876Y356871D02*
X1384447D01*
G01X1388661Y577192D02*
X1391086D01*
G01X1388662Y581317D02*
X1391087D01*
G01X1388662Y627817D02*
X1391587D01*
G01X1401377Y621311D02*
X1398946D01*
G01X1388661Y623692D02*
X1391586D01*
G01X1401377Y629311D02*
X1398946D01*
G01X1390925Y675000D02*
X1388414D01*
G01X1390925Y722000D02*
X1388241D01*
G01X1388346Y924070D02*
Y921709D01*
X1388980Y921075D01*
G01X1407461Y236134D02*
Y238714D01*
G01X1404766Y250599D02*
Y248698D01*
X1402942Y246874D01*
G01X1411950Y451376D02*
Y448466D01*
G01X1414903Y467494D02*
Y469905D01*
G01X1413452Y639386D02*
Y641817D01*
G01X1407952Y639386D02*
Y641817D01*
G01X1402575Y652000D02*
X1402803Y652228D01*
X1405029D01*
X1405229Y652028D01*
G01X1402575Y656000D02*
X1405000D01*
G01X1402575Y660000D02*
X1405000D01*
G01X1412425Y685000D02*
X1410000D01*
G01X1412425Y681000D02*
X1410000D01*
G01X1402075Y675000D02*
X1404500D01*
G01X1402575Y699000D02*
X1405000D01*
G01X1412425Y689000D02*
X1410000D01*
G01X1412425Y701000D02*
X1410000D01*
G01X1412425Y697000D02*
X1410000D01*
G01X1412425Y705000D02*
X1410000D01*
G01X1412425Y709000D02*
X1410000D01*
G01X1412425Y713000D02*
X1410000D01*
G01X1402575Y707000D02*
X1405000D01*
G01X1402575Y703000D02*
X1405000D01*
G01X1412425Y733000D02*
X1410000D01*
G01X1402075Y722000D02*
X1404500D01*
G01X1412425Y729000D02*
X1410000D01*
G01X1412425Y725000D02*
X1410000D01*
G01X1412425Y749000D02*
X1410000D01*
G01X1412425Y745000D02*
X1410000D01*
G01X1412425Y741000D02*
X1410000D01*
G01X1412425Y757000D02*
X1410000D01*
G01X1412425Y753000D02*
X1410000D01*
G01X1410889Y911137D02*
X1413733D01*
G01X1410889Y915186D02*
X1413575D01*
G01X1413322Y958908D02*
X1408887Y954473D01*
X1404030D01*
G01X1414144Y992307D02*
X1416618D01*
G01X1408536Y1536570D02*
Y1507047D01*
X1420877Y1494706D01*
G01X1407747Y1546535D02*
Y1549054D01*
G01X1408536Y1539557D02*
Y1536570D01*
G01X1408044Y1562235D02*
Y1559306D01*
G01X1407255Y1569213D02*
Y1571732D01*
G01X1430986Y356051D02*
X1434608Y359673D01*
G01X1431019Y436919D02*
Y434508D01*
G01X1427019Y436919D02*
Y434508D01*
G01X1417903Y442344D02*
Y439919D01*
G01X1424196Y448763D02*
Y446352D01*
G01X1417856Y458462D02*
Y455466D01*
G01X1427484Y467634D02*
Y470045D01*
G01X1422903Y467494D02*
Y469905D01*
G01X1418903Y467494D02*
Y469905D01*
G01X1431527Y608311D02*
X1434049D01*
G01X1423575Y709000D02*
X1426000D01*
G01X1423575Y713000D02*
X1426000D01*
G01X1423575Y717000D02*
X1426000D01*
G01X1423575Y757000D02*
X1426000D01*
G01X1423575Y753000D02*
X1426000D01*
G01X1429425Y766500D02*
X1427000D01*
G01X1423575Y761000D02*
X1426000D01*
G01X1429425Y774500D02*
X1427000D01*
G01X1429425Y786500D02*
Y782500D01*
G01D02*
X1427682D01*
X1427016Y781834D01*
X1427000D01*
G01X1429425Y770500D02*
X1427000D01*
G01X1429425Y790500D02*
X1427000D01*
G01X1429425Y794500D02*
Y798500D01*
G01Y794500D02*
X1427000D01*
G01X1429425Y810500D02*
X1427000D01*
G01X1429425Y814500D02*
X1427000D01*
G01X1429425Y818500D02*
X1427000D01*
G01X1429425Y830500D02*
X1427000D01*
G01X1429425Y826500D02*
X1427000D01*
G01X1429425Y834500D02*
X1427000D01*
G01X1429425Y842500D02*
X1427000D01*
G01X1429425Y838500D02*
X1427000D01*
G01X1430247Y900295D02*
X1429617D01*
G01D02*
X1424126D01*
G01X1424958Y943390D02*
Y941795D01*
X1427553Y939200D01*
G01X1418344Y1020250D02*
X1418340Y1020246D01*
Y1016266D01*
G01X1436258Y1407740D02*
X1432258D01*
G01D02*
X1428840D01*
G01X1426253Y1407702D02*
X1428802D01*
X1428840Y1407740D01*
G01X1430374Y1495495D02*
Y1492474D01*
G01X1423396Y1494706D02*
X1420877D01*
G01X1426593Y1508327D02*
X1423065D01*
G01X1432499Y1515413D02*
Y1512175D01*
G01X1426366Y1524252D02*
X1423806D01*
G01X1426364Y1520364D02*
X1423930D01*
G01X1428454Y1537432D02*
X1425558D01*
G01X1421368Y1543338D02*
X1424245D01*
G01X1428081Y1558072D02*
X1425260D01*
G01X1420995Y1563978D02*
X1423701D01*
G01X1432913Y1566245D02*
Y1568679D01*
G01X1441837Y98551D02*
X1444370D01*
G01X1441837Y101701D02*
X1444370D01*
G01X1447920Y101348D02*
Y103783D01*
G01X1445460Y147540D02*
X1442682D01*
G01X1449430Y141247D02*
X1446454D01*
G01X1445460Y151540D02*
X1442682D01*
G01X1448026Y259535D02*
Y256535D01*
G01X1447079Y288058D02*
Y290755D01*
G01X1437758Y359673D02*
Y362584D01*
G01X1446282Y356861D02*
X1449060D01*
G01X1434608Y359673D02*
Y362584D01*
G01X1435019Y436919D02*
Y434508D01*
G01X1435484Y467634D02*
Y470045D01*
G01X1435248Y628242D02*
X1437770D01*
G01X1441984Y683532D02*
X1437784D01*
G01X1441984Y727532D02*
X1436567D01*
G01X1440575Y798500D02*
X1443000D01*
G01X1440575Y794500D02*
X1443000D01*
G01X1440575Y802500D02*
X1443000D01*
G01X1440575Y842500D02*
X1443000D01*
G01X1440575Y838500D02*
X1443000D01*
G01X1440575Y846500D02*
X1443000D01*
G01X1448137Y949440D02*
X1450467D01*
X1452007Y950980D01*
X1456543D01*
G01X1439031Y957683D02*
Y951902D01*
G01X1433996Y981437D02*
X1438634Y986075D01*
X1441670D01*
G01X1437980Y1031522D02*
X1435266D01*
G01X1435197Y1028372D02*
X1437980D01*
G01X1437293Y1543565D02*
Y1546125D01*
G01X1433405Y1543567D02*
Y1546001D01*
G01X1436792Y1555366D02*
X1433558D01*
G01X1436801Y1566243D02*
Y1568803D01*
G01X1462675Y17645D02*
Y14334D01*
G01X1463087Y107921D02*
Y103621D01*
G01X1451920Y101348D02*
Y103783D01*
G01X1461264Y146461D02*
X1458262D01*
G01X1454178Y152367D02*
X1457164D01*
G01X1456026Y259535D02*
Y256535D01*
G01X1455079Y288058D02*
Y290755D01*
G01X1451079Y288058D02*
Y290755D01*
G01X1456282Y320861D02*
X1459060D01*
G01X1456282Y325361D02*
X1459060D01*
G01X1456282Y329861D02*
X1459060D01*
G01X1456282Y338861D02*
X1459060D01*
G01X1456282Y343361D02*
X1459060D01*
G01X1456282Y334361D02*
X1459060D01*
G01X1456282Y356861D02*
X1458982D01*
G01X1456282Y347861D02*
X1459060D01*
G01X1456282Y352361D02*
X1459060D01*
G01X1471500Y712925D02*
X1469424D01*
X1468967Y712468D01*
X1465016D01*
G01X1471500Y756925D02*
X1469424D01*
X1468967Y756468D01*
X1465016D01*
G01X1458984Y769032D02*
X1453032D01*
G01X1458984Y813032D02*
X1453775D01*
G01X1458621Y928177D02*
X1454676D01*
X1451005Y931848D01*
G01X1459693Y950980D02*
X1461835D01*
X1462819Y949996D01*
G01X1462388Y1006560D02*
Y1006573D01*
X1463025Y1007210D01*
Y1009260D01*
G01X1455959Y1001391D02*
Y999514D01*
X1456966Y998507D01*
G01X1455939Y1015166D02*
Y1018368D01*
G01X1483541Y32645D02*
X1481250D01*
X1479972Y33923D01*
Y38244D01*
G01X1476822D02*
Y40780D01*
G01X1479972Y38244D02*
Y40780D01*
G01X1480160Y64722D02*
X1480460Y64422D01*
Y60922D01*
G01X1471892Y81848D02*
Y85052D01*
X1469931Y87013D01*
Y88801D01*
G01Y91951D02*
X1472489D01*
G01X1469931Y88801D02*
X1472514D01*
G01X1471093Y117261D02*
X1471514Y116840D01*
Y114488D01*
G01X1481368Y130898D02*
X1478867D01*
G01X1483014Y134579D02*
X1480851Y136742D01*
X1479903D01*
G01X1469221Y149768D02*
Y152562D01*
G01X1478056Y158015D02*
Y160715D01*
X1477465Y161306D01*
G01X1476249Y225719D02*
Y221867D01*
X1476252Y221864D01*
G01X1483367Y252371D02*
X1480589D01*
G01X1483367Y248371D02*
X1480589D01*
G01X1479971Y327200D02*
X1477549D01*
G01X1479971Y322700D02*
X1477549D01*
G01X1479971Y340700D02*
X1477549D01*
G01X1479971Y331700D02*
X1477549D01*
G01X1479971Y345200D02*
X1477549D01*
G01X1479971Y358700D02*
X1477549D01*
G01X1479971Y349700D02*
X1477549D01*
G01X1479971Y354200D02*
X1477549D01*
G01X1473900Y433100D02*
Y434756D01*
X1484650Y445506D01*
X1498495D01*
G01X1481925Y685630D02*
X1478710D01*
G01X1481925Y681630D02*
X1478964D01*
X1477597Y682997D01*
G01X1481925Y693630D02*
X1479297D01*
G01X1481925Y706500D02*
X1479500D01*
G01X1471500Y716075D02*
X1474425D01*
G01Y712925D02*
X1474624Y712726D01*
X1489421D01*
X1493075Y709072D01*
Y706500D01*
G01X1474425Y712925D02*
X1471500D01*
G01X1482425Y727500D02*
X1479962D01*
G01X1481925Y750500D02*
X1479500D01*
G01X1482425Y743500D02*
X1479759D01*
G01X1482425Y735500D02*
X1479657D01*
G01X1471500Y760075D02*
X1474425D01*
G01Y756925D02*
X1471500D01*
G01X1468043Y875295D02*
X1472440D01*
X1473468Y874267D01*
G01X1469692Y947600D02*
X1472555D01*
X1474349Y949394D01*
G01X1470925Y972000D02*
X1470681D01*
X1468500Y974181D01*
G01X1474075Y972000D02*
X1474500D01*
X1476500Y974000D01*
G01X1483096Y982956D02*
X1479096D01*
G01D02*
X1475096D01*
G01D02*
X1471096D01*
G01X1467096D02*
X1471096D01*
G01D02*
Y980330D01*
G01X1475096D02*
Y982956D01*
G01X1479096Y995106D02*
Y997860D01*
G01X1471096Y995106D02*
Y997860D01*
G01X1475096Y995106D02*
Y997860D01*
G01X1467096Y995106D02*
Y997860D01*
G01X1465846Y1021177D02*
Y1023900D01*
G01X1468869Y1018469D02*
Y1013972D01*
G01X1480796Y1207882D02*
X1477846Y1204932D01*
G01X1480675Y1202103D02*
Y1202787D01*
X1482941Y1205053D01*
X1483625D01*
G01X1477968Y1210710D02*
X1474287Y1207029D01*
Y1203125D01*
X1478766Y1198646D01*
X1481350D01*
X1482705Y1200001D01*
G01X1477968Y1210710D02*
X1474786Y1213892D01*
G01D02*
X1473762Y1214916D01*
Y1220352D01*
X1476861Y1223451D01*
G01D02*
X1480861D01*
G01X1486884Y1220921D02*
X1483144D01*
X1480861Y1223204D01*
Y1223451D01*
G01X1496197Y15043D02*
X1498621D01*
G01X1496197Y19043D02*
X1498621D01*
G01X1496197Y35043D02*
X1498621D01*
G01X1496197Y27043D02*
X1498621D01*
G01X1496197Y31043D02*
X1498621D01*
G01X1496197Y23043D02*
X1498621D01*
G01X1483287Y91974D02*
Y94374D01*
G01X1490842Y104749D02*
Y102249D01*
G01X1486842Y104749D02*
Y102249D01*
G01X1482842Y104749D02*
Y102249D01*
G01X1498461Y106495D02*
X1495866D01*
G01X1498461Y102495D02*
X1495866D01*
G01X1488867Y130898D02*
Y133298D01*
G01X1493100Y146012D02*
X1495600D01*
G01X1496040Y138838D02*
Y139762D01*
X1497506Y141228D01*
G01X1493100Y142862D02*
X1490519D01*
X1490305Y142648D01*
X1486989D01*
G01X1495600Y142862D02*
X1493100D01*
G01X1496448Y153296D02*
X1499349D01*
X1500394Y152251D01*
Y150847D01*
G01X1492186Y236009D02*
Y238589D01*
G01X1497713Y236121D02*
X1495152D01*
G01X1497466Y242078D02*
X1499947D01*
G01X1495178Y232971D02*
X1497713D01*
G01X1492085Y253198D02*
X1495071D01*
G01X1489971Y358700D02*
X1486360D01*
G01X1489971Y354200D02*
X1486360D01*
G01X1493075Y750500D02*
X1495500D01*
G01X1499425Y769000D02*
X1496473D01*
G01X1499425Y777000D02*
X1496763D01*
G01X1498925Y792000D02*
X1496500D01*
G01X1499425Y785000D02*
X1496756D01*
G01X1488500Y798425D02*
X1486424D01*
X1485967Y797968D01*
X1482016D01*
G01X1491425Y798425D02*
X1488500D01*
G01Y801575D02*
X1491425D01*
G01X1499425Y813000D02*
X1496845D01*
G01X1499425Y829000D02*
X1496621D01*
G01X1499425Y821000D02*
X1496447D01*
G01X1488500Y845575D02*
X1491425D01*
G01X1498925Y836000D02*
X1496500D01*
G01X1488500Y842425D02*
X1486424D01*
X1485967Y841968D01*
X1482016D01*
G01X1491425Y842425D02*
X1488500D01*
G01X1487096Y982956D02*
X1483096D01*
G01X1491096D02*
X1487096D01*
G01X1495096D02*
X1491096D01*
G01X1499096D02*
X1495096D01*
G01X1491096Y995106D02*
Y997860D01*
G01X1483096Y995106D02*
Y997860D01*
G01X1495096Y995106D02*
Y997860D01*
G01X1487096Y995106D02*
Y997860D01*
G01X1482705Y1200001D02*
X1484229D01*
X1486453Y1202225D01*
G01X1492550Y1211541D02*
Y1202152D01*
X1490818Y1200420D01*
X1488272D01*
X1486467Y1202225D01*
X1486453D01*
G01X1503430Y1209183D02*
X1502295Y1208048D01*
X1499756D01*
X1498197Y1209607D01*
G01X1494944Y1217668D02*
X1492471Y1215195D01*
G01X1492550Y1211541D02*
X1486884Y1217207D01*
Y1220921D01*
G01X1492114Y1220496D02*
Y1220497D01*
X1489287Y1223324D01*
G01X1500601Y1212011D02*
X1497773Y1214839D01*
X1497772D01*
G01D02*
X1494474Y1211541D01*
X1492550D01*
G01X1486884Y1220921D02*
X1489287Y1223324D01*
G01X1486460Y1226152D02*
X1486458D01*
X1484055Y1223749D01*
G01X1502645Y97667D02*
X1500210D01*
G01X1509823Y236134D02*
Y238714D01*
G01X1499171Y247292D02*
X1502362D01*
G01X1507128Y250599D02*
Y248698D01*
X1505304Y246874D01*
G01X1511835Y450750D02*
X1507864D01*
G01X1514221Y538775D02*
Y538640D01*
X1511963Y536382D01*
G01D02*
X1510231Y538114D01*
Y538816D01*
G01X1510075Y792000D02*
Y793328D01*
X1506559Y796844D01*
X1504495D01*
G01X1510075Y836000D02*
Y834174D01*
X1510527Y833722D01*
Y833500D01*
G01X1515743Y888133D02*
X1511365D01*
G01X1517310Y968739D02*
X1514000D01*
G01X1514063Y973740D02*
X1510740D01*
G01X1515096Y982956D02*
X1511096D01*
G01X1503096D02*
X1499096D01*
G01X1507096D02*
X1503096D01*
G01X1511096D02*
X1507096D01*
G01Y995106D02*
Y997860D01*
G01X1503096Y995106D02*
Y997860D01*
G01X1511096Y995106D02*
Y997860D01*
G01X1499096Y995106D02*
Y997860D01*
G01X1525523Y558555D02*
Y554555D01*
G01D02*
X1526980D01*
X1527659Y555234D01*
X1528635D01*
G01X1525555Y562567D02*
X1527786D01*
X1528350Y562003D01*
G01X1521685Y637969D02*
Y637119D01*
X1523646Y635158D01*
Y634946D01*
G01D02*
X1524835Y633757D01*
Y631421D01*
G01X1523096Y982956D02*
X1519096D01*
G01D02*
X1515096D01*
G01X1523096D02*
X1525647D01*
X1527096Y984405D01*
G01D02*
Y991956D01*
G01X1531096Y982956D02*
X1528545D01*
X1527096Y984405D01*
G01X1515096Y995106D02*
Y997860D01*
G01X1519096Y995106D02*
Y997860D01*
G01X1523096Y995106D02*
Y997860D01*
G01X1544199Y98551D02*
X1546732D01*
G01X1544199Y101701D02*
X1546732D01*
G01X1547822Y147540D02*
X1545044D01*
G01X1547822Y151540D02*
X1545044D01*
G01X1541283Y354553D02*
Y352053D01*
G01X1538133Y354553D02*
Y352053D01*
G01X1531096Y995106D02*
Y997860D01*
G01X1554282Y101348D02*
Y103783D01*
G01X1550282Y101348D02*
Y103783D01*
G01X1563626Y146461D02*
X1560624D01*
G01X1551792Y141247D02*
X1548816D01*
G01X1556540Y152367D02*
X1559526D01*
G01X1550388Y259535D02*
Y256535D01*
G01X1558388Y259535D02*
Y256535D01*
G01X1549441Y288058D02*
Y290755D01*
G01X1553441Y288058D02*
Y290755D01*
G01X1557441Y288058D02*
Y290755D01*
G01X1561454Y325363D02*
X1563877D01*
G01X1561454Y316363D02*
X1563877D01*
G01X1561454Y329863D02*
X1563877D01*
G01X1561454Y343363D02*
X1563877D01*
G01X1561454Y334363D02*
X1563877D01*
G01X1551454Y352363D02*
X1554403D01*
G01X1561454D02*
X1563877D01*
G01X1574254Y81848D02*
Y85052D01*
X1572293Y87013D01*
Y88801D01*
G01Y91951D02*
X1574851D01*
G01X1572293Y88801D02*
X1574876D01*
G01X1573455Y117261D02*
X1573876Y116840D01*
Y114488D01*
G01X1565449Y107921D02*
Y103621D01*
G01X1571583Y149768D02*
Y152562D01*
G01X1578519Y180665D02*
X1581162D01*
G01X1578611Y225719D02*
Y221867D01*
X1578614Y221864D01*
G01X1571625Y336200D02*
Y333549D01*
G01Y341600D02*
Y344131D01*
G01X1574775Y336200D02*
Y333549D01*
G01X1582437Y335455D02*
X1577628D01*
X1576883Y336200D01*
X1574775D01*
G01X1570640Y424587D02*
X1574539D01*
X1574540Y424586D01*
G01X1569926Y666275D02*
Y668885D01*
G01X1575291Y660402D02*
Y662322D01*
X1575950Y662981D01*
G01X1572141D02*
Y660402D01*
G01X1573076Y666275D02*
X1572612Y666739D01*
Y672360D01*
G01X1573076Y666275D02*
Y663916D01*
X1572141Y662981D01*
G01X1565132Y682006D02*
Y677843D01*
G01X1575192Y710129D02*
Y707592D01*
G01X1582522Y64722D02*
X1582822Y64422D01*
Y60922D01*
G01X1585649Y91974D02*
Y94374D01*
G01X1593204Y104749D02*
Y102249D01*
G01X1585204Y104749D02*
Y102249D01*
G01X1589204Y104749D02*
Y102249D01*
G01X1591229Y130898D02*
Y133298D01*
G01X1583229Y130898D02*
Y133298D01*
G01X1595462Y146012D02*
X1597962D01*
G01X1585376Y134579D02*
X1584925Y135030D01*
X1584892D01*
X1583180Y136742D01*
X1582265D01*
G01X1595462Y142862D02*
X1592881D01*
X1592667Y142648D01*
X1589351D01*
G01X1597962Y142862D02*
X1595462D01*
G01X1580418Y158015D02*
Y160715D01*
X1579827Y161306D01*
G01X1594548Y236009D02*
Y238589D01*
G01X1594447Y253198D02*
X1597433D01*
G01X1585729Y252371D02*
X1582951D01*
G01X1585729Y248371D02*
X1582951D01*
G01X1592835Y549800D02*
X1595460D01*
G01X1598285Y557700D02*
X1596400D01*
X1595300Y558800D01*
G01X1584776Y926608D02*
X1617208D01*
X1619863Y929263D01*
X1645128D01*
G01X1593857Y1446488D02*
X1596836D01*
G01X1594264Y1469940D02*
X1591610D01*
G01X1594312Y1479190D02*
Y1473138D01*
X1594264Y1473090D01*
G01D02*
X1591775D01*
G01X1594312Y1496316D02*
Y1501975D01*
X1594307Y1501980D01*
G01Y1505130D02*
X1591586D01*
G01X1594307Y1501980D02*
X1591333D01*
G01X1594500Y1512075D02*
X1591925D01*
G01X1605007Y97667D02*
X1602572D01*
G01X1600823Y106495D02*
X1598228D01*
G01X1600823Y102495D02*
X1598228D01*
G01X1598402Y138838D02*
Y139762D01*
X1599868Y141228D01*
G01X1598810Y153296D02*
X1601711D01*
X1602756Y152251D01*
Y150847D01*
G01X1601533Y247292D02*
X1604724D01*
G01X1600075Y236121D02*
X1597514D01*
G01X1599828Y242078D02*
X1602309D01*
G01X1609490Y250599D02*
Y248698D01*
X1607666Y246874D01*
G01X1600075Y232971D02*
X1597540D01*
G01X1611872Y336252D02*
Y332632D01*
X1608240Y329000D01*
G01X1599563Y343723D02*
X1602537D01*
X1603664Y342596D01*
G01X1607947Y332326D02*
X1608722Y333101D01*
Y336252D01*
G01D02*
X1608370Y335900D01*
X1606320D01*
X1605875Y335455D01*
X1599563D01*
G01X1598285Y553700D02*
X1596985Y555000D01*
X1595760D01*
G01X1600333Y1443410D02*
Y1440504D01*
G01X1603363Y1463362D02*
Y1460570D01*
G01X1597457Y1456276D02*
Y1452556D01*
G01X1602580Y1479190D02*
Y1483108D01*
G01X1604687Y1471973D02*
X1606745Y1474031D01*
Y1474242D01*
G01X1602441Y1468023D02*
X1605430D01*
G01X1608500Y1512075D02*
Y1515000D01*
G01X1605000Y1512075D02*
X1608500D01*
G01X1610858Y1520240D02*
X1613460D01*
X1614200Y1519500D01*
G01X1600700Y1534300D02*
X1600000D01*
X1598142Y1532442D01*
Y1530460D01*
G01X1612185Y236134D02*
Y238714D01*
G01X1619872Y344252D02*
Y340252D01*
G01D02*
X1625722Y334402D01*
X1629302D01*
G01X1623535Y449873D02*
X1625938D01*
G01X1620385Y458859D02*
Y457597D01*
X1621596Y456386D01*
G01X1623535Y445873D02*
X1625938D01*
G01X1614338Y633786D02*
Y636842D01*
G01X1620244Y640872D02*
Y638125D01*
G01X1617843Y661113D02*
Y665140D01*
G01X1613843Y669913D02*
X1616260Y672330D01*
Y675832D01*
G01X1613110D02*
Y678462D01*
G01X1616260Y675832D02*
Y678462D01*
G01X1627155Y705836D02*
X1626570D01*
X1624148Y708258D01*
G01X1627155Y723736D02*
Y725387D01*
X1628813Y727045D01*
G01X1627455Y738336D02*
X1627479D01*
X1629969Y740826D01*
G01X1627427Y744317D02*
Y746372D01*
X1628343Y747288D01*
G01X1627455Y756536D02*
Y759489D01*
G01X1626727Y762717D02*
X1625817D01*
X1624000Y760900D01*
G01X1616655Y780736D02*
X1617196D01*
X1619612Y783152D01*
G01X1623741Y774830D02*
X1620359D01*
G01X1623541Y787530D02*
X1620755D01*
G01X1619569Y796035D02*
Y795991D01*
X1617014Y793436D01*
X1616455D01*
G01X1616155Y807536D02*
X1614165D01*
X1613235Y808466D01*
G01X1623341Y815730D02*
X1620479D01*
G01X1623241Y801630D02*
X1620072D01*
G01X1631383Y801427D02*
X1628027D01*
G01X1616255Y821636D02*
Y824405D01*
G01X1616427Y828117D02*
X1613117D01*
G01X1615760Y1528558D02*
X1618800D01*
G01X1615460Y1535258D02*
Y1535140D01*
X1618600Y1532000D01*
G01X1619360Y1539358D02*
Y1540726D01*
X1617226Y1542860D01*
X1614360D01*
G01X1641565Y580925D02*
X1637666D01*
X1637665Y580926D01*
G01X1634241Y699930D02*
X1637526D01*
G01X1634241Y717830D02*
X1637472D01*
G01X1631027Y711417D02*
X1628200D01*
G01X1634541Y732430D02*
X1631031D01*
G01X1638427Y728117D02*
X1635283D01*
G01X1634541Y750630D02*
X1631187D01*
G01X1634083Y774627D02*
X1630327D01*
G01X1632583Y787327D02*
X1629927D01*
G01X1635149Y891353D02*
X1644304D01*
G01X1634580Y962120D02*
X1645342D01*
G01X1646561Y98551D02*
X1649094D01*
G01X1646561Y101701D02*
X1649094D01*
G01X1656644Y101348D02*
Y103783D01*
G01X1652644Y101348D02*
Y103783D01*
G01X1650184Y147540D02*
X1647406D01*
G01X1654154Y141247D02*
X1651178D01*
G01X1658902Y152367D02*
X1661888D01*
G01X1650184Y151540D02*
X1647406D01*
G01X1652750Y259535D02*
Y256535D01*
G01X1655803Y288058D02*
Y290755D01*
G01X1651803Y288058D02*
Y290755D01*
G01X1659803Y288058D02*
Y290755D01*
G01X1658200Y317873D02*
Y315039D01*
G01X1676616Y81848D02*
Y85052D01*
X1674655Y87013D01*
Y88801D01*
G01Y91951D02*
X1677213D01*
G01X1674655Y88801D02*
X1677238D01*
G01X1675817Y117261D02*
X1676238Y116840D01*
Y114488D01*
G01X1667811Y107921D02*
Y103621D01*
G01X1665988Y146461D02*
X1662986D01*
G01X1673945Y149768D02*
Y152562D01*
G01X1660750Y259535D02*
Y256535D01*
G01X1684884Y64722D02*
X1685184Y64422D01*
Y60922D01*
G01X1688011Y91974D02*
Y94374D01*
G01X1687566Y104749D02*
Y102249D01*
G01X1691566Y104749D02*
Y102249D01*
G01X1686171Y130898D02*
X1683591D01*
G01X1687738Y134579D02*
X1686790D01*
X1684627Y136742D01*
G01X1697824Y142862D02*
X1695243D01*
X1695029Y142648D01*
X1691713D01*
G01X1682780Y158015D02*
Y160715D01*
X1682189Y161306D01*
G01X1680973Y225719D02*
Y221867D01*
X1680976Y221864D01*
G01X1688091Y252371D02*
X1685313D01*
G01X1688091Y248371D02*
X1685313D01*
G01X1683523Y311740D02*
X1686115D01*
G01X1691534Y336324D02*
X1687164D01*
G01X1691743Y350850D02*
Y353506D01*
G01X1688593Y353470D02*
Y350850D01*
G01X1707369Y97667D02*
X1704934D01*
G01X1695566Y104749D02*
Y102249D01*
G01X1703185Y106495D02*
X1700590D01*
G01X1703185Y102495D02*
X1700590D01*
G01X1693591Y130898D02*
Y133298D01*
G01X1697824Y146012D02*
X1700324D01*
G01X1700764Y138838D02*
Y139762D01*
X1702230Y141228D01*
G01X1700324Y142862D02*
X1697824D01*
G01X1701172Y153296D02*
X1704073D01*
X1705118Y152251D01*
Y150847D01*
G01X1703895Y247292D02*
X1707086D01*
G01X1702437Y236121D02*
X1699876D01*
G01X1696910Y236009D02*
Y238589D01*
G01X1702190Y242078D02*
X1704671D01*
G01X1702437Y232971D02*
X1699902D01*
G01X1696809Y253198D02*
X1699795D01*
G01X1695142Y306652D02*
Y303839D01*
G01X1698292Y303962D02*
Y306652D01*
G01D02*
X1698687Y307047D01*
Y312849D01*
G01X1713545Y565287D02*
X1705449D01*
X1700205Y560043D01*
G01X1708889Y1189221D02*
Y1178900D01*
G01X1703400Y1174400D02*
X1704750Y1175750D01*
X1708889D01*
G01X1714547Y236134D02*
Y238714D01*
G01X1711852Y250599D02*
Y248698D01*
X1710028Y246874D01*
G01X1717746Y379573D02*
Y377153D01*
X1723964Y370935D01*
G01X1721746Y379573D02*
Y377173D01*
G01X1713746Y379573D02*
X1711802D01*
X1710457Y380918D01*
Y383195D01*
X1715228Y387966D01*
G01X1718851Y393933D02*
Y391533D01*
G01X1718710Y447486D02*
Y450334D01*
G01Y458334D02*
X1716310D01*
G01X1717008Y1137129D02*
Y1135347D01*
X1717626Y1134729D01*
G01X1717645Y1153242D02*
Y1146686D01*
X1718260Y1146071D01*
G01X1720960Y1148000D02*
Y1146700D01*
X1720331Y1146071D01*
X1718260D01*
G01X1723974Y1163968D02*
Y1160346D01*
X1723796Y1160168D01*
G01X1721660Y1195419D02*
Y1193019D01*
G01X1721662Y1206593D02*
X1725662D01*
G01X1715726Y1220765D02*
X1715210Y1220249D01*
Y1216063D01*
X1721662Y1209611D01*
Y1206593D01*
G01X1718555Y1223592D02*
X1718553D01*
X1715726Y1220765D01*
G01X1721384Y1226421D02*
X1718555Y1223592D01*
G01X1724213Y1229250D02*
X1721384Y1226421D01*
G01X1733746Y385123D02*
Y382723D01*
G01X1739847Y406616D02*
Y409016D01*
G01X1735811Y406532D02*
Y409032D01*
G01X1739847Y401066D02*
Y403466D01*
G01X1739508Y1137129D02*
X1737008D01*
G01X1737417Y1146937D02*
X1739917D01*
G01Y1150087D02*
X1737417D01*
G01X1732242Y1146842D02*
Y1148404D01*
X1733925Y1150087D01*
X1737417D01*
G01X1737393Y1165217D02*
Y1162817D01*
G01Y1168367D02*
Y1170767D01*
G01X1732242Y1163968D02*
Y1167546D01*
X1733063Y1168367D01*
X1737393D01*
G01X1728333Y1178240D02*
X1725674D01*
G01X1730999Y1178288D02*
X1730951Y1178240D01*
X1728333D01*
G01X1725660Y1195419D02*
Y1193019D01*
G01X1733660Y1195419D02*
Y1193019D01*
G01X1729660Y1195419D02*
Y1193019D01*
G01X1737660Y1195419D02*
Y1193019D01*
G01X1740785Y1219254D02*
X1735967Y1224072D01*
G01X1737781Y1208993D02*
Y1206712D01*
X1737662Y1206593D01*
G01X1725662D02*
X1729662D01*
G01D02*
X1733662D01*
G01D02*
X1737662D01*
G01X1733139Y1221244D02*
X1734392Y1219991D01*
X1735222D01*
X1739024Y1216189D01*
Y1210236D01*
X1737781Y1208993D01*
G01X1748923Y98551D02*
X1751456D01*
G01X1748923Y101701D02*
X1751456D01*
G01X1755006Y101348D02*
Y103783D01*
G01X1755112Y259535D02*
Y256535D01*
G01X1754165Y288058D02*
Y290755D01*
G01X1744524Y372604D02*
Y370010D01*
G01X1748497Y373680D02*
Y371060D01*
G01X1744859Y454309D02*
X1747359D01*
G01X1744859Y458309D02*
X1747359D01*
G01X1744859Y462309D02*
X1747359D01*
G01X1754125Y931100D02*
X1751200D01*
G01X1759274Y1005250D02*
X1756060Y1008464D01*
Y1010750D01*
G01D02*
Y1015240D01*
X1756297Y1015477D01*
G01X1753221Y1618504D02*
X1750685D01*
G01X1753221Y1621654D02*
X1757542D01*
X1758820Y1622932D01*
Y1625223D01*
G01X1750685Y1621654D02*
X1753221D01*
G01X1756422Y1637879D02*
Y1640303D01*
G01X1770173Y107921D02*
Y103621D01*
G01X1759006Y101348D02*
Y103783D01*
G01X1763112Y259535D02*
Y256535D01*
G01X1758165Y288058D02*
Y290755D01*
G01X1762165Y288058D02*
Y290755D01*
G01X1765497Y373481D02*
Y370899D01*
G01X1762503Y466409D02*
X1765097D01*
G01X1770986Y467560D02*
X1768586D01*
G01X1762503Y470382D02*
X1764903D01*
G01X1762503Y487382D02*
X1765083D01*
G01X1770986Y479560D02*
X1768575D01*
G01X1770986Y475560D02*
X1768575D01*
G01X1776778Y818696D02*
X1772768D01*
G01X1760487Y1015477D02*
Y1011874D01*
X1761745Y1010616D01*
G01D02*
X1764999Y1007362D01*
Y1005250D01*
G01X1775948D02*
X1775817Y1005381D01*
Y1008104D01*
X1773278Y1010643D01*
G01D02*
X1771992Y1011929D01*
Y1015477D01*
G01X1765131D02*
Y1012603D01*
X1767133Y1010601D01*
G01D02*
X1770492Y1007242D01*
Y1005250D01*
G01X1774216Y1472725D02*
Y1470165D01*
G01X1773820Y1604357D02*
X1777131D01*
G01X1764422Y1637879D02*
Y1640303D01*
G01X1760422Y1637879D02*
Y1640303D01*
G01X1768422Y1637879D02*
Y1640303D01*
G01X1772422Y1637879D02*
Y1640303D01*
G01X1787246Y64722D02*
Y62968D01*
X1788884Y61330D01*
Y59871D01*
G01X1778978Y81848D02*
Y85052D01*
X1777017Y87013D01*
Y88801D01*
G01Y91951D02*
X1779575D01*
G01X1777017Y88801D02*
X1779600D01*
G01X1778179Y117261D02*
X1778600Y116840D01*
Y114488D01*
G01X1785918Y204864D02*
X1785954Y204900D01*
X1791464D01*
X1792737Y203627D01*
Y200716D01*
G01X1783338Y204864D02*
X1785918D01*
G01X1783335Y225719D02*
Y221867D01*
X1783338Y221864D01*
G01X1783107Y429262D02*
Y426740D01*
G01X1787104Y468607D02*
X1790014D01*
G01X1780018Y474513D02*
X1783014D01*
G01X1776071Y836469D02*
X1778801D01*
G01X1781389Y1005250D02*
X1781327Y1005312D01*
Y1009102D01*
X1779761Y1010668D01*
G01D02*
X1778042Y1012387D01*
Y1015477D01*
G01X1784145D02*
Y1011983D01*
X1785473Y1010655D01*
G01D02*
X1786783Y1009345D01*
Y1005254D01*
X1786779Y1005250D01*
G01X1792278D02*
Y1009278D01*
X1790820Y1010736D01*
G01D02*
X1790035Y1011521D01*
Y1015477D01*
G01X1774339Y1440535D02*
Y1437975D01*
G01X1790264Y1440762D02*
X1793976D01*
G01X1783178Y1446668D02*
X1779868D01*
G01X1778227Y1440533D02*
Y1438099D01*
G01X1790141Y1472952D02*
X1793879D01*
G01X1783055Y1478858D02*
X1786564D01*
G01X1778104Y1472723D02*
Y1470289D01*
G01X1776422Y1637879D02*
Y1640303D01*
G01X1804933Y459176D02*
Y461607D01*
G01X1796933Y459176D02*
Y461607D01*
G01X1796136Y474560D02*
Y471334D01*
G01X1796344Y1015477D02*
Y1010845D01*
X1796594Y1010595D01*
G01D02*
X1797640Y1009549D01*
Y1005330D01*
X1797720Y1005250D01*
G01X1802432Y1015477D02*
Y1010609D01*
G01X1804012Y1004858D02*
X1803760D01*
X1802432Y1006186D01*
Y1010609D01*
G01X1795263Y1103246D02*
X1792863D01*
G01X1795347Y1099210D02*
X1792847D01*
G01X1800813Y1103246D02*
X1798413D01*
G01X1796607Y1202756D02*
Y1200108D01*
G01X1809349Y1205159D02*
X1806544D01*
X1805384Y1206319D01*
G01D02*
X1803383D01*
X1801147Y1208555D01*
G01X1803885Y1437565D02*
Y1435046D01*
G01X1803096Y1444543D02*
X1806428D01*
G01X1803762Y1469755D02*
Y1467236D01*
G01X1802973Y1476733D02*
X1809342D01*
G01X1815008Y452601D02*
X1817439D01*
G01X1815008Y447101D02*
X1817439D01*
G01X1818934Y1010724D02*
Y1012803D01*
X1816260Y1015477D01*
G01X1824814Y1004895D02*
X1824763D01*
X1818934Y1010724D01*
G01X1807688Y1010616D02*
Y1014845D01*
X1808320Y1015477D01*
G01X1811133Y1004858D02*
Y1005212D01*
X1807688Y1008657D01*
Y1010616D01*
G01X1812697Y1010724D02*
Y1015045D01*
X1812265Y1015477D01*
G01X1817965Y1004858D02*
X1812697Y1010126D01*
Y1010724D01*
G01X1808765Y1075688D02*
X1812296D01*
G01X1822306Y1081145D02*
X1824706D01*
G01X1822306Y1085145D02*
X1824706D01*
G01X1822306Y1077145D02*
X1824949D01*
G01X1807946Y1082250D02*
X1810346D01*
G01X1816756Y1097145D02*
X1819156D01*
G01X1828272Y1109146D02*
X1830915D01*
X80290Y1345691D03*
Y1350683D03*
X75334Y1345691D03*
Y1350683D03*
X76112Y1348187D03*
X79512D03*
X80290Y1357603D03*
Y1362595D03*
X75334Y1357603D03*
Y1362595D03*
X76112Y1360099D03*
X79512D03*
X80290Y1381801D03*
Y1369889D03*
Y1374881D03*
X75334Y1381801D03*
Y1374881D03*
Y1369889D03*
X79512Y1372385D03*
X76112D03*
Y1384297D03*
X79512D03*
X80290Y1386793D03*
X75334D03*
X87574Y1345691D03*
Y1350683D03*
X99814D03*
Y1345691D03*
X92530D03*
Y1350683D03*
X88352Y1348187D03*
X91752D03*
X100592D03*
X87574Y1362595D03*
Y1357603D03*
X99814Y1362595D03*
Y1357603D03*
X92530Y1362595D03*
Y1357603D03*
X91752Y1360099D03*
X88352D03*
X100592D03*
X87574Y1374881D03*
Y1369795D03*
Y1381801D03*
X99814D03*
Y1374881D03*
Y1369889D03*
X92530Y1374881D03*
Y1369795D03*
Y1381801D03*
X100592Y1384297D03*
Y1372385D03*
X91752D03*
X88352D03*
Y1384297D03*
X91752D03*
X87574Y1399079D03*
Y1393993D03*
Y1386793D03*
X99814Y1399079D03*
Y1394087D03*
Y1386793D03*
X92530Y1393993D03*
Y1399079D03*
Y1386793D03*
X91752Y1396583D03*
X88352D03*
X100592D03*
X87574Y1410991D03*
Y1405999D03*
X99814Y1410991D03*
Y1405999D03*
X92530Y1410991D03*
Y1405999D03*
X91752Y1408495D03*
X88352D03*
X100592D03*
X104770Y1350683D03*
Y1345691D03*
X112054D03*
Y1350683D03*
X117010Y1345691D03*
Y1350683D03*
X116232Y1348187D03*
X112832D03*
X103992D03*
X104770Y1362595D03*
Y1357603D03*
X112054Y1362595D03*
Y1357603D03*
X117010Y1362595D03*
Y1357603D03*
X112832Y1360099D03*
X116232D03*
X103992D03*
X117010Y1369889D03*
Y1374881D03*
Y1381801D03*
X104770D03*
Y1374881D03*
Y1369889D03*
X112054D03*
Y1374881D03*
Y1381801D03*
X103992Y1372385D03*
Y1384297D03*
X112832D03*
X116232Y1372385D03*
Y1384297D03*
X112832Y1372385D03*
X104770Y1399079D03*
Y1394087D03*
Y1386793D03*
X112054Y1399079D03*
Y1394087D03*
Y1386793D03*
X117010Y1394087D03*
Y1399079D03*
Y1386793D03*
X116232Y1396583D03*
X112832D03*
X103992D03*
X104770Y1410991D03*
Y1405999D03*
X112054Y1410991D03*
Y1405999D03*
X117010Y1410991D03*
Y1405999D03*
X112832Y1408495D03*
X116232D03*
X103992D03*
X124294Y1350683D03*
Y1345691D03*
X129250Y1350683D03*
Y1345691D03*
X125072Y1348187D03*
X128472D03*
X124294Y1362595D03*
Y1357603D03*
X129250D03*
Y1362595D03*
X128472Y1360099D03*
X125072D03*
X124294Y1374881D03*
Y1369889D03*
Y1381801D03*
X129250Y1374881D03*
Y1369889D03*
Y1381801D03*
X125072Y1384297D03*
X128472D03*
X125072Y1372385D03*
X128472D03*
X124294Y1394087D03*
Y1399079D03*
Y1386793D03*
X129250Y1394087D03*
Y1399079D03*
Y1386793D03*
X125072Y1396583D03*
X128472D03*
X124294Y1405999D03*
Y1410991D03*
X129250Y1405999D03*
Y1410991D03*
X125072Y1408495D03*
X128472D03*
X148818Y1075196D03*
Y1078936D03*
X145078D03*
X148818Y1086417D03*
X145078D03*
X148818Y1090157D03*
X145078D03*
X148818Y1082677D03*
X145078D03*
X148818Y1093897D03*
X145078D03*
X148818Y1097637D03*
X145078D03*
X148818Y1105117D03*
X145078D03*
X148818Y1101377D03*
X145078D03*
X148818Y1112598D03*
X145078D03*
X148818Y1120078D03*
X145078D03*
X148818Y1108858D03*
Y1116338D03*
Y1123818D03*
X145078Y1108858D03*
Y1116338D03*
Y1123818D03*
X148818Y1127558D03*
X145078D03*
X148818Y1135039D03*
X145078D03*
X148818Y1131299D03*
Y1138779D03*
X145078Y1131299D03*
Y1138779D03*
X148818Y1142519D03*
X145078D03*
X148818Y1146259D03*
X145078D03*
X148818Y1153740D03*
X145078D03*
X148818Y1149999D03*
X145078D03*
X148818Y1161220D03*
X145078D03*
X148818Y1168700D03*
X145078D03*
X148818Y1157480D03*
X145078D03*
X148818Y1164960D03*
X145078D03*
X148818Y1172440D03*
X145078D03*
X148818Y1183661D03*
X145078D03*
X148818Y1187401D03*
X145078D03*
X148818Y1176180D03*
X145078D03*
X148818Y1179921D03*
X145078D03*
X148818Y1194881D03*
X145078D03*
X148818Y1202362D03*
X145078D03*
X148818Y1198621D03*
Y1191141D03*
X145078Y1198621D03*
Y1191141D03*
X148818Y1209842D03*
X145078D03*
X148818Y1217322D03*
X145078D03*
X148818Y1221062D03*
Y1213582D03*
Y1206102D03*
X145078Y1221062D03*
Y1213582D03*
Y1206102D03*
X148818Y1224803D03*
X145078D03*
X148818Y1232283D03*
X145078D03*
X148818Y1236023D03*
X145078D03*
X148818Y1228543D03*
X145078D03*
X148818Y1243503D03*
X145078D03*
X148818Y1250984D03*
X145078D03*
X148818Y1239763D03*
X145078D03*
X148818Y1247243D03*
X145078D03*
X148818Y1254724D03*
X141490Y1345691D03*
Y1350683D03*
X136534D03*
Y1345691D03*
X148774Y1350683D03*
Y1345691D03*
X140712Y1348187D03*
X137312D03*
X149552D03*
X141490Y1357603D03*
Y1362595D03*
X136534D03*
Y1357603D03*
X148774D03*
Y1362595D03*
X137312Y1360099D03*
X140712D03*
X149552D03*
Y1384297D03*
X141490Y1369889D03*
Y1374881D03*
Y1381801D03*
X136534Y1369889D03*
Y1381801D03*
Y1374881D03*
X148774Y1369889D03*
Y1381801D03*
Y1374881D03*
X149552Y1372385D03*
X140712D03*
Y1384297D03*
X137312D03*
Y1372385D03*
X141490Y1386793D03*
Y1394087D03*
Y1399079D03*
X136534D03*
Y1394087D03*
Y1386793D03*
X148774Y1394087D03*
Y1399079D03*
Y1386793D03*
X140712Y1396583D03*
X137312D03*
X149552D03*
X140712Y1408495D03*
X137312D03*
X141490Y1405999D03*
Y1410991D03*
X136534D03*
Y1405999D03*
X148774D03*
Y1410991D03*
X149552Y1408495D03*
X163779Y1075196D03*
X156299D03*
X160039D03*
X152559D03*
X163779Y1078936D03*
X156299D03*
X160039Y1082677D03*
X152559D03*
X160039Y1086417D03*
X152559D03*
X163779Y1090157D03*
X160039D03*
X156299D03*
X152559D03*
X163779Y1086417D03*
X160039Y1078936D03*
X156299Y1086417D03*
X152559Y1078936D03*
X163779Y1082677D03*
X156299D03*
X163779Y1093897D03*
X156299D03*
X163779Y1097637D03*
X156299D03*
X160039Y1101377D03*
X152559D03*
X160039Y1105117D03*
X152559D03*
X163779D03*
X160039Y1097637D03*
X156299Y1105117D03*
X152559Y1097637D03*
X163779Y1101377D03*
X160039Y1093897D03*
X156299Y1101377D03*
X152559Y1093897D03*
X163779Y1108858D03*
X160039D03*
X156299D03*
X152559D03*
X160039Y1112598D03*
X163779Y1116338D03*
X160039D03*
X156299D03*
X152559D03*
X160039Y1120078D03*
X163779Y1123818D03*
X160039D03*
X156299D03*
X152559D03*
X163779Y1112598D03*
Y1120078D03*
X156299Y1112598D03*
Y1120078D03*
X152559Y1112598D03*
Y1120078D03*
X160039Y1127558D03*
X163779Y1131299D03*
X160039D03*
X156299D03*
X152559D03*
X160039Y1135039D03*
X163779Y1138779D03*
X160039D03*
X156299D03*
X152559D03*
X163779Y1127558D03*
Y1135039D03*
X156299Y1127558D03*
Y1135039D03*
X152559Y1127558D03*
Y1135039D03*
X163779Y1142519D03*
X160039D03*
X156299D03*
X152559D03*
X163779Y1146259D03*
X152559D03*
X163779Y1149999D03*
X160039D03*
X156299D03*
X152559D03*
X163779Y1153740D03*
X152559D03*
X156299Y1146259D03*
X160039D03*
Y1153740D03*
X156299D03*
X163779Y1157480D03*
X160039D03*
X156299D03*
X152559D03*
X163779Y1161220D03*
X152559D03*
X163779Y1164960D03*
X160039D03*
X156299D03*
X152559D03*
X163779Y1168700D03*
X152559D03*
X163779Y1172440D03*
X160039D03*
X156299D03*
X152559D03*
X160039Y1161220D03*
X156299D03*
X160039Y1168700D03*
X156299D03*
X163779Y1183661D03*
X160039D03*
X156299D03*
X152559D03*
X160039Y1187401D03*
X163779Y1176180D03*
X152559D03*
X163779Y1179921D03*
X160039D03*
X156299D03*
X152559D03*
X160039Y1176180D03*
X156299D03*
X163779Y1187401D03*
X156299D03*
X152559D03*
X163779Y1191141D03*
X160039D03*
X156299D03*
X152559D03*
X160039Y1194881D03*
X163779Y1198621D03*
X160039D03*
X156299D03*
X152559D03*
X160039Y1202362D03*
X163779D03*
Y1194881D03*
X156299Y1202362D03*
Y1194881D03*
X152559Y1202362D03*
Y1194881D03*
X163779Y1206102D03*
X160039D03*
X156299D03*
X152559D03*
X160039Y1209842D03*
X163779Y1213582D03*
X160039D03*
X156299D03*
X152559D03*
X160039Y1217322D03*
X163779Y1221062D03*
X160039D03*
X156299D03*
X152559D03*
X163779Y1217322D03*
Y1209842D03*
X156299Y1217322D03*
Y1209842D03*
X152559Y1217322D03*
Y1209842D03*
X160039Y1224803D03*
X152559D03*
X160039Y1228543D03*
X152559D03*
X163779Y1232283D03*
X156299D03*
X163779Y1236023D03*
X156299D03*
X163779Y1224803D03*
X160039Y1232283D03*
X156299Y1224803D03*
X152559Y1232283D03*
X163779Y1228543D03*
X160039Y1236023D03*
X156299Y1228543D03*
X152559Y1236023D03*
X163779Y1239763D03*
X160039D03*
X156299D03*
X152559D03*
X160039Y1243503D03*
X152559D03*
X160039Y1247243D03*
X152559D03*
X163779Y1250984D03*
X156299D03*
X163779Y1243503D03*
X160039Y1250984D03*
X156299Y1243503D03*
X152559Y1250984D03*
X163779Y1247243D03*
X156299D03*
X163779Y1254724D03*
X156299D03*
X160039D03*
X152559D03*
X161014Y1345691D03*
Y1350683D03*
X153730Y1345691D03*
Y1350683D03*
X165970Y1345691D03*
Y1350683D03*
X165192Y1348187D03*
X161792D03*
X152952D03*
X165192Y1360099D03*
X161792D03*
X161014Y1362595D03*
Y1357603D03*
X153730Y1362595D03*
Y1357603D03*
X165970Y1362595D03*
Y1357603D03*
X152952Y1360099D03*
Y1384297D03*
X161014Y1381801D03*
Y1369889D03*
Y1374881D03*
X153730Y1369889D03*
Y1381801D03*
Y1374881D03*
X165970D03*
Y1381801D03*
Y1369889D03*
X152952Y1372385D03*
X161792Y1384297D03*
X165192Y1372385D03*
Y1384297D03*
X161792Y1372385D03*
X161014Y1394087D03*
Y1386793D03*
X153730Y1394087D03*
Y1386793D03*
X165970Y1394087D03*
Y1386793D03*
X161014Y1399079D03*
X153730D03*
X165970D03*
X165192Y1396583D03*
X161792D03*
X152952D03*
X165192Y1408495D03*
X161792D03*
X161014Y1410991D03*
Y1405999D03*
X153730D03*
Y1410991D03*
X165970D03*
Y1405999D03*
X152952Y1408495D03*
X171259Y1075196D03*
X178740D03*
X167519D03*
X174999D03*
X182480D03*
X171259Y1078936D03*
X178740D03*
X174999Y1082677D03*
X167519D03*
X182480D03*
X174999Y1086417D03*
X167519D03*
X182480D03*
X174999Y1090157D03*
X171259D03*
X167519D03*
X182480D03*
X178740D03*
X171259Y1086417D03*
X167519Y1078936D03*
X171259Y1082677D03*
X174999Y1078936D03*
X178740Y1086417D03*
X182480Y1078936D03*
X178740Y1082677D03*
X171259Y1093897D03*
X178740D03*
X171259Y1097637D03*
X178740D03*
X174999Y1101377D03*
X167519D03*
X182480D03*
X174999Y1105117D03*
X167519D03*
X182480D03*
X171259D03*
X167519Y1097637D03*
X171259Y1101377D03*
X167519Y1093897D03*
X174999Y1097637D03*
X178740Y1105117D03*
X182480Y1097637D03*
X174999Y1093897D03*
X178740Y1101377D03*
X182480Y1093897D03*
X174999Y1108858D03*
X171259D03*
X167519D03*
X182480D03*
X178740D03*
X174999Y1112598D03*
X171259D03*
X182480D03*
X178740D03*
X167519Y1116338D03*
X182480D03*
X178740D03*
X174999Y1120078D03*
X171259D03*
X182480D03*
X178740D03*
X167519Y1123818D03*
X182480D03*
X178740D03*
X167519Y1112598D03*
X174999Y1116338D03*
X167519Y1120078D03*
X174999Y1123818D03*
X171259Y1116338D03*
Y1123818D03*
X174999Y1127558D03*
X171259D03*
X182480D03*
X178740D03*
X167519Y1131299D03*
X182480D03*
X178740D03*
X174999Y1135039D03*
X171259D03*
X182480D03*
X178740D03*
X167519Y1138779D03*
X182480D03*
X178740D03*
X167519Y1127558D03*
X174999Y1131299D03*
X167519Y1135039D03*
X174999Y1138779D03*
X171259Y1131299D03*
Y1138779D03*
X174999Y1142519D03*
X171259D03*
X167519D03*
X182480D03*
X178740D03*
X174999Y1146259D03*
X171259D03*
X182480D03*
X174999Y1149999D03*
X182480D03*
X174999Y1153740D03*
X182480D03*
X178740Y1146259D03*
Y1149999D03*
Y1153740D03*
X171259D03*
X167519Y1149999D03*
X171259D03*
X167519Y1146259D03*
Y1153740D03*
X174999Y1157480D03*
X182480D03*
X178740D03*
X174999Y1161220D03*
X182480D03*
X174999Y1164960D03*
X182480D03*
X174999Y1168700D03*
X182480D03*
X178740D03*
X174999Y1172440D03*
X182480D03*
X178740D03*
Y1161220D03*
Y1164960D03*
X171259D03*
Y1172440D03*
Y1168700D03*
X167519Y1172440D03*
Y1168700D03*
Y1164960D03*
X171259Y1157480D03*
Y1161220D03*
X167519D03*
Y1157480D03*
X174999Y1183661D03*
X171259D03*
X167519D03*
X182480D03*
X178740D03*
X174999Y1187401D03*
X171259D03*
X182480D03*
X178740D03*
X174999Y1176180D03*
X182480D03*
X174999Y1179921D03*
X171259D03*
X167519D03*
X182480D03*
X178740Y1176180D03*
Y1179921D03*
X167519Y1176180D03*
X171259D03*
X167519Y1187401D03*
Y1191141D03*
X182480D03*
X178740D03*
X174999Y1194881D03*
X171259D03*
X182480D03*
X178740D03*
X167519Y1198621D03*
X182480D03*
X178740D03*
X174999Y1202362D03*
X171259D03*
X182480D03*
X178740D03*
X167519D03*
X174999Y1198621D03*
X167519Y1194881D03*
X174999Y1191141D03*
X171259Y1198621D03*
Y1191141D03*
X167519Y1206102D03*
X182480D03*
X178740D03*
X174999Y1209842D03*
X171259D03*
X182480D03*
X178740D03*
X167519Y1213582D03*
X182480D03*
X178740D03*
X174999Y1217322D03*
X171259D03*
X182480D03*
X178740D03*
X174999Y1221062D03*
X171259D03*
X167519D03*
X182480D03*
X178740D03*
X167519Y1217322D03*
X174999Y1213582D03*
X167519Y1209842D03*
X174999Y1206102D03*
X171259Y1213582D03*
Y1206102D03*
X174999Y1224803D03*
X167519D03*
X182480D03*
X174999Y1228543D03*
X167519D03*
X182480D03*
X171259Y1232283D03*
X178740D03*
X171259Y1236023D03*
X178740D03*
X167519Y1232283D03*
Y1236023D03*
X171259Y1224803D03*
X174999Y1232283D03*
X178740Y1224803D03*
X182480Y1232283D03*
X171259Y1228543D03*
X174999Y1236023D03*
X178740Y1228543D03*
X182480Y1236023D03*
X174999Y1239763D03*
X171259D03*
X167519D03*
X182480D03*
X178740D03*
X174999Y1243503D03*
X167519D03*
X182480D03*
X174999Y1247243D03*
X167519D03*
X182480D03*
X171259Y1250984D03*
X178740D03*
X167519D03*
X171259Y1243503D03*
X174999Y1250984D03*
X178740Y1243503D03*
X182480Y1250984D03*
X171259Y1247243D03*
X178740D03*
X171259Y1254724D03*
X178740D03*
X167519D03*
X174999D03*
X182480D03*
X173254Y1345691D03*
Y1350683D03*
X178210Y1345691D03*
Y1350683D03*
X177432Y1348187D03*
X174032D03*
X173254Y1362595D03*
Y1357603D03*
X178210D03*
Y1362595D03*
X174032Y1360099D03*
X177432D03*
Y1384297D03*
X174032D03*
X173254Y1374881D03*
Y1369889D03*
Y1381801D03*
X178210Y1374881D03*
Y1369889D03*
Y1381801D03*
X174032Y1372385D03*
X177432D03*
X173254Y1394087D03*
Y1386793D03*
X178210Y1394087D03*
Y1386793D03*
X173254Y1399079D03*
X178210D03*
X177432Y1396583D03*
X174032D03*
X173254Y1405999D03*
Y1410991D03*
X178210Y1405999D03*
Y1410991D03*
X177432Y1408495D03*
X174032D03*
X193700Y1075196D03*
X186220D03*
X189960D03*
X197440D03*
X193700Y1078936D03*
X186220D03*
X197440Y1082677D03*
X189960D03*
X197440Y1086417D03*
X189960D03*
X197440Y1090157D03*
X193700D03*
X189960D03*
X186220D03*
Y1086417D03*
X189960Y1078936D03*
X193700Y1086417D03*
X197440Y1078936D03*
X186220Y1082677D03*
X193700D03*
Y1093897D03*
X186220D03*
X193700Y1097637D03*
X186220D03*
X197440Y1101377D03*
X189960D03*
X197440Y1105117D03*
X189960D03*
X186220D03*
X189960Y1097637D03*
X193700Y1105117D03*
X197440Y1097637D03*
X186220Y1101377D03*
X189960Y1093897D03*
X193700Y1101377D03*
X197440Y1093897D03*
Y1108858D03*
X193700D03*
X189960D03*
X186220D03*
X197440Y1120078D03*
X193700D03*
X189960D03*
X186220D03*
X197440Y1123818D03*
X193700D03*
X189960D03*
X186220D03*
X189960Y1116338D03*
X186220D03*
Y1112598D03*
X189960D03*
X193700Y1116338D03*
Y1112598D03*
X197440Y1116338D03*
Y1112598D03*
Y1127558D03*
X193700D03*
X189960D03*
X186220D03*
X197440Y1131299D03*
X189960D03*
X186220D03*
X197440Y1135039D03*
X189960D03*
X186220D03*
X197440Y1138779D03*
X189960D03*
X186220D03*
X193700D03*
Y1131299D03*
Y1135039D03*
X186220Y1149999D03*
X189960Y1153740D03*
Y1142519D03*
X186220D03*
X197440Y1146259D03*
X189960D03*
X193700Y1149999D03*
X197440Y1153740D03*
X193700Y1142519D03*
X197440D03*
X186220Y1146259D03*
X189960Y1149999D03*
X186220Y1153740D03*
X193700Y1146259D03*
X197440Y1149999D03*
X193700Y1153740D03*
X186220Y1157480D03*
X189960Y1161220D03*
X186220Y1164960D03*
X189960Y1168700D03*
X186220Y1172440D03*
X193700Y1157480D03*
X197440Y1161220D03*
X193700Y1164960D03*
X197440Y1168700D03*
X193700Y1172440D03*
X189960D03*
Y1157480D03*
X186220Y1161220D03*
X189960Y1164960D03*
X186220Y1168700D03*
X197440Y1157480D03*
X193700Y1161220D03*
X197440Y1164960D03*
X193700Y1168700D03*
X197440Y1172440D03*
X189960Y1176180D03*
X186220Y1179921D03*
X197440Y1183661D03*
X189960D03*
X197440Y1187401D03*
X193700D03*
X189960D03*
X186220D03*
X197440Y1176180D03*
X193700Y1179921D03*
X186220Y1183661D03*
Y1176180D03*
X189960Y1179921D03*
X193700Y1183661D03*
Y1176180D03*
X197440Y1179921D03*
Y1191141D03*
X189960D03*
X186220D03*
X197440Y1194881D03*
X189960D03*
X186220D03*
X197440Y1198621D03*
X189960D03*
X186220D03*
X197440Y1202362D03*
X193700D03*
X189960D03*
X186220D03*
X193700Y1191141D03*
Y1198621D03*
Y1194881D03*
X197440Y1206102D03*
X193700D03*
X189960D03*
X186220D03*
X197440Y1209842D03*
X193700D03*
X189960D03*
X186220D03*
X193700Y1213582D03*
X186220D03*
X193700Y1217322D03*
X197440Y1221062D03*
X193700D03*
X189960D03*
X186220D03*
X189960Y1217322D03*
X186220D03*
X197440Y1213582D03*
Y1217322D03*
X189960Y1213582D03*
X197440Y1224803D03*
X189960D03*
X197440Y1228543D03*
X189960D03*
X193700Y1232283D03*
X186220D03*
X193700Y1236023D03*
X186220D03*
Y1224803D03*
X189960Y1232283D03*
X193700Y1224803D03*
X197440Y1232283D03*
X186220Y1228543D03*
X189960Y1236023D03*
X193700Y1228543D03*
X197440Y1236023D03*
Y1239763D03*
X193700D03*
X189960D03*
X186220D03*
X197440Y1243503D03*
X189960D03*
X197440Y1247243D03*
X189960D03*
X193700Y1250984D03*
X186220D03*
Y1243503D03*
X189960Y1250984D03*
X193700Y1243503D03*
X197440Y1250984D03*
X186220Y1247243D03*
X193700D03*
Y1254724D03*
X186220D03*
X189960D03*
X197440D03*
X185494Y1345597D03*
Y1350683D03*
X190450Y1345597D03*
Y1350683D03*
X197734Y1345691D03*
Y1350683D03*
X189672Y1348187D03*
X186272D03*
X198512D03*
X189672Y1360099D03*
X186272D03*
X185494Y1362595D03*
Y1357603D03*
X197734Y1362595D03*
Y1357603D03*
X190450Y1362595D03*
Y1357603D03*
X198512Y1360099D03*
Y1384297D03*
X185494Y1374881D03*
Y1381801D03*
Y1369889D03*
X197734D03*
Y1381801D03*
Y1374881D03*
X190450Y1369889D03*
Y1374881D03*
Y1381801D03*
X198512Y1372385D03*
X186272Y1384297D03*
X189672D03*
Y1372385D03*
X186272D03*
X185494Y1393993D03*
Y1386793D03*
X190450Y1393993D03*
Y1386793D03*
X197734Y1394087D03*
Y1386793D03*
X185494Y1399079D03*
X190450D03*
X197734D03*
X186272Y1396583D03*
X189672D03*
X198512D03*
X189672Y1408495D03*
X186272D03*
X185494Y1410991D03*
Y1405999D03*
X190450Y1410991D03*
Y1405999D03*
X197734D03*
Y1410991D03*
X198512Y1408495D03*
X208661Y1075196D03*
X201181D03*
X204921D03*
X212401D03*
X208661Y1078936D03*
X201181D03*
X212401Y1082677D03*
X204921D03*
X212401Y1086417D03*
X204921D03*
X212401Y1090157D03*
X208661D03*
X204921D03*
X201181D03*
Y1086417D03*
X204921Y1078936D03*
X208661Y1086417D03*
X212401Y1078936D03*
X201181Y1082677D03*
X208661D03*
Y1093897D03*
X201181D03*
X208661Y1097637D03*
X201181D03*
X212401Y1101377D03*
X204921D03*
X212401Y1105117D03*
X204921D03*
X201181D03*
X204921Y1097637D03*
X208661Y1105117D03*
X212401Y1097637D03*
X201181Y1101377D03*
X204921Y1093897D03*
X208661Y1101377D03*
X212401Y1093897D03*
Y1108858D03*
X208661D03*
X204921D03*
X201181D03*
X212401Y1120078D03*
X208661D03*
X204921D03*
X201181D03*
X212401Y1123818D03*
X208661D03*
X204921D03*
X201181D03*
Y1112598D03*
X204921Y1116338D03*
X201181D03*
X204921Y1112598D03*
X208661Y1116338D03*
Y1112598D03*
X212401Y1116338D03*
Y1112598D03*
Y1127558D03*
X208661D03*
X204921D03*
X201181D03*
X212401Y1135039D03*
X208661D03*
X204921D03*
X201181D03*
X212401Y1131299D03*
X208661D03*
X204921D03*
X201181D03*
X212401Y1138779D03*
X208661D03*
X204921D03*
X201181D03*
X212401Y1142519D03*
X208661D03*
X204921D03*
X201181D03*
X212401Y1149999D03*
X208661D03*
X204921D03*
X201181D03*
X212401Y1146259D03*
X208661D03*
X204921D03*
X201181D03*
X212401Y1153740D03*
X208661D03*
X204921D03*
X201181D03*
X208661Y1157480D03*
X201181D03*
X212401Y1161220D03*
X204921D03*
X208661Y1164960D03*
X201181D03*
X212401Y1168700D03*
X204921D03*
X208661Y1172440D03*
X201181D03*
X212401Y1157480D03*
X204921D03*
X208661Y1161220D03*
X201181D03*
X212401Y1164960D03*
X204921D03*
X208661Y1168700D03*
X201181D03*
X212401Y1172440D03*
X204921D03*
X212401Y1187401D03*
X208661D03*
X204921D03*
X201181D03*
X212401Y1179921D03*
X208661D03*
X204921D03*
X201181D03*
X212401Y1183661D03*
X208661D03*
X204921D03*
X201181D03*
X212401Y1176180D03*
X208661D03*
X204921D03*
X201181D03*
X212401Y1194881D03*
X208661D03*
X204921D03*
X201181D03*
X212401Y1202362D03*
X208661D03*
X204921D03*
X201181D03*
X212401Y1198621D03*
X208661D03*
X204921D03*
X201181D03*
X212401Y1191141D03*
X208661D03*
X204921D03*
X201181D03*
X212401Y1206102D03*
X208661D03*
X204921D03*
X201181D03*
X212401Y1209842D03*
X208661D03*
X204921D03*
X201181D03*
X212401Y1221062D03*
X208661D03*
X204921D03*
X201181D03*
X204921Y1213582D03*
X201181D03*
X212401D03*
X208661Y1217322D03*
Y1213582D03*
X212401Y1217322D03*
X204921D03*
X201181D03*
X212401Y1224803D03*
X204921D03*
X212401Y1228543D03*
X204921D03*
X208661Y1232283D03*
X201181D03*
X208661Y1236023D03*
X201181D03*
Y1224803D03*
X204921Y1232283D03*
X208661Y1224803D03*
X212401Y1232283D03*
X201181Y1228543D03*
X204921Y1236023D03*
X208661Y1228543D03*
X212401Y1236023D03*
Y1239763D03*
X208661D03*
X204921D03*
X201181D03*
X212401Y1243503D03*
X204921D03*
X212401Y1247243D03*
X204921D03*
X208661Y1250984D03*
X201181D03*
Y1243503D03*
X204921Y1250984D03*
X208661Y1243503D03*
X212401Y1250984D03*
X201181Y1247243D03*
X208661D03*
Y1254724D03*
X201181D03*
X204921D03*
X212401D03*
X202690Y1345597D03*
Y1350683D03*
X201912Y1348187D03*
X202690Y1362595D03*
Y1357603D03*
X201912Y1360099D03*
Y1384297D03*
X202690Y1369889D03*
Y1381801D03*
Y1374881D03*
X201912Y1372385D03*
X202690Y1394087D03*
Y1386793D03*
Y1399079D03*
X201912Y1396583D03*
X202690Y1405999D03*
Y1410991D03*
X201912Y1408495D03*
X211473Y1446675D03*
Y1451631D03*
Y1462631D03*
Y1457675D03*
X231102Y1075196D03*
X223622D03*
X216141D03*
X219881D03*
X227362D03*
X231102Y1078936D03*
X223622D03*
X216141D03*
X227362Y1082677D03*
X219881D03*
X227362Y1086417D03*
X219881D03*
X231102Y1090157D03*
X227362D03*
X223622D03*
X219881D03*
X216141D03*
Y1086417D03*
X219881Y1078936D03*
X223622Y1086417D03*
X227362Y1078936D03*
X231102Y1086417D03*
X216141Y1082677D03*
X223622D03*
X231102D03*
Y1093897D03*
X223622D03*
X216141D03*
X231102Y1097637D03*
X223622D03*
X216141D03*
X227362Y1101377D03*
X219881D03*
X227362Y1105117D03*
X219881D03*
X216141D03*
X219881Y1097637D03*
X223622Y1105117D03*
X227362Y1097637D03*
X231102Y1105117D03*
X216141Y1101377D03*
X219881Y1093897D03*
X223622Y1101377D03*
X227362Y1093897D03*
X231102Y1101377D03*
Y1108858D03*
X227362D03*
X223622D03*
X219881D03*
X216141D03*
X231102Y1112598D03*
X216141D03*
X231102Y1116338D03*
X216141D03*
X231102Y1120078D03*
X227362D03*
X223622D03*
X219881D03*
X216141D03*
X231102Y1123818D03*
X227362D03*
X223622D03*
X219881D03*
X216141D03*
X227362Y1116338D03*
X223622Y1112598D03*
Y1116338D03*
X219881D03*
Y1112598D03*
X227362D03*
X231102Y1127558D03*
X227362D03*
X223622D03*
X219881D03*
X216141D03*
X231102Y1135039D03*
X227362D03*
X223622D03*
X219881D03*
X216141D03*
X231102Y1131299D03*
X227362D03*
X223622D03*
X219881D03*
X216141D03*
X231102Y1138779D03*
X227362D03*
X223622D03*
X219881D03*
X216141D03*
X231102Y1142519D03*
X227362D03*
X223622D03*
X219881D03*
X216141D03*
X231102Y1149999D03*
X227362D03*
X223622D03*
X219881D03*
X216141D03*
X231102Y1146259D03*
X227362D03*
X223622D03*
X219881D03*
X216141D03*
X231102Y1153740D03*
X227362D03*
X223622D03*
X219881D03*
X216141D03*
X231102Y1157480D03*
X223622D03*
X216141D03*
X227362Y1161220D03*
X219881D03*
X231102Y1164960D03*
X223622D03*
X216141D03*
X227362Y1168700D03*
X219881D03*
X231102Y1172440D03*
X223622D03*
X216141D03*
X227362Y1157480D03*
X219881D03*
X231102Y1161220D03*
X223622D03*
X216141D03*
X227362Y1164960D03*
X219881D03*
X231102Y1168700D03*
X223622D03*
X216141D03*
X227362Y1172440D03*
X219881D03*
X231102Y1187401D03*
X227362D03*
X223622D03*
X219881D03*
X216141D03*
X231102Y1179921D03*
X227362D03*
X223622D03*
X219881D03*
X216141D03*
X231102Y1183661D03*
X227362D03*
X223622D03*
X219881D03*
X216141D03*
X231102Y1176180D03*
X227362D03*
X223622D03*
X219881D03*
X216141D03*
X231102Y1194881D03*
X227362D03*
X223622D03*
X219881D03*
X216141D03*
X231102Y1202362D03*
X227362D03*
X223622D03*
X219881D03*
X216141D03*
X231102Y1198621D03*
X227362D03*
X223622D03*
X219881D03*
X216141D03*
X231102Y1191141D03*
X227362D03*
X223622D03*
X219881D03*
X216141D03*
X231102Y1206102D03*
X227362D03*
X223622D03*
X219881D03*
X216141D03*
X231102Y1209842D03*
X227362D03*
X223622D03*
X219881D03*
X216141D03*
X219881Y1213582D03*
Y1217322D03*
X231102Y1221062D03*
X227362D03*
X223622D03*
X219881D03*
X216141D03*
X231102Y1213582D03*
X227362Y1217322D03*
Y1213582D03*
X223622D03*
Y1217322D03*
X231102D03*
X216141D03*
Y1213582D03*
X227362Y1224803D03*
X219881D03*
X227362Y1228543D03*
X219881D03*
X231102Y1232283D03*
X223622D03*
X216141D03*
X231102Y1236023D03*
X223622D03*
X216141D03*
Y1224803D03*
X219881Y1232283D03*
X223622Y1224803D03*
X227362Y1232283D03*
X216141Y1228543D03*
X219881Y1236023D03*
X223622Y1228543D03*
X227362Y1236023D03*
X231102Y1224803D03*
Y1228543D03*
Y1239763D03*
X227362D03*
X223622D03*
X219881D03*
X216141D03*
X227362Y1243503D03*
X219881D03*
X227362Y1247243D03*
X219881D03*
X231102Y1250984D03*
X223622D03*
X216141D03*
Y1243503D03*
X219881Y1250984D03*
X223622Y1243503D03*
X227362Y1250984D03*
X216141Y1247243D03*
X223622D03*
X231102Y1243503D03*
Y1247243D03*
Y1254724D03*
X223622D03*
X216141D03*
X219881D03*
X227362D03*
X216465Y1446675D03*
X229745D03*
X224753D03*
X216465Y1451631D03*
Y1462631D03*
Y1457675D03*
X224753Y1462631D03*
X229745Y1457675D03*
X224753D03*
X229745Y1451631D03*
Y1462631D03*
X224753Y1451631D03*
X246062Y1075196D03*
X238582D03*
X242322D03*
X234842D03*
X246062Y1078936D03*
X238582D03*
X242322Y1082677D03*
X234842D03*
X242322Y1086417D03*
X234842D03*
X246062Y1090157D03*
X242322D03*
X238582D03*
X234842D03*
X246062Y1086417D03*
X242322Y1078936D03*
X238582Y1086417D03*
X234842Y1078936D03*
X246062Y1082677D03*
X238582D03*
X246062Y1093897D03*
X238582D03*
X246062Y1097637D03*
X238582D03*
X242322Y1101377D03*
X234842D03*
X242322Y1105117D03*
X234842D03*
X246062D03*
X242322Y1097637D03*
X238582Y1105117D03*
X234842Y1097637D03*
X246062Y1101377D03*
X242322Y1093897D03*
X238582Y1101377D03*
X234842Y1093897D03*
X246062Y1108858D03*
X242322D03*
X238582D03*
X234842D03*
X246062Y1120078D03*
X242322D03*
X238582D03*
X234842D03*
X246062Y1123818D03*
X242322D03*
X238582D03*
X234842D03*
X246062Y1116338D03*
X238582D03*
X234842Y1112598D03*
X246062D03*
X242322Y1116338D03*
X234842D03*
X242322Y1112598D03*
X238582D03*
X246062Y1127558D03*
X242322D03*
X238582D03*
X234842D03*
X246062Y1135039D03*
X242322D03*
X238582D03*
X234842D03*
X246062Y1131299D03*
X242322D03*
X238582D03*
X234842D03*
X246062Y1138779D03*
X242322D03*
X238582D03*
X234842D03*
X246062Y1142519D03*
X242322D03*
X238582D03*
X234842D03*
X246062Y1149999D03*
X242322D03*
X238582D03*
X234842D03*
X246062Y1146259D03*
X242322D03*
X238582D03*
X234842D03*
X246062Y1153740D03*
X242322D03*
X238582D03*
X234842D03*
X246062Y1157480D03*
X238582D03*
X242322Y1161220D03*
X234842D03*
X246062Y1164960D03*
X238582D03*
X242322Y1168700D03*
X234842D03*
X246062Y1172440D03*
X238582D03*
X242322Y1157480D03*
X234842D03*
X246062Y1161220D03*
X238582D03*
X242322Y1164960D03*
X234842D03*
X246062Y1168700D03*
X238582D03*
X242322Y1172440D03*
X234842D03*
X246062Y1187401D03*
X242322D03*
X238582D03*
X234842D03*
X246062Y1179921D03*
X242322D03*
X238582D03*
X234842D03*
X246062Y1183661D03*
X242322D03*
X238582D03*
X234842D03*
X246062Y1176180D03*
X242322D03*
X238582D03*
X234842D03*
X246062Y1194881D03*
X242322D03*
X238582D03*
X234842D03*
X246062Y1202362D03*
X242322D03*
X238582D03*
X234842D03*
X246062Y1198621D03*
X242322D03*
X238582D03*
X234842D03*
X246062Y1191141D03*
X242322D03*
X238582D03*
X234842D03*
X246062Y1206102D03*
X242322D03*
X238582D03*
X234842D03*
X246062Y1209842D03*
X242322D03*
X238582D03*
X234842D03*
X246062Y1221062D03*
X242322D03*
X238582D03*
X234842D03*
X238582Y1217322D03*
X246062Y1213582D03*
X242322D03*
X246062Y1217322D03*
X234842D03*
Y1213582D03*
X242322Y1217322D03*
X238582Y1213582D03*
X242322Y1224803D03*
X234842D03*
X242322Y1228543D03*
X234842D03*
X246062Y1232283D03*
X238582D03*
X246062Y1236023D03*
X238582D03*
X246062Y1224803D03*
X242322Y1232283D03*
X238582Y1224803D03*
X234842Y1232283D03*
X246062Y1228543D03*
X242322Y1236023D03*
X238582Y1228543D03*
X234842Y1236023D03*
X246062Y1239763D03*
X242322D03*
X238582D03*
X234842D03*
X242322Y1243503D03*
X234842D03*
X242322Y1247243D03*
X234842D03*
X246062Y1250984D03*
X238582D03*
X246062Y1243503D03*
X242322Y1250984D03*
X238582Y1243503D03*
X234842Y1250984D03*
X246062Y1247243D03*
X238582D03*
X246062Y1254724D03*
X238582D03*
X242322D03*
X234842D03*
X241623Y1348187D03*
X245023D03*
X240845Y1345691D03*
Y1350683D03*
X245801Y1345691D03*
Y1350683D03*
X240845Y1357603D03*
Y1362595D03*
X245801Y1357603D03*
Y1362595D03*
X245023Y1360099D03*
X241623D03*
X245023Y1372385D03*
X241623D03*
X240845Y1381801D03*
Y1374881D03*
Y1369889D03*
X245801Y1381801D03*
Y1374881D03*
Y1369889D03*
X241623Y1384297D03*
X245023D03*
X240845Y1386793D03*
X245801D03*
X261023Y1075196D03*
X253543D03*
X257283D03*
X249803D03*
X261023Y1078936D03*
X253543D03*
X257283Y1082677D03*
X249803D03*
X257283Y1086417D03*
X249803D03*
X261023Y1090157D03*
X257283D03*
X253543D03*
X249803D03*
X261023Y1086417D03*
X257283Y1078936D03*
X253543Y1086417D03*
X249803Y1078936D03*
X261023Y1082677D03*
X253543D03*
X261023Y1093897D03*
X253543D03*
X261023Y1097637D03*
X253543D03*
X257283Y1101377D03*
X249803D03*
X257283Y1105117D03*
X249803D03*
X261023D03*
X257283Y1097637D03*
X253543Y1105117D03*
X249803Y1097637D03*
X261023Y1101377D03*
X257283Y1093897D03*
X253543Y1101377D03*
X249803Y1093897D03*
X261023Y1108858D03*
X257283D03*
X253543D03*
X249803D03*
X261023Y1120078D03*
X257283D03*
X253543D03*
X249803D03*
X261023Y1123818D03*
X257283D03*
X253543D03*
X249803D03*
X253543Y1116338D03*
X249803D03*
Y1112598D03*
X257283Y1116338D03*
X261023Y1112598D03*
X257283D03*
X261023Y1116338D03*
X253543Y1112598D03*
X261023Y1127558D03*
X257283D03*
X253543D03*
X249803D03*
X261023Y1135039D03*
X257283D03*
X253543D03*
X249803D03*
X261023Y1131299D03*
X257283D03*
X253543D03*
X249803D03*
X261023Y1138779D03*
X257283D03*
X253543D03*
X249803D03*
X261023Y1142519D03*
X257283D03*
X253543D03*
X249803D03*
X261023Y1149999D03*
X257283D03*
X253543D03*
X249803D03*
X261023Y1146259D03*
X257283D03*
X253543D03*
X249803D03*
X261023Y1153740D03*
X257283D03*
X253543D03*
X249803D03*
X261023Y1157480D03*
X253543D03*
X257283Y1161220D03*
X249803D03*
X261023Y1164960D03*
X253543D03*
X257283Y1168700D03*
X249803D03*
X261023Y1172440D03*
X253543D03*
X261023Y1161220D03*
Y1168700D03*
X257283Y1157480D03*
X249803D03*
X253543Y1161220D03*
X257283Y1164960D03*
X249803D03*
X253543Y1168700D03*
X257283Y1172440D03*
X249803D03*
X261023Y1187401D03*
X257283D03*
X253543D03*
X249803D03*
X261023Y1179921D03*
X257283D03*
X253543D03*
X249803D03*
X261023Y1183661D03*
X257283D03*
X253543D03*
X249803D03*
X261023Y1176180D03*
X257283D03*
X253543D03*
X249803D03*
X261023Y1194881D03*
X257283D03*
X253543D03*
X249803D03*
X261023Y1202362D03*
X257283D03*
X253543D03*
X249803D03*
X261023Y1198621D03*
X257283D03*
X253543D03*
X249803D03*
X261023Y1191141D03*
X257283D03*
X253543D03*
X249803D03*
X261023Y1206102D03*
X257283D03*
X253543D03*
X249803D03*
X261023Y1209842D03*
X257283D03*
X253543D03*
X249803D03*
X261023Y1221062D03*
X257283D03*
X253543D03*
X249803D03*
Y1213582D03*
X261023D03*
X257283Y1217322D03*
X249803D03*
X257283Y1213582D03*
X253543D03*
X261023Y1217322D03*
X253543D03*
X257283Y1224803D03*
X249803D03*
X257283Y1228543D03*
X249803D03*
X261023Y1232283D03*
X253543D03*
X261023Y1236023D03*
X253543D03*
X261023Y1224803D03*
X257283Y1232283D03*
X253543Y1224803D03*
X249803Y1232283D03*
X261023Y1228543D03*
X257283Y1236023D03*
X253543Y1228543D03*
X249803Y1236023D03*
X261023Y1239763D03*
X257283D03*
X253543D03*
X249803D03*
X257283Y1243503D03*
X249803D03*
X257283Y1247243D03*
X249803D03*
X261023Y1250984D03*
X253543D03*
X261023Y1243503D03*
X257283Y1250984D03*
X253543Y1243503D03*
X249803Y1250984D03*
X261023Y1247243D03*
X253543D03*
X261023Y1254724D03*
X253543D03*
X257283D03*
X249803D03*
X253863Y1348187D03*
X258041Y1350683D03*
Y1345691D03*
X253085Y1350683D03*
Y1345691D03*
X257263Y1348187D03*
X258041Y1362595D03*
X253085D03*
X258041Y1357603D03*
X253085D03*
X253863Y1360099D03*
X257263D03*
X253863Y1372385D03*
X258041Y1381801D03*
Y1369795D03*
Y1374881D03*
X253085Y1381801D03*
Y1369795D03*
Y1374881D03*
X257263Y1372385D03*
X253863Y1384297D03*
X257263D03*
X253863Y1396583D03*
X257263D03*
X253085Y1393993D03*
Y1399079D03*
X258041Y1386793D03*
Y1399079D03*
Y1393993D03*
X253085Y1386793D03*
X257263Y1408495D03*
X253863D03*
X258041Y1405999D03*
Y1410991D03*
X253085Y1405999D03*
Y1410991D03*
X275984Y1075196D03*
X268503D03*
X279724D03*
X272244D03*
X264763D03*
X275984Y1078936D03*
X268503D03*
X279724Y1082677D03*
X272244D03*
X264763D03*
X279724Y1086417D03*
X272244D03*
X264763D03*
X279724Y1090157D03*
X275984D03*
X272244D03*
X268503D03*
X264763D03*
X279724Y1078936D03*
X275984Y1086417D03*
X272244Y1078936D03*
X268503Y1086417D03*
X264763Y1078936D03*
X275984Y1082677D03*
X268503D03*
X275984Y1093897D03*
X268503D03*
X275984Y1097637D03*
X268503D03*
X279724Y1101377D03*
X272244D03*
X264763D03*
X279724Y1105117D03*
X272244D03*
X264763D03*
X279724Y1097637D03*
X275984Y1105117D03*
X272244Y1097637D03*
X268503Y1105117D03*
X264763Y1097637D03*
X279724Y1093897D03*
X275984Y1101377D03*
X272244Y1093897D03*
X268503Y1101377D03*
X264763Y1093897D03*
X279724Y1108858D03*
X275984D03*
X272244D03*
X268503D03*
X264763D03*
X279724Y1120078D03*
X275984D03*
X272244D03*
X268503D03*
X264763D03*
X279724Y1123818D03*
X272244D03*
X268503D03*
X264763D03*
X275984D03*
X279724Y1112598D03*
Y1116338D03*
X272244D03*
X275984Y1112598D03*
X264763Y1116338D03*
Y1112598D03*
X275984Y1116338D03*
X272244Y1112598D03*
X268503Y1116338D03*
Y1112598D03*
X279724Y1127558D03*
X272244D03*
X268503D03*
X264763D03*
X279724Y1131299D03*
X268503D03*
X279724Y1135039D03*
X272244D03*
X268503D03*
X264763D03*
X279724Y1138779D03*
X275984D03*
X268503D03*
X272244Y1131299D03*
Y1138779D03*
X264763Y1131299D03*
Y1138779D03*
X275984Y1127558D03*
Y1135039D03*
Y1131299D03*
X279724Y1142519D03*
X275984D03*
X268503D03*
X264763D03*
X279724Y1146259D03*
X275984D03*
X268503D03*
X279724Y1149999D03*
X275984D03*
X272244D03*
X268503D03*
X264763D03*
X279724Y1153740D03*
X275984D03*
X272244D03*
X268503D03*
X264763Y1146259D03*
Y1153740D03*
X272244Y1142519D03*
Y1146259D03*
X279724Y1157480D03*
X272244D03*
X268503D03*
X279724Y1161220D03*
X272244D03*
X279724Y1164960D03*
X272244D03*
X279724Y1168700D03*
X272244D03*
X279724Y1172440D03*
X272244D03*
X268503D03*
Y1161220D03*
X264763D03*
X268503Y1164960D03*
X264763D03*
X268503Y1168700D03*
X264763D03*
Y1157480D03*
Y1172440D03*
X275984Y1157480D03*
Y1161220D03*
Y1164960D03*
Y1168700D03*
Y1172440D03*
X279724Y1183661D03*
X275984D03*
X268503D03*
X279724Y1187401D03*
X275984D03*
X268503D03*
X264763D03*
X279724Y1176180D03*
X275984D03*
X268503D03*
X275984Y1179921D03*
X264763D03*
Y1183661D03*
Y1176180D03*
X279724Y1179921D03*
X268503D03*
X272244Y1183661D03*
Y1187401D03*
Y1179921D03*
Y1176180D03*
X279724Y1191141D03*
X275984D03*
X268503D03*
X279724Y1194881D03*
X272244D03*
X268503D03*
X264763D03*
X279724Y1198621D03*
X268503D03*
X279724Y1202362D03*
X272244D03*
X268503D03*
X264763D03*
X272244Y1198621D03*
Y1191141D03*
X264763Y1198621D03*
Y1191141D03*
X275984Y1198621D03*
Y1202362D03*
Y1194881D03*
X279724Y1206102D03*
X272244D03*
X268503D03*
X264763D03*
X279724Y1209842D03*
X275984D03*
X272244D03*
X268503D03*
X264763D03*
X279724Y1221062D03*
X275984D03*
X272244D03*
X268503D03*
X264763D03*
X275984Y1206102D03*
X268503Y1217322D03*
X275984D03*
Y1213582D03*
X279724D03*
X272244D03*
X268503D03*
X264763D03*
Y1217322D03*
X272244D03*
X279724D03*
Y1224803D03*
X272244D03*
X264763D03*
X279724Y1228543D03*
X272244D03*
X264763D03*
X275984Y1232283D03*
X268503D03*
X275984Y1236023D03*
X268503D03*
X279724Y1232283D03*
X275984Y1224803D03*
X272244Y1232283D03*
X268503Y1224803D03*
X264763Y1232283D03*
X279724Y1236023D03*
X275984Y1228543D03*
X272244Y1236023D03*
X268503Y1228543D03*
X264763Y1236023D03*
X279724Y1239763D03*
X275984D03*
X272244D03*
X268503D03*
X264763D03*
X279724Y1243503D03*
X272244D03*
X264763D03*
X279724Y1247243D03*
X272244D03*
X264763D03*
X275984Y1250984D03*
X268503D03*
X279724D03*
X275984Y1243503D03*
X272244Y1250984D03*
X268503Y1243503D03*
X264763Y1250984D03*
X275984Y1247243D03*
X268503D03*
X275984Y1254724D03*
X268503D03*
X279724D03*
X272244D03*
X264763D03*
X269503Y1348187D03*
X278343D03*
X266103D03*
X277565Y1350683D03*
Y1345691D03*
X265325D03*
Y1350683D03*
X270281Y1345691D03*
Y1350683D03*
X277565Y1362595D03*
X265325D03*
X270281D03*
X277565Y1357603D03*
X265325D03*
X270281D03*
X278343Y1360099D03*
X266103D03*
X269503D03*
Y1372385D03*
X266103D03*
X278343D03*
X277565Y1381801D03*
Y1374881D03*
Y1369889D03*
X265325D03*
Y1374881D03*
Y1381801D03*
X270281Y1369889D03*
Y1374881D03*
Y1381801D03*
X266103Y1384297D03*
X269503D03*
X278343D03*
Y1396583D03*
X269503D03*
X266103D03*
X277565Y1386793D03*
Y1394087D03*
Y1399079D03*
X265325Y1394087D03*
Y1399079D03*
Y1386793D03*
X270281Y1399079D03*
Y1394087D03*
Y1386793D03*
X265325Y1405999D03*
Y1410991D03*
X270281Y1405999D03*
Y1410991D03*
X277565Y1405999D03*
Y1410991D03*
X278343Y1408495D03*
X269503D03*
X266103D03*
X290944Y1075196D03*
X283464D03*
X287204D03*
X294685D03*
X290944Y1078936D03*
X283464D03*
X294685Y1082677D03*
X287204D03*
X294685Y1086417D03*
X287204D03*
X294685Y1090157D03*
X290944D03*
X287204D03*
X283464D03*
X290944Y1086417D03*
X287204Y1078936D03*
X283464Y1086417D03*
X290944Y1082677D03*
X283464D03*
X294685Y1078936D03*
X290944Y1093897D03*
X283464D03*
X290944Y1097637D03*
X283464D03*
X294685Y1101377D03*
X287204D03*
X294685Y1105117D03*
X287204D03*
X290944D03*
X287204Y1097637D03*
X283464Y1105117D03*
X290944Y1101377D03*
X287204Y1093897D03*
X283464Y1101377D03*
X294685Y1097637D03*
Y1093897D03*
Y1108858D03*
X290944D03*
X287204D03*
X283464D03*
X294685Y1112598D03*
X290944D03*
Y1116338D03*
X294685Y1120078D03*
X290944D03*
Y1123818D03*
X283464Y1120078D03*
Y1116338D03*
Y1123818D03*
X287204Y1116338D03*
Y1123818D03*
Y1120078D03*
Y1112598D03*
X283464D03*
X294685Y1116338D03*
Y1123818D03*
Y1127558D03*
X290944D03*
Y1131299D03*
X294685Y1135039D03*
X290944D03*
Y1138779D03*
X287204Y1127558D03*
Y1131299D03*
X283464Y1127558D03*
Y1131299D03*
X287204Y1138779D03*
X283464Y1135039D03*
X287204D03*
X283464Y1138779D03*
X294685D03*
Y1131299D03*
Y1142519D03*
X290944D03*
Y1146259D03*
X294685Y1149999D03*
X290944D03*
Y1153740D03*
X287204D03*
X283464D03*
Y1142519D03*
X287204Y1149999D03*
X283464D03*
Y1146259D03*
X287204Y1142519D03*
Y1146259D03*
X294685D03*
Y1153740D03*
Y1157480D03*
X290944D03*
X287204D03*
X290944Y1161220D03*
X287204D03*
X294685Y1164960D03*
X290944D03*
X287204D03*
X290944Y1168700D03*
X287204D03*
X294685Y1172440D03*
X290944D03*
X287204D03*
X283464Y1157480D03*
Y1161220D03*
Y1164960D03*
Y1168700D03*
Y1172440D03*
X294685Y1161220D03*
Y1168700D03*
X290944Y1183661D03*
X283464D03*
X294685Y1187401D03*
X290944D03*
Y1176180D03*
X287204D03*
X283464D03*
X294685Y1179921D03*
X290944D03*
X283464D03*
X287204Y1187401D03*
X283464D03*
X287204Y1179921D03*
Y1183661D03*
X294685Y1176180D03*
Y1183661D03*
X290944Y1191141D03*
X283464D03*
X294685Y1194881D03*
X290944D03*
Y1198621D03*
X294685Y1202362D03*
X290944D03*
X287204Y1191141D03*
X283464Y1194881D03*
Y1202362D03*
X287204Y1194881D03*
Y1202362D03*
Y1198621D03*
X283464D03*
X294685Y1191141D03*
Y1198621D03*
X290944Y1206102D03*
X294685Y1209842D03*
X290944D03*
Y1213582D03*
X294685Y1217322D03*
X290944D03*
X294685Y1221062D03*
X290944D03*
X287204D03*
X283464D03*
X287204Y1217322D03*
X283464Y1209842D03*
Y1213582D03*
Y1217322D03*
X287204Y1213582D03*
Y1209842D03*
X283464Y1206102D03*
X287204D03*
X294685Y1213582D03*
Y1206102D03*
Y1224803D03*
X287204D03*
X294685Y1228543D03*
X287204D03*
X290944Y1232283D03*
X283464D03*
X290944Y1236023D03*
X283464D03*
X287204Y1232283D03*
X283464Y1224803D03*
X287204Y1236023D03*
X283464Y1228543D03*
X290944Y1224803D03*
X294685Y1232283D03*
X290944Y1228543D03*
X294685Y1236023D03*
Y1239763D03*
X290944D03*
X287204D03*
X283464D03*
X294685Y1243503D03*
X287204D03*
X294685Y1247243D03*
X287204D03*
X290944Y1250984D03*
X283464D03*
X287204D03*
X283464Y1243503D03*
Y1247243D03*
X290944Y1243503D03*
X294685Y1250984D03*
X290944Y1247243D03*
Y1254724D03*
X283464D03*
X287204D03*
X294685D03*
X281743Y1348187D03*
X282521Y1345691D03*
X289805Y1350683D03*
Y1345691D03*
X294761Y1350683D03*
Y1345691D03*
X282521Y1350683D03*
X293983Y1348187D03*
X290583D03*
X289805Y1362595D03*
X294761D03*
X282521D03*
X289805Y1357603D03*
X294761D03*
X282521D03*
X281743Y1360099D03*
X293983D03*
X290583D03*
X293983Y1372385D03*
X289805Y1374881D03*
Y1369889D03*
Y1381801D03*
X294761Y1374881D03*
Y1369889D03*
Y1381801D03*
X282521D03*
Y1374881D03*
Y1369889D03*
X281743Y1372385D03*
X290583Y1384297D03*
X293983D03*
X290583Y1372385D03*
X281743Y1384297D03*
X293983Y1396583D03*
X289805Y1394087D03*
Y1399079D03*
Y1386793D03*
X294761Y1394087D03*
Y1399079D03*
Y1386793D03*
X282521D03*
Y1399079D03*
Y1394087D03*
X290583Y1396583D03*
X281743D03*
X289805Y1405999D03*
Y1410991D03*
X294761Y1405999D03*
Y1410991D03*
X282521Y1405999D03*
Y1410991D03*
X281743Y1408495D03*
X293983D03*
X290583D03*
X305905Y1075196D03*
X298425D03*
X302165D03*
X309645D03*
X305905Y1078936D03*
X298425D03*
X309645Y1082677D03*
X302165D03*
X309645Y1086417D03*
X302165D03*
X309645Y1090157D03*
X305905D03*
X302165D03*
X298425D03*
Y1086417D03*
X302165Y1078936D03*
X305905Y1086417D03*
X309645Y1078936D03*
X298425Y1082677D03*
X305905D03*
Y1093897D03*
X298425D03*
X305905Y1097637D03*
X298425D03*
X309645Y1101377D03*
X302165D03*
X309645Y1105117D03*
X302165D03*
X298425D03*
X302165Y1097637D03*
X305905Y1105117D03*
X309645Y1097637D03*
X298425Y1101377D03*
X302165Y1093897D03*
X305905Y1101377D03*
X309645Y1093897D03*
Y1108858D03*
X305905D03*
X302165D03*
X298425D03*
X309645Y1112598D03*
X298425D03*
X309645Y1116338D03*
X305905D03*
X302165D03*
X309645Y1120078D03*
X298425D03*
X309645Y1123818D03*
X305905D03*
X302165D03*
Y1112598D03*
Y1120078D03*
X305905Y1112598D03*
X298425Y1116338D03*
X305905Y1120078D03*
X298425Y1123818D03*
X309645Y1127558D03*
X298425D03*
X309645Y1131299D03*
X305905D03*
X302165D03*
X309645Y1135039D03*
X298425D03*
X309645Y1138779D03*
X305905D03*
X302165D03*
X298425D03*
X302165Y1127558D03*
Y1135039D03*
X305905Y1127558D03*
X298425Y1131299D03*
X305905Y1135039D03*
X309645Y1142519D03*
X298425D03*
X309645Y1146259D03*
X305905D03*
X302165D03*
X309645Y1149999D03*
X298425D03*
X309645Y1153740D03*
X305905D03*
X302165D03*
Y1142519D03*
Y1149999D03*
X305905Y1142519D03*
X298425Y1146259D03*
X305905Y1149999D03*
X298425Y1153740D03*
X309645Y1157480D03*
X298425D03*
X309645Y1161220D03*
X305905D03*
X302165D03*
X309645Y1164960D03*
X298425D03*
X309645Y1168700D03*
X305905D03*
X302165D03*
X309645Y1172440D03*
X298425D03*
X302165Y1157480D03*
Y1164960D03*
Y1172440D03*
X305905Y1157480D03*
X298425Y1161220D03*
X305905Y1164960D03*
X298425Y1168700D03*
X305905Y1172440D03*
X309645Y1183661D03*
X305905D03*
X302165D03*
X309645Y1187401D03*
X298425D03*
X309645Y1176180D03*
X305905D03*
X302165D03*
X309645Y1179921D03*
X298425D03*
X302165D03*
Y1187401D03*
X298425Y1176180D03*
X305905Y1179921D03*
X298425Y1183661D03*
X305905Y1187401D03*
X309645Y1191141D03*
X305905D03*
X302165D03*
X309645Y1194881D03*
X298425D03*
X309645Y1198621D03*
X305905D03*
X302165D03*
X309645Y1202362D03*
X298425D03*
X302165Y1194881D03*
X298425Y1191141D03*
X305905Y1194881D03*
X302165Y1202362D03*
X305905D03*
X298425Y1198621D03*
X309645Y1206102D03*
X305905D03*
X302165D03*
X309645Y1209842D03*
X298425D03*
X309645Y1213582D03*
X305905D03*
X302165D03*
X309645Y1217322D03*
X298425D03*
X309645Y1221062D03*
X305905D03*
X302165D03*
X298425D03*
X302165Y1217322D03*
Y1209842D03*
X305905Y1217322D03*
X298425Y1213582D03*
X305905Y1209842D03*
X298425Y1206102D03*
X309645Y1224803D03*
X302165D03*
X309645Y1228543D03*
X302165D03*
X305905Y1232283D03*
X298425D03*
X305905Y1236023D03*
X298425D03*
Y1224803D03*
X302165Y1232283D03*
X305905Y1224803D03*
X309645Y1232283D03*
X298425Y1228543D03*
X302165Y1236023D03*
X305905Y1228543D03*
X309645Y1236023D03*
Y1239763D03*
X305905D03*
X302165D03*
X298425D03*
X309645Y1243503D03*
X302165D03*
X309645Y1247243D03*
X302165D03*
X305905Y1250984D03*
X298425D03*
Y1243503D03*
X302165Y1250984D03*
X305905Y1243503D03*
X309645Y1250984D03*
X298425Y1247243D03*
X305905D03*
Y1254724D03*
X298425D03*
X302165D03*
X309645D03*
X302823Y1348187D03*
X306223D03*
X302045Y1345691D03*
Y1350683D03*
X307001D03*
Y1345691D03*
X302045Y1362595D03*
X307001D03*
X302045Y1357603D03*
X307001D03*
X306223Y1360099D03*
X302823D03*
X306223Y1372385D03*
X302823D03*
X302045Y1374881D03*
Y1381801D03*
Y1369889D03*
X307001Y1374881D03*
Y1369889D03*
Y1381801D03*
X306223Y1384297D03*
X302823D03*
Y1396583D03*
X302045Y1386793D03*
Y1394087D03*
Y1399079D03*
X307001Y1386793D03*
Y1399079D03*
Y1394087D03*
X306223Y1396583D03*
X302823Y1408495D03*
X306223D03*
X302045Y1405999D03*
Y1410991D03*
X307001Y1405999D03*
Y1410991D03*
X320866Y1075196D03*
X313385D03*
X317125D03*
X324606Y1078936D03*
X320866D03*
X313385D03*
X317125Y1082677D03*
X324606Y1086417D03*
X320866D03*
X317125D03*
Y1090157D03*
X313385D03*
X320866D03*
X324606D03*
X317125Y1078936D03*
X320866Y1082677D03*
X313385Y1086417D03*
X324606Y1082677D03*
X313385D03*
X324606Y1093897D03*
X320866D03*
X313385D03*
X324606Y1097637D03*
X320866D03*
X313385D03*
X317125Y1101377D03*
X324606Y1105117D03*
X320866D03*
X317125D03*
Y1097637D03*
X320866Y1101377D03*
X313385Y1105117D03*
X317125Y1093897D03*
X324606Y1101377D03*
X313385D03*
X317125Y1108858D03*
X313385D03*
X324606Y1112598D03*
X320866D03*
X317125Y1116338D03*
X313385D03*
X324606Y1120078D03*
X320866D03*
X317125Y1123818D03*
X313385D03*
X320866Y1108858D03*
X313385Y1112598D03*
X320866Y1116338D03*
X313385Y1120078D03*
X320866Y1123818D03*
X324606Y1108858D03*
X317125Y1112598D03*
X324606Y1116338D03*
X317125Y1120078D03*
X324606Y1123818D03*
Y1127558D03*
X320866D03*
X317125Y1131299D03*
X313385D03*
X324606Y1135039D03*
X320866D03*
X317125Y1138779D03*
X313385D03*
X320866D03*
X324606D03*
X313385Y1127558D03*
X320866Y1131299D03*
X313385Y1135039D03*
X317125Y1127558D03*
X324606Y1131299D03*
X317125Y1135039D03*
X324606Y1142519D03*
X320866D03*
X317125Y1146259D03*
X313385D03*
X324606Y1149999D03*
X320866D03*
X317125Y1153740D03*
X313385D03*
Y1142519D03*
X320866Y1146259D03*
X313385Y1149999D03*
X320866Y1153740D03*
X317125Y1142519D03*
X324606Y1146259D03*
X317125Y1149999D03*
X324606Y1153740D03*
Y1157480D03*
X320866D03*
X317125Y1161220D03*
X313385D03*
X324606Y1164960D03*
X320866D03*
X317125Y1168700D03*
X313385D03*
X324606Y1172440D03*
X320866D03*
X313385Y1157480D03*
X320866Y1161220D03*
X313385Y1164960D03*
X320866Y1168700D03*
X313385Y1172440D03*
X317125Y1157480D03*
X324606Y1161220D03*
X317125Y1164960D03*
X324606Y1168700D03*
X317125Y1172440D03*
Y1183661D03*
X313385D03*
X324606Y1187401D03*
X320866D03*
X317125Y1176180D03*
X313385D03*
X324606Y1179921D03*
X320866D03*
Y1176180D03*
X313385Y1179921D03*
X320866Y1183661D03*
X313385Y1187401D03*
X324606Y1176180D03*
X317125Y1179921D03*
X324606Y1183661D03*
X317125Y1187401D03*
Y1191141D03*
X313385D03*
X324606Y1194881D03*
X320866D03*
X317125Y1198621D03*
X313385D03*
X324606Y1202362D03*
X320866D03*
Y1191141D03*
X313385Y1194881D03*
X324606Y1191141D03*
X317125Y1194881D03*
X313385Y1202362D03*
X320866Y1198621D03*
X317125Y1202362D03*
X324606Y1198621D03*
X317125Y1206102D03*
X313385D03*
X324606Y1209842D03*
X320866D03*
X317125Y1213582D03*
X313385D03*
X324606Y1217322D03*
X320866D03*
X317125Y1221062D03*
X313385D03*
X320866D03*
X313385Y1217322D03*
X320866Y1213582D03*
X313385Y1209842D03*
X320866Y1206102D03*
X324606Y1221062D03*
X317125Y1217322D03*
X324606Y1213582D03*
X317125Y1209842D03*
X324606Y1206102D03*
Y1224803D03*
X320866D03*
X317125D03*
Y1228543D03*
X324606Y1232283D03*
X320866D03*
X313385D03*
X324606Y1236023D03*
X320866D03*
X313385D03*
Y1224803D03*
X317125Y1232283D03*
X320866Y1228543D03*
X313385D03*
X317125Y1236023D03*
X324606Y1228543D03*
X317125Y1239763D03*
X313385D03*
X324606Y1243503D03*
X320866D03*
X317125D03*
Y1247243D03*
X324606Y1250984D03*
X320866D03*
X313385D03*
X320866Y1239763D03*
X324606D03*
X313385Y1243503D03*
X317125Y1250984D03*
X320866Y1247243D03*
X313385D03*
X324606D03*
X320866Y1254724D03*
X313385D03*
X317125D03*
X327303Y1348187D03*
X315063D03*
X319241Y1350683D03*
Y1345691D03*
X314285D03*
Y1350683D03*
X326525Y1345691D03*
Y1350683D03*
X318463Y1348187D03*
X327303Y1360099D03*
X319241Y1362595D03*
X314285D03*
X326525D03*
X319241Y1357603D03*
X314285D03*
X326525D03*
X315063Y1360099D03*
X318463D03*
X315063Y1372385D03*
X318463Y1384297D03*
X315063D03*
X319241Y1374881D03*
Y1381801D03*
Y1369889D03*
X314285Y1374881D03*
Y1381801D03*
Y1369889D03*
X326525Y1381801D03*
Y1369889D03*
Y1374881D03*
X327303Y1372385D03*
X318463D03*
X327303Y1384297D03*
Y1396583D03*
X315063D03*
X319241Y1386793D03*
Y1399079D03*
Y1394087D03*
X314285Y1386793D03*
Y1399079D03*
Y1394087D03*
X326525Y1399079D03*
Y1394087D03*
Y1386793D03*
X318463Y1396583D03*
X327303Y1408495D03*
X319241Y1410991D03*
Y1405999D03*
X314285Y1410991D03*
Y1405999D03*
X326525Y1410991D03*
Y1405999D03*
X318463Y1408495D03*
X315063D03*
X339543Y1348187D03*
X338765Y1350683D03*
Y1345691D03*
X331481D03*
Y1350683D03*
X343721Y1345691D03*
Y1350683D03*
X342943Y1348187D03*
X330703D03*
Y1360099D03*
X331481Y1362595D03*
X343721D03*
X338765D03*
X331481Y1357603D03*
X343721D03*
X338765D03*
X342943Y1360099D03*
X339543D03*
Y1372385D03*
X342943D03*
X330703D03*
X331481Y1374881D03*
Y1381801D03*
Y1369889D03*
X343721Y1381801D03*
Y1369889D03*
Y1374881D03*
X338765Y1381801D03*
Y1369889D03*
Y1374881D03*
X342943Y1384297D03*
X339543D03*
X330703D03*
Y1396583D03*
X331481Y1399079D03*
Y1394087D03*
Y1386793D03*
X343721D03*
Y1394087D03*
Y1399079D03*
X338765Y1386793D03*
Y1394087D03*
Y1399079D03*
X339543Y1396583D03*
X342943D03*
X330703Y1408495D03*
X331481Y1410991D03*
Y1405999D03*
X343721Y1410991D03*
Y1405999D03*
X338765Y1410991D03*
Y1405999D03*
X342943Y1408495D03*
X339543D03*
X351783Y1348187D03*
X355183D03*
X355961Y1350683D03*
X351005Y1345597D03*
Y1350683D03*
X355961Y1345597D03*
X351005Y1362595D03*
X355961D03*
X351005Y1357603D03*
X355961D03*
X355183Y1360099D03*
X351783D03*
Y1372385D03*
X355183D03*
X351005Y1374881D03*
Y1381801D03*
Y1369889D03*
X355961Y1381801D03*
Y1374881D03*
Y1369889D03*
X355183Y1384297D03*
X351783D03*
Y1396583D03*
X351005Y1399079D03*
Y1393993D03*
Y1386793D03*
X355961D03*
Y1399079D03*
Y1393993D03*
X355183Y1396583D03*
X351005Y1410991D03*
Y1405999D03*
X355961D03*
Y1410991D03*
X351783Y1408495D03*
X355183D03*
X363245Y1345691D03*
Y1350683D03*
X368201Y1345691D03*
Y1350683D03*
X364023Y1348187D03*
X367423D03*
X363245Y1362595D03*
X368201D03*
X363245Y1357603D03*
X368201D03*
X367423Y1360099D03*
X364023D03*
Y1372385D03*
X363245Y1369889D03*
Y1381801D03*
Y1374881D03*
X368201D03*
Y1381801D03*
Y1369889D03*
X367423Y1384297D03*
X364023D03*
X367423Y1372385D03*
X363245Y1399079D03*
Y1394087D03*
Y1386793D03*
X368201D03*
Y1394087D03*
Y1399079D03*
X364023Y1396583D03*
X367423D03*
X363245Y1405999D03*
Y1410991D03*
X368201D03*
Y1405999D03*
X364023Y1408495D03*
X367423D03*
X393094Y1423600D03*
X408523Y1332967D03*
X404657D03*
X395894Y1423600D03*
X439624Y1345691D03*
Y1350683D03*
X440402Y1348187D03*
X439624Y1357603D03*
Y1362595D03*
X440402Y1360099D03*
X439624Y1381801D03*
Y1369889D03*
Y1374881D03*
X440402Y1372385D03*
Y1384297D03*
X439624Y1386793D03*
X435881Y1394934D03*
Y1398800D03*
X456820Y1345691D03*
X451864D03*
Y1350683D03*
X456820D03*
X444580Y1345691D03*
Y1350683D03*
X452642Y1348187D03*
X456042D03*
X443802D03*
X456820Y1362595D03*
Y1357603D03*
X451864Y1362595D03*
Y1357603D03*
X444580D03*
Y1362595D03*
X456042Y1360099D03*
X452642D03*
X443802D03*
X456820Y1374881D03*
X451864D03*
X444580Y1369889D03*
X456820Y1369795D03*
X451864D03*
X444580Y1374881D03*
Y1381801D03*
X456820D03*
X451864D03*
X443802Y1372385D03*
X452642D03*
X456042D03*
X452642Y1384297D03*
X456042D03*
X443802D03*
X456820Y1399079D03*
X451864Y1393993D03*
Y1399079D03*
X456820Y1393993D03*
Y1386793D03*
X451864D03*
X444580D03*
X452642Y1396583D03*
X456042D03*
X456820Y1405999D03*
X451864D03*
Y1410991D03*
X456820D03*
X452642Y1408495D03*
X456042D03*
X454125Y1461182D03*
Y1465913D03*
Y1481267D03*
Y1476536D03*
Y1491890D03*
Y1496621D03*
Y1511976D03*
Y1507245D03*
Y1578898D03*
Y1568275D03*
Y1563544D03*
Y1583629D03*
Y1594253D03*
Y1609607D03*
Y1598984D03*
Y1614338D03*
X469060Y1345691D03*
Y1350683D03*
X464104Y1345691D03*
Y1350683D03*
X468282Y1348187D03*
X464882D03*
X469060Y1357603D03*
Y1362595D03*
X464104D03*
Y1357603D03*
X468282Y1360099D03*
X464882D03*
X464104Y1381801D03*
X469060D03*
X464104Y1369889D03*
X469060D03*
X464104Y1374881D03*
X469060D03*
X464882Y1372385D03*
X468282D03*
X464882Y1384297D03*
X468282D03*
X469060Y1386793D03*
X464104D03*
X469060Y1399079D03*
X464104Y1394087D03*
X469060D03*
X464104Y1399079D03*
X468282Y1396583D03*
X464882D03*
X464104Y1405999D03*
X469060D03*
X464104Y1410991D03*
X469060D03*
X464882Y1408495D03*
X468282D03*
X471448Y1461182D03*
Y1465913D03*
X462786Y1465513D03*
X471448Y1481267D03*
X462786Y1480867D03*
X471448Y1476536D03*
X462786Y1470244D03*
X471448Y1496621D03*
X462786Y1496221D03*
X471448Y1491890D03*
X462786Y1485598D03*
X471448Y1511976D03*
Y1507245D03*
X462786Y1511576D03*
Y1500952D03*
Y1516307D03*
X471448Y1568275D03*
Y1563544D03*
X462786Y1567875D03*
Y1572606D03*
X471448Y1578898D03*
Y1594253D03*
Y1583629D03*
X462786Y1583229D03*
Y1587960D03*
X471448Y1598984D03*
X462786Y1598584D03*
Y1603315D03*
X471448Y1609607D03*
Y1614338D03*
X462786Y1613938D03*
Y1618669D03*
X488584Y1345691D03*
Y1350683D03*
X481300Y1345691D03*
X476344D03*
X481300Y1350683D03*
X476344D03*
X489362Y1348187D03*
X480522D03*
X477122D03*
X488584Y1357603D03*
Y1362595D03*
X481300D03*
Y1357603D03*
X476344Y1362595D03*
Y1357603D03*
X480522Y1360099D03*
X477122D03*
X489362D03*
X488584Y1381801D03*
X481300D03*
X488584Y1374881D03*
Y1369889D03*
X481300D03*
Y1374881D03*
X476344Y1381801D03*
Y1369889D03*
Y1374881D03*
X477122Y1372385D03*
X480522D03*
X489362D03*
Y1384297D03*
X480522D03*
X477122D03*
X488584Y1386793D03*
X481300D03*
Y1399079D03*
X476344Y1394087D03*
Y1399079D03*
X488584Y1394087D03*
X481300D03*
X488584Y1399079D03*
X476344Y1386793D03*
X480522Y1396583D03*
X477122D03*
X489362D03*
X476344Y1410991D03*
X481300Y1405999D03*
X476344D03*
X488584D03*
Y1410991D03*
X481300D03*
X477122Y1408495D03*
X480522D03*
X489362D03*
X480109Y1465513D03*
X488771Y1465913D03*
Y1461182D03*
X480109Y1470244D03*
X488771Y1476536D03*
Y1481267D03*
X480109Y1480867D03*
Y1496221D03*
X488771Y1491890D03*
X480109Y1485598D03*
X488771Y1496621D03*
Y1511976D03*
X480109Y1511576D03*
Y1500952D03*
X488771Y1507245D03*
X480109Y1516307D03*
X488771Y1578898D03*
Y1568275D03*
Y1563544D03*
X480109Y1567875D03*
Y1572606D03*
X488771Y1583629D03*
X480109Y1583229D03*
Y1587960D03*
X488771Y1594253D03*
Y1609607D03*
Y1598984D03*
X480109Y1598584D03*
Y1603315D03*
X488771Y1614338D03*
X480109Y1613938D03*
Y1618669D03*
X500824Y1350683D03*
Y1345691D03*
X505780Y1350683D03*
Y1345691D03*
X493540D03*
Y1350683D03*
X492762Y1348187D03*
X501602D03*
X505002D03*
X505780Y1362595D03*
Y1357603D03*
X500824Y1362595D03*
Y1357603D03*
X493540Y1362595D03*
Y1357603D03*
X501602Y1360099D03*
X505002D03*
X492762D03*
X493540Y1381801D03*
Y1374881D03*
Y1369889D03*
X505780Y1381801D03*
Y1374881D03*
Y1369889D03*
X500824D03*
Y1381801D03*
Y1374881D03*
X505002Y1372385D03*
X492762D03*
X501602D03*
X492762Y1384297D03*
X505002D03*
X501602D03*
X505002Y1396583D03*
X500824Y1394087D03*
X505780Y1399079D03*
X500824D03*
X505780Y1394087D03*
X493540Y1386793D03*
Y1394087D03*
Y1399079D03*
X505780Y1386793D03*
X500824D03*
X492762Y1396583D03*
X501602D03*
X505780Y1410991D03*
X500824D03*
X505780Y1405999D03*
X500824D03*
X493540D03*
Y1410991D03*
X505002Y1408495D03*
X501602D03*
X492762D03*
X497432Y1465513D03*
X506093Y1465913D03*
Y1461182D03*
X497432Y1480867D03*
X506093Y1481267D03*
X497432Y1470244D03*
X506093Y1476536D03*
X497432Y1496221D03*
Y1485598D03*
X506093Y1491890D03*
Y1496621D03*
Y1511976D03*
X497432Y1500952D03*
X506093Y1507245D03*
X497432Y1511576D03*
Y1516307D03*
X506093Y1578898D03*
X497432Y1567875D03*
Y1572606D03*
X506093Y1568275D03*
Y1563544D03*
X497432Y1587960D03*
X506093Y1583629D03*
Y1594253D03*
X497432Y1583229D03*
X506093Y1598984D03*
Y1609607D03*
X497432Y1598584D03*
Y1603315D03*
Y1613938D03*
Y1618669D03*
X506093Y1614338D03*
X515573Y692515D03*
X518299Y692384D03*
X520799D03*
X517242Y1348187D03*
X513064Y1345691D03*
X518020Y1350683D03*
X513064D03*
X518020Y1345691D03*
X513842Y1348187D03*
X518020Y1357603D03*
X513064Y1362595D03*
Y1357603D03*
X518020Y1362595D03*
X513842Y1360099D03*
X517242D03*
Y1372385D03*
X513064Y1369889D03*
Y1381801D03*
Y1374881D03*
X518020Y1369889D03*
Y1381801D03*
Y1374881D03*
X513842Y1372385D03*
X517242Y1384297D03*
X513842D03*
X518020Y1394087D03*
Y1399079D03*
X513064Y1394087D03*
Y1399079D03*
Y1386793D03*
X518020D03*
X517242Y1396583D03*
X513842D03*
X518020Y1405999D03*
Y1410991D03*
X513064D03*
Y1405999D03*
X517242Y1408495D03*
X513842D03*
X514755Y1465513D03*
Y1480867D03*
Y1470244D03*
Y1485598D03*
Y1496221D03*
Y1511576D03*
Y1500952D03*
Y1516307D03*
Y1567875D03*
Y1572606D03*
Y1583229D03*
Y1587960D03*
Y1603315D03*
Y1598584D03*
Y1613938D03*
Y1618669D03*
X529493Y692443D03*
Y697443D03*
Y699943D03*
X529501Y702622D03*
X526993Y692443D03*
X529493Y694943D03*
X524493Y692443D03*
X525304Y1345691D03*
X530260D03*
X537544Y1350683D03*
X525304D03*
X530260D03*
X537544Y1345691D03*
X529482Y1348187D03*
X526082D03*
X538322D03*
X537544Y1357603D03*
X525304Y1362595D03*
X530260D03*
X525304Y1357603D03*
X530260D03*
X537544Y1362595D03*
X538322Y1360099D03*
X529482D03*
X526082D03*
X529482Y1372385D03*
X537544Y1374881D03*
X525304Y1369889D03*
Y1381801D03*
Y1374881D03*
X530260Y1369889D03*
Y1381801D03*
Y1374881D03*
X537544Y1369889D03*
Y1381801D03*
X538322Y1384297D03*
X529482D03*
X538322Y1372385D03*
X526082D03*
Y1384297D03*
Y1396583D03*
X537544Y1399079D03*
Y1394087D03*
X530260D03*
Y1399079D03*
X525304Y1394087D03*
Y1399079D03*
X537544Y1386793D03*
X525304D03*
X530260D03*
X538322Y1396583D03*
X529482D03*
X537544Y1410991D03*
Y1405999D03*
X530260D03*
X525304D03*
X530260Y1410991D03*
X525304D03*
X529482Y1408495D03*
X526082D03*
X538322D03*
X553962Y1348187D03*
X554740Y1345597D03*
X542500Y1345691D03*
X549784Y1345597D03*
X542500Y1350683D03*
X549784D03*
X554740D03*
X541722Y1348187D03*
X550562D03*
X554740Y1362595D03*
Y1357603D03*
X542500Y1362595D03*
X549784D03*
X542500Y1357603D03*
X549784D03*
X553962Y1360099D03*
X550562D03*
X541722D03*
Y1372385D03*
X550562D03*
X554740Y1381801D03*
Y1374881D03*
X542500D03*
X549784Y1369889D03*
Y1381801D03*
Y1374881D03*
X542500Y1369889D03*
Y1381801D03*
X554740Y1369889D03*
X541722Y1384297D03*
X553962D03*
X550562D03*
X553962Y1372385D03*
Y1396583D03*
X541722D03*
X554740Y1399079D03*
Y1393993D03*
X542500Y1399079D03*
X549784Y1393993D03*
Y1399079D03*
X542500Y1394087D03*
X554740Y1386793D03*
X549784D03*
X542500D03*
X550562Y1396583D03*
X554740Y1410991D03*
Y1405999D03*
X542500Y1410991D03*
X549784D03*
X542500Y1405999D03*
X549784D03*
X553962Y1408495D03*
X550562D03*
X541722D03*
X562024Y1350683D03*
Y1345691D03*
X566980D03*
Y1350683D03*
X562802Y1348187D03*
X566202D03*
X562024Y1357603D03*
X566980D03*
Y1362595D03*
X562024D03*
X566202Y1360099D03*
X562802D03*
X566202Y1372385D03*
X562024Y1369889D03*
Y1381801D03*
Y1374881D03*
X566980Y1369889D03*
Y1381801D03*
Y1374881D03*
X566202Y1384297D03*
X562802D03*
Y1372385D03*
X566202Y1396583D03*
X566980Y1399079D03*
Y1394087D03*
X562024Y1399079D03*
Y1394087D03*
X566980Y1386793D03*
X562024D03*
X562802Y1396583D03*
X566980Y1410991D03*
X562024D03*
X566980Y1405999D03*
X562024D03*
X566202Y1408495D03*
X562802D03*
X602165Y1078936D03*
Y1086417D03*
Y1090157D03*
Y1082677D03*
Y1093897D03*
Y1097637D03*
Y1105117D03*
Y1101377D03*
Y1112598D03*
Y1120078D03*
Y1108858D03*
Y1116338D03*
Y1123818D03*
Y1127558D03*
Y1135039D03*
Y1131299D03*
Y1138779D03*
Y1142519D03*
Y1146259D03*
Y1153740D03*
Y1149999D03*
Y1161220D03*
Y1168700D03*
Y1157480D03*
Y1164960D03*
Y1172440D03*
Y1183661D03*
Y1187401D03*
Y1176180D03*
Y1179921D03*
Y1194881D03*
Y1202362D03*
Y1198621D03*
Y1191141D03*
Y1209842D03*
Y1217322D03*
Y1221062D03*
Y1213582D03*
Y1206102D03*
Y1224803D03*
Y1232283D03*
Y1236023D03*
Y1228543D03*
Y1243503D03*
Y1250984D03*
Y1239763D03*
Y1247243D03*
X620866Y1075196D03*
X613386D03*
X605905D03*
X617126D03*
X609646D03*
X620866Y1078936D03*
X613386D03*
X605905D03*
X617126Y1082677D03*
X609646D03*
X617126Y1086417D03*
X609646D03*
X605905D03*
X620866Y1090157D03*
X617126D03*
X613386D03*
X609646D03*
X605905D03*
X620866Y1086417D03*
X617126Y1078936D03*
X613386Y1086417D03*
X609646Y1078936D03*
X605905Y1082677D03*
X620866D03*
X613386D03*
X620866Y1093897D03*
X613386D03*
X605905D03*
X620866Y1097637D03*
X613386D03*
X605905D03*
X617126Y1101377D03*
X609646D03*
X617126Y1105117D03*
X609646D03*
X605905D03*
X620866D03*
X617126Y1097637D03*
X613386Y1105117D03*
X609646Y1097637D03*
X605905Y1101377D03*
X620866D03*
X617126Y1093897D03*
X613386Y1101377D03*
X609646Y1093897D03*
X620866Y1108858D03*
X617126D03*
X613386D03*
X609646D03*
X617126Y1112598D03*
X605905D03*
X620866Y1116338D03*
X617126D03*
X613386D03*
X609646D03*
X617126Y1120078D03*
X605905D03*
X620866Y1123818D03*
X617126D03*
X613386D03*
X609646D03*
X620866Y1112598D03*
Y1120078D03*
X605905Y1108858D03*
X613386Y1112598D03*
X605905Y1116338D03*
X613386Y1120078D03*
X605905Y1123818D03*
X609646Y1112598D03*
Y1120078D03*
X617126Y1127558D03*
X605905D03*
X620866Y1131299D03*
X617126D03*
X613386D03*
X609646D03*
X617126Y1135039D03*
X605905D03*
X620866Y1138779D03*
X617126D03*
X613386D03*
X609646D03*
X620866Y1127558D03*
Y1135039D03*
X613386Y1127558D03*
X605905Y1131299D03*
X613386Y1135039D03*
X605905Y1138779D03*
X609646Y1127558D03*
Y1135039D03*
X620866Y1142519D03*
X617126D03*
X613386D03*
X609646D03*
X605905D03*
X620866Y1146259D03*
X609646D03*
X605905D03*
X620866Y1149999D03*
X617126D03*
X613386D03*
X609646D03*
X620866Y1153740D03*
X609646D03*
X605905D03*
X613386Y1146259D03*
X617126D03*
X605905Y1149999D03*
X617126Y1153740D03*
X613386D03*
X620866Y1157480D03*
X617126D03*
X613386D03*
X609646D03*
X620866Y1161220D03*
X609646D03*
X605905D03*
X620866Y1164960D03*
X617126D03*
X613386D03*
X609646D03*
X620866Y1168700D03*
X609646D03*
X605905D03*
X620866Y1172440D03*
X617126D03*
X613386D03*
X609646D03*
X605905Y1157480D03*
X617126Y1161220D03*
X613386D03*
X605905Y1164960D03*
X617126Y1168700D03*
X613386D03*
X605905Y1172440D03*
X620866Y1183661D03*
X617126D03*
X613386D03*
X609646D03*
X605905D03*
X617126Y1187401D03*
X605905D03*
X620866Y1176180D03*
X609646D03*
X605905D03*
X620866Y1179921D03*
X617126D03*
X613386D03*
X609646D03*
X605905D03*
X617126Y1176180D03*
X613386D03*
X620866Y1187401D03*
X613386D03*
X609646D03*
X620866Y1191141D03*
X617126D03*
X613386D03*
X609646D03*
X617126Y1194881D03*
X605905D03*
X620866Y1198621D03*
X617126D03*
X613386D03*
X609646D03*
X617126Y1202362D03*
X605905D03*
X620866D03*
Y1194881D03*
X613386Y1202362D03*
X605905Y1198621D03*
X613386Y1194881D03*
X605905Y1191141D03*
X609646Y1202362D03*
Y1194881D03*
X620866Y1206102D03*
X617126D03*
X613386D03*
X609646D03*
X617126Y1209842D03*
X605905D03*
X620866Y1213582D03*
X617126D03*
X613386D03*
X609646D03*
X617126Y1217322D03*
X605905D03*
X620866Y1221062D03*
X617126D03*
X613386D03*
X609646D03*
X620866Y1217322D03*
Y1209842D03*
X605905Y1221062D03*
X613386Y1217322D03*
X605905Y1213582D03*
X613386Y1209842D03*
X605905Y1206102D03*
X609646Y1217322D03*
Y1209842D03*
X617126Y1224803D03*
X609646D03*
X605905D03*
X617126Y1228543D03*
X609646D03*
X620866Y1232283D03*
X613386D03*
X605905D03*
X620866Y1236023D03*
X613386D03*
X605905D03*
X620866Y1224803D03*
X617126Y1232283D03*
X613386Y1224803D03*
X609646Y1232283D03*
X605905Y1228543D03*
X620866D03*
X617126Y1236023D03*
X613386Y1228543D03*
X609646Y1236023D03*
X620866Y1239763D03*
X617126D03*
X613386D03*
X609646D03*
X617126Y1243503D03*
X609646D03*
X605905D03*
X617126Y1247243D03*
X609646D03*
X620866Y1250984D03*
X613386D03*
X605905D03*
Y1239763D03*
X620866Y1243503D03*
X617126Y1250984D03*
X613386Y1243503D03*
X609646Y1250984D03*
X605905Y1247243D03*
X620866D03*
X613386D03*
X620866Y1254724D03*
X613386D03*
X605905D03*
X617126D03*
X609646D03*
X628346Y1075196D03*
X635827D03*
X624606D03*
X632086D03*
X628346Y1078936D03*
X635827D03*
X632086Y1082677D03*
X624606D03*
X632086Y1086417D03*
X624606D03*
X632086Y1090157D03*
X628346D03*
X624606D03*
X635827D03*
X628346Y1086417D03*
X624606Y1078936D03*
X628346Y1082677D03*
X632086Y1078936D03*
X635827Y1086417D03*
Y1082677D03*
X628346Y1093897D03*
X635827D03*
X628346Y1097637D03*
X635827D03*
X632086Y1101377D03*
X624606D03*
X632086Y1105117D03*
X624606D03*
X628346D03*
X624606Y1097637D03*
X628346Y1101377D03*
X624606Y1093897D03*
X632086Y1097637D03*
X635827Y1105117D03*
X632086Y1093897D03*
X635827Y1101377D03*
X632086Y1108858D03*
X628346D03*
X624606D03*
X635827D03*
X632086Y1112598D03*
X628346D03*
X635827D03*
X624606Y1116338D03*
X635827D03*
X632086Y1120078D03*
X628346D03*
X635827D03*
X624606Y1123818D03*
X635827D03*
X624606Y1112598D03*
X632086Y1116338D03*
X624606Y1120078D03*
X632086Y1123818D03*
X628346Y1116338D03*
Y1123818D03*
X632086Y1127558D03*
X628346D03*
X635827D03*
X624606Y1131299D03*
X635827D03*
X632086Y1135039D03*
X628346D03*
X635827D03*
X624606Y1138779D03*
X635827D03*
X624606Y1127558D03*
X632086Y1131299D03*
X624606Y1135039D03*
X632086Y1138779D03*
X628346Y1131299D03*
Y1138779D03*
X632086Y1142519D03*
X628346D03*
X624606D03*
X635827D03*
X632086Y1146259D03*
X628346D03*
X632086Y1149999D03*
Y1153740D03*
X635827Y1146259D03*
Y1149999D03*
Y1153740D03*
X628346D03*
X624606Y1149999D03*
X628346D03*
X624606Y1146259D03*
Y1153740D03*
X632086Y1157480D03*
X635827D03*
X632086Y1161220D03*
Y1164960D03*
Y1168700D03*
X635827D03*
X632086Y1172440D03*
X635827D03*
Y1161220D03*
Y1164960D03*
X628346D03*
Y1172440D03*
Y1168700D03*
X624606Y1172440D03*
Y1168700D03*
Y1164960D03*
X628346Y1157480D03*
Y1161220D03*
X624606D03*
Y1157480D03*
X632086Y1183661D03*
X628346D03*
X624606D03*
X635827D03*
X632086Y1187401D03*
X628346D03*
X635827D03*
X632086Y1176180D03*
Y1179921D03*
X628346D03*
X624606D03*
X635827Y1176180D03*
Y1179921D03*
X624606Y1176180D03*
X628346D03*
X624606Y1187401D03*
Y1191141D03*
X635827D03*
X632086Y1194881D03*
X628346D03*
X635827D03*
X624606Y1198621D03*
X635827D03*
X632086Y1202362D03*
X628346D03*
X635827D03*
X624606D03*
X632086Y1198621D03*
X624606Y1194881D03*
X632086Y1191141D03*
X628346Y1198621D03*
Y1191141D03*
X624606Y1206102D03*
X635827D03*
X632086Y1209842D03*
X628346D03*
X635827D03*
X624606Y1213582D03*
X635827D03*
X632086Y1217322D03*
X628346D03*
X635827D03*
X632086Y1221062D03*
X628346D03*
X624606D03*
X635827D03*
X624606Y1217322D03*
X632086Y1213582D03*
X624606Y1209842D03*
X632086Y1206102D03*
X628346Y1213582D03*
Y1206102D03*
X632086Y1224803D03*
X624606D03*
X632086Y1228543D03*
X624606D03*
X628346Y1232283D03*
X635827D03*
X628346Y1236023D03*
X635827D03*
X624606Y1232283D03*
Y1236023D03*
X628346Y1224803D03*
X632086Y1232283D03*
X635827Y1224803D03*
X628346Y1228543D03*
X632086Y1236023D03*
X635827Y1228543D03*
X632086Y1239763D03*
X628346D03*
X624606D03*
X635827D03*
X632086Y1243503D03*
X624606D03*
X632086Y1247243D03*
X624606D03*
X628346Y1250984D03*
X635827D03*
X624606D03*
X628346Y1243503D03*
X632086Y1250984D03*
X635827Y1243503D03*
X628346Y1247243D03*
X635827D03*
X628346Y1254724D03*
X635827D03*
X624606D03*
X632086D03*
X630466Y1394087D03*
X625510Y1399079D03*
Y1394087D03*
X630466Y1399079D03*
X629688Y1396583D03*
X626288D03*
Y1408495D03*
X625510Y1405999D03*
X630466D03*
X625510Y1410991D03*
X630466D03*
X629688Y1408495D03*
X650787Y1075196D03*
X643307D03*
X639567D03*
X647047D03*
X650787Y1078936D03*
X643307D03*
X647047Y1082677D03*
X639567D03*
X647047Y1086417D03*
X639567D03*
X650787Y1090157D03*
X647047D03*
X643307D03*
X639567D03*
Y1078936D03*
X643307Y1086417D03*
X647047Y1078936D03*
X650787Y1086417D03*
X643307Y1082677D03*
X650787D03*
Y1093897D03*
X643307D03*
X650787Y1097637D03*
X643307D03*
X647047Y1101377D03*
X639567D03*
X647047Y1105117D03*
X639567D03*
Y1097637D03*
X643307Y1105117D03*
X647047Y1097637D03*
X650787Y1105117D03*
X639567Y1093897D03*
X643307Y1101377D03*
X647047Y1093897D03*
X650787Y1101377D03*
Y1108858D03*
X647047D03*
X643307D03*
X639567D03*
Y1112598D03*
Y1116338D03*
X650787Y1120078D03*
X647047D03*
X643307D03*
X639567D03*
X650787Y1123818D03*
X647047D03*
X643307D03*
X639567D03*
X647047Y1116338D03*
X643307D03*
Y1112598D03*
X647047D03*
X650787Y1116338D03*
Y1112598D03*
Y1127558D03*
X647047D03*
X643307D03*
X639567D03*
X647047Y1131299D03*
X643307D03*
X639567D03*
X647047Y1135039D03*
X643307D03*
X639567D03*
X647047Y1138779D03*
X639567D03*
X643307D03*
X650787D03*
Y1131299D03*
Y1135039D03*
X643307Y1149999D03*
X647047Y1153740D03*
Y1142519D03*
X643307D03*
X639567D03*
X647047Y1146259D03*
X639567D03*
X650787Y1149999D03*
X639567D03*
Y1153740D03*
X650787Y1142519D03*
X643307Y1146259D03*
X647047Y1149999D03*
X643307Y1153740D03*
X650787Y1146259D03*
Y1153740D03*
X643307Y1157480D03*
X647047Y1161220D03*
X643307Y1164960D03*
X647047Y1168700D03*
X643307Y1172440D03*
X650787Y1157480D03*
X639567D03*
Y1161220D03*
X650787Y1164960D03*
X639567D03*
Y1168700D03*
X650787Y1172440D03*
X639567D03*
X647047D03*
Y1157480D03*
X643307Y1161220D03*
X647047Y1164960D03*
X643307Y1168700D03*
X650787Y1161220D03*
Y1168700D03*
X647047Y1176180D03*
X643307Y1179921D03*
X647047Y1183661D03*
X639567D03*
X650787Y1187401D03*
X647047D03*
X643307D03*
X639567D03*
Y1176180D03*
X650787Y1179921D03*
X639567D03*
X643307Y1183661D03*
Y1176180D03*
X647047Y1179921D03*
X650787Y1183661D03*
Y1176180D03*
X647047Y1191141D03*
X643307D03*
X639567D03*
X647047Y1194881D03*
X643307D03*
X639567D03*
X647047Y1198621D03*
X643307D03*
X639567D03*
X650787Y1202362D03*
X647047D03*
X643307D03*
X639567D03*
X650787Y1191141D03*
Y1198621D03*
Y1194881D03*
Y1206102D03*
X647047D03*
X643307D03*
X639567D03*
X650787Y1209842D03*
X647047D03*
X643307D03*
X639567D03*
X650787Y1213582D03*
X643307D03*
X639567D03*
X650787Y1217322D03*
X639567D03*
X650787Y1221062D03*
X647047D03*
X643307D03*
X639567D03*
X647047Y1217322D03*
X643307D03*
X647047Y1213582D03*
Y1224803D03*
X639567D03*
X647047Y1228543D03*
X639567D03*
X650787Y1232283D03*
X643307D03*
X650787Y1236023D03*
X643307D03*
X639567Y1232283D03*
X643307Y1224803D03*
X647047Y1232283D03*
X650787Y1224803D03*
X639567Y1236023D03*
X643307Y1228543D03*
X647047Y1236023D03*
X650787Y1228543D03*
Y1239763D03*
X647047D03*
X643307D03*
X639567D03*
X647047Y1243503D03*
X639567D03*
X647047Y1247243D03*
X639567D03*
X650787Y1250984D03*
X643307D03*
X639567D03*
X643307Y1243503D03*
X647047Y1250984D03*
X650787Y1243503D03*
X643307Y1247243D03*
X650787D03*
Y1254724D03*
X643307D03*
X639567D03*
X647047D03*
X649990Y1350683D03*
Y1345691D03*
X650768Y1348187D03*
X649990Y1357603D03*
Y1362595D03*
X650768Y1360099D03*
X649990Y1381801D03*
X642706Y1374881D03*
Y1381801D03*
Y1369889D03*
X649990Y1374881D03*
Y1369889D03*
X637750Y1374881D03*
Y1381801D03*
Y1369889D03*
X650768Y1384297D03*
Y1372385D03*
X638528D03*
X641928D03*
X638528Y1384297D03*
X641928D03*
X649990Y1399079D03*
Y1394087D03*
X642706Y1386793D03*
X649990D03*
X637750Y1399079D03*
X642706Y1394087D03*
X637750D03*
X642706Y1399079D03*
X637750Y1386793D03*
X641928Y1396583D03*
X638528D03*
X650768D03*
X638528Y1408495D03*
X649990Y1405999D03*
Y1410991D03*
X637750D03*
X642706D03*
Y1405999D03*
X637750D03*
X641928Y1408495D03*
X650768D03*
X665748Y1075196D03*
X658268D03*
X654527D03*
X662008D03*
X669488D03*
X665748Y1078936D03*
X658268D03*
X669488Y1082677D03*
X662008D03*
X654527D03*
X669488Y1086417D03*
X662008D03*
X654527D03*
X669488Y1090157D03*
X665748D03*
X662008D03*
X658268D03*
X654527D03*
Y1078936D03*
X658268Y1086417D03*
X662008Y1078936D03*
X665748Y1086417D03*
X669488Y1078936D03*
X658268Y1082677D03*
X665748D03*
Y1093897D03*
X658268D03*
X665748Y1097637D03*
X658268D03*
X669488Y1101377D03*
X662008D03*
X654527D03*
X669488Y1105117D03*
X662008D03*
X654527D03*
Y1097637D03*
X658268Y1105117D03*
X662008Y1097637D03*
X665748Y1105117D03*
X669488Y1097637D03*
X654527Y1093897D03*
X658268Y1101377D03*
X662008Y1093897D03*
X665748Y1101377D03*
X669488Y1093897D03*
Y1108858D03*
X665748D03*
X662008D03*
X658268D03*
X654527D03*
X669488Y1120078D03*
X665748D03*
X662008D03*
X658268D03*
X654527D03*
X669488Y1123818D03*
X665748D03*
X662008D03*
X658268D03*
X654527D03*
X658268Y1112598D03*
X662008Y1116338D03*
X658268D03*
X662008Y1112598D03*
X665748Y1116338D03*
Y1112598D03*
X669488Y1116338D03*
X654527D03*
Y1112598D03*
X669488D03*
Y1127558D03*
X665748D03*
X662008D03*
X658268D03*
X654527D03*
Y1131299D03*
X669488Y1135039D03*
X665748D03*
X662008D03*
X658268D03*
X654527D03*
Y1138779D03*
X669488Y1131299D03*
X665748D03*
X662008D03*
X658268D03*
X669488Y1138779D03*
X665748D03*
X662008D03*
X658268D03*
X669488Y1142519D03*
X665748D03*
X662008D03*
X658268D03*
X654527Y1146259D03*
X669488Y1149999D03*
X665748D03*
X662008D03*
X658268D03*
X654527Y1153740D03*
X669488Y1146259D03*
X665748D03*
X662008D03*
X658268D03*
X669488Y1153740D03*
X665748D03*
X662008D03*
X658268D03*
X654527Y1142519D03*
Y1149999D03*
X665748Y1157480D03*
X658268D03*
X669488Y1161220D03*
X662008D03*
X654527D03*
X665748Y1164960D03*
X658268D03*
X669488Y1168700D03*
X662008D03*
X654527D03*
X665748Y1172440D03*
X658268D03*
X669488Y1157480D03*
X662008D03*
X654527D03*
X665748Y1161220D03*
X658268D03*
X669488Y1164960D03*
X662008D03*
X654527D03*
X665748Y1168700D03*
X658268D03*
X669488Y1172440D03*
X662008D03*
X654527D03*
Y1183661D03*
X669488Y1187401D03*
X665748D03*
X662008D03*
X658268D03*
X654527D03*
Y1176180D03*
X669488Y1179921D03*
X665748D03*
X662008D03*
X658268D03*
X669488Y1183661D03*
X665748D03*
X662008D03*
X658268D03*
X669488Y1176180D03*
X665748D03*
X662008D03*
X658268D03*
X654527Y1179921D03*
Y1191141D03*
X669488Y1194881D03*
X665748D03*
X662008D03*
X658268D03*
X654527D03*
Y1198621D03*
X669488Y1202362D03*
X665748D03*
X662008D03*
X658268D03*
X654527D03*
X669488Y1198621D03*
X665748D03*
X662008D03*
X658268D03*
X669488Y1191141D03*
X665748D03*
X662008D03*
X658268D03*
X669488Y1206102D03*
X665748D03*
X662008D03*
X658268D03*
X654527D03*
X669488Y1209842D03*
X665748D03*
X662008D03*
X658268D03*
X654527D03*
X669488Y1221062D03*
X665748D03*
X662008D03*
X658268D03*
X654527D03*
X662008Y1213582D03*
X658268D03*
X669488D03*
X665748Y1217322D03*
Y1213582D03*
X669488Y1217322D03*
X662008D03*
X654527Y1213582D03*
X658268Y1217322D03*
X654527D03*
X669488Y1224803D03*
X662008D03*
X654527D03*
X669488Y1228543D03*
X662008D03*
X654527D03*
X665748Y1232283D03*
X658268D03*
X665748Y1236023D03*
X658268D03*
X654527Y1232283D03*
X658268Y1224803D03*
X662008Y1232283D03*
X665748Y1224803D03*
X669488Y1232283D03*
X654527Y1236023D03*
X658268Y1228543D03*
X662008Y1236023D03*
X665748Y1228543D03*
X669488Y1236023D03*
Y1239763D03*
X665748D03*
X662008D03*
X658268D03*
X654527D03*
X669488Y1243503D03*
X662008D03*
X654527D03*
X669488Y1247243D03*
X662008D03*
X654527D03*
X665748Y1250984D03*
X658268D03*
X654527D03*
X658268Y1243503D03*
X662008Y1250984D03*
X665748Y1243503D03*
X669488Y1250984D03*
X658268Y1247243D03*
X665748D03*
Y1254724D03*
X658268D03*
X654527D03*
X662008D03*
X669488D03*
X654946Y1350683D03*
X662230D03*
X667186D03*
Y1345691D03*
X654946D03*
X662230D03*
X666408Y1348187D03*
X663008D03*
X654168D03*
X654946Y1357603D03*
Y1362595D03*
X662230Y1357603D03*
Y1362595D03*
X667186Y1357603D03*
Y1362595D03*
X666408Y1360099D03*
X663008D03*
X654168D03*
X662230Y1369889D03*
X667186Y1374881D03*
Y1381801D03*
Y1369889D03*
X662230Y1374881D03*
Y1381801D03*
X654946D03*
Y1369889D03*
Y1374881D03*
X654168Y1384297D03*
Y1372385D03*
X663008D03*
X666408D03*
X663008Y1384297D03*
X666408D03*
X667186Y1399079D03*
Y1393993D03*
X662230D03*
Y1399079D03*
X655046D03*
Y1394087D03*
X667186Y1386793D03*
X662230D03*
X654946D03*
X666408Y1396583D03*
X663008D03*
X654168D03*
X667186Y1410991D03*
Y1405999D03*
X662230D03*
Y1410991D03*
X655046Y1405999D03*
Y1410991D03*
X666408Y1408495D03*
X663008D03*
X654168D03*
X680709Y1075196D03*
X673228D03*
X676968D03*
X684449D03*
X680709Y1078936D03*
X673228D03*
X684449Y1082677D03*
X676968D03*
X684449Y1086417D03*
X676968D03*
X684449Y1090157D03*
X680709D03*
X676968D03*
X673228D03*
Y1086417D03*
X676968Y1078936D03*
X680709Y1086417D03*
X684449Y1078936D03*
X673228Y1082677D03*
X680709D03*
Y1093897D03*
X673228D03*
X680709Y1097637D03*
X673228D03*
X684449Y1101377D03*
X676968D03*
X684449Y1105117D03*
X676968D03*
X673228D03*
X676968Y1097637D03*
X680709Y1105117D03*
X684449Y1097637D03*
X673228Y1101377D03*
X676968Y1093897D03*
X680709Y1101377D03*
X684449Y1093897D03*
Y1108858D03*
X680709D03*
X676968D03*
X673228D03*
Y1112598D03*
Y1116338D03*
X684449Y1120078D03*
X680709D03*
X676968D03*
X673228D03*
X684449Y1123818D03*
X680709D03*
X676968D03*
X673228D03*
X684449Y1116338D03*
X680709Y1112598D03*
Y1116338D03*
X676968D03*
Y1112598D03*
X684449D03*
Y1127558D03*
X680709D03*
X676968D03*
X673228D03*
X684449Y1135039D03*
X680709D03*
X676968D03*
X673228D03*
X684449Y1131299D03*
X680709D03*
X676968D03*
X673228D03*
X684449Y1138779D03*
X680709D03*
X676968D03*
X673228D03*
X684449Y1142519D03*
X680709D03*
X676968D03*
X673228D03*
X684449Y1149999D03*
X680709D03*
X676968D03*
X673228D03*
X684449Y1146259D03*
X680709D03*
X676968D03*
X673228D03*
X684449Y1153740D03*
X680709D03*
X676968D03*
X673228D03*
X680709Y1157480D03*
X673228D03*
X684449Y1161220D03*
X676968D03*
X680709Y1164960D03*
X673228D03*
X684449Y1168700D03*
X676968D03*
X680709Y1172440D03*
X673228D03*
X684449Y1157480D03*
X676968D03*
X680709Y1161220D03*
X673228D03*
X684449Y1164960D03*
X676968D03*
X680709Y1168700D03*
X673228D03*
X684449Y1172440D03*
X676968D03*
X684449Y1187401D03*
X680709D03*
X676968D03*
X673228D03*
X684449Y1179921D03*
X680709D03*
X676968D03*
X673228D03*
X684449Y1183661D03*
X680709D03*
X676968D03*
X673228D03*
X684449Y1176180D03*
X680709D03*
X676968D03*
X673228D03*
X684449Y1194881D03*
X680709D03*
X676968D03*
X673228D03*
X684449Y1202362D03*
X680709D03*
X676968D03*
X673228D03*
X684449Y1198621D03*
X680709D03*
X676968D03*
X673228D03*
X684449Y1191141D03*
X680709D03*
X676968D03*
X673228D03*
X684449Y1206102D03*
X680709D03*
X676968D03*
X673228D03*
X684449Y1209842D03*
X680709D03*
X676968D03*
X673228D03*
X676968Y1213582D03*
Y1217322D03*
X684449Y1221062D03*
X680709D03*
X676968D03*
X673228D03*
X684449Y1217322D03*
Y1213582D03*
X680709D03*
Y1217322D03*
X673228D03*
Y1213582D03*
X684449Y1224803D03*
X676968D03*
X684449Y1228543D03*
X676968D03*
X680709Y1232283D03*
X673228D03*
X680709Y1236023D03*
X673228D03*
Y1224803D03*
X676968Y1232283D03*
X680709Y1224803D03*
X684449Y1232283D03*
X673228Y1228543D03*
X676968Y1236023D03*
X680709Y1228543D03*
X684449Y1236023D03*
Y1239763D03*
X680709D03*
X676968D03*
X673228D03*
X684449Y1243503D03*
X676968D03*
X684449Y1247243D03*
X676968D03*
X680709Y1250984D03*
X673228D03*
Y1243503D03*
X676968Y1250984D03*
X680709Y1243503D03*
X684449Y1250984D03*
X673228Y1247243D03*
X680709D03*
Y1254724D03*
X673228D03*
X676968D03*
X684449D03*
X679426Y1350683D03*
X674470Y1345691D03*
X679426D03*
X674470Y1350683D03*
X678648Y1348187D03*
X675248D03*
X674470Y1357603D03*
Y1362595D03*
X679426Y1357603D03*
Y1362595D03*
X678648Y1360099D03*
X675248D03*
X679426Y1374881D03*
X674470D03*
Y1381801D03*
X679426D03*
Y1369889D03*
X674470D03*
X675248Y1384297D03*
X678648D03*
Y1372385D03*
X675248D03*
X679426Y1399079D03*
X674470Y1394087D03*
X679426D03*
X674470Y1399079D03*
Y1386793D03*
X679426D03*
X675248Y1396583D03*
X678648D03*
X674470Y1405999D03*
X679426D03*
X674470Y1410991D03*
X679426D03*
X678648Y1408495D03*
X675248D03*
X695669Y1075196D03*
X688189D03*
X699409D03*
X691929D03*
X695669Y1078936D03*
X688189D03*
X699409Y1082677D03*
X691929D03*
X699409Y1086417D03*
X691929D03*
X699409Y1090157D03*
X695669D03*
X691929D03*
X688189D03*
Y1086417D03*
Y1082677D03*
X699409Y1078936D03*
X695669Y1086417D03*
X691929Y1078936D03*
X695669Y1082677D03*
Y1093897D03*
X688189D03*
X695669Y1097637D03*
X688189D03*
X699409Y1101377D03*
X691929D03*
X699409Y1105117D03*
X691929D03*
X688189D03*
Y1101377D03*
X699409Y1097637D03*
X695669Y1105117D03*
X691929Y1097637D03*
X699409Y1093897D03*
X695669Y1101377D03*
X691929Y1093897D03*
X699409Y1108858D03*
X695669D03*
X691929D03*
X688189D03*
Y1112598D03*
Y1116338D03*
X699409Y1120078D03*
X695669D03*
X691929D03*
X688189D03*
X699409Y1123818D03*
X695669D03*
X691929D03*
X688189D03*
X695669Y1116338D03*
X691929Y1112598D03*
X699409Y1116338D03*
X691929D03*
X699409Y1112598D03*
X695669D03*
X699409Y1127558D03*
X695669D03*
X691929D03*
X688189D03*
X699409Y1135039D03*
X695669D03*
X691929D03*
X688189D03*
X699409Y1131299D03*
X695669D03*
X691929D03*
X688189D03*
X699409Y1138779D03*
X695669D03*
X691929D03*
X688189D03*
X699409Y1142519D03*
X695669D03*
X691929D03*
X688189D03*
X699409Y1149999D03*
X695669D03*
X691929D03*
X688189D03*
X699409Y1146259D03*
X695669D03*
X691929D03*
X688189D03*
X699409Y1153740D03*
X695669D03*
X691929D03*
X688189D03*
X695669Y1157480D03*
X688189D03*
X699409Y1161220D03*
X691929D03*
X695669Y1164960D03*
X688189D03*
X699409Y1168700D03*
X691929D03*
X695669Y1172440D03*
X688189D03*
X699409Y1157480D03*
X691929D03*
X695669Y1161220D03*
X688189D03*
X699409Y1164960D03*
X691929D03*
X695669Y1168700D03*
X688189D03*
X699409Y1172440D03*
X691929D03*
X699409Y1187401D03*
X695669D03*
X691929D03*
X688189D03*
X699409Y1179921D03*
X695669D03*
X691929D03*
X688189D03*
X699409Y1183661D03*
X695669D03*
X691929D03*
X688189D03*
X699409Y1176180D03*
X695669D03*
X691929D03*
X688189D03*
X699409Y1194881D03*
X695669D03*
X691929D03*
X688189D03*
X699409Y1202362D03*
X695669D03*
X691929D03*
X688189D03*
X699409Y1198621D03*
X695669D03*
X691929D03*
X688189D03*
X699409Y1191141D03*
X695669D03*
X691929D03*
X688189D03*
X699409Y1206102D03*
X695669D03*
X691929D03*
X688189D03*
X699409Y1209842D03*
X695669D03*
X691929D03*
X688189D03*
X699409Y1221062D03*
X695669D03*
X691929D03*
X688189D03*
X695669Y1217322D03*
X688189Y1213582D03*
Y1217322D03*
X699409Y1213582D03*
X691929Y1217322D03*
Y1213582D03*
X699409Y1217322D03*
X695669Y1213582D03*
X699409Y1224803D03*
X691929D03*
X699409Y1228543D03*
X691929D03*
X695669Y1232283D03*
X688189D03*
X695669Y1236023D03*
X688189D03*
X699409Y1232283D03*
X695669Y1224803D03*
X691929Y1232283D03*
X688189Y1224803D03*
X699409Y1236023D03*
X695669Y1228543D03*
X691929Y1236023D03*
X688189Y1228543D03*
X699409Y1239763D03*
X695669D03*
X691929D03*
X688189D03*
X699409Y1243503D03*
X691929D03*
X699409Y1247243D03*
X691929D03*
X695669Y1250984D03*
X688189D03*
X699409D03*
X695669Y1243503D03*
X691929Y1250984D03*
X688189Y1243503D03*
X695669Y1247243D03*
X688189D03*
X695669Y1254724D03*
X688189D03*
X699409D03*
X691929D03*
X698950Y1350683D03*
Y1345597D03*
X686710Y1350683D03*
X691666D03*
X686710Y1345691D03*
X691666D03*
X690888Y1348187D03*
X687488D03*
X699728D03*
X698950Y1362595D03*
Y1357603D03*
X686710D03*
Y1362595D03*
X691666Y1357603D03*
Y1362595D03*
X687488Y1360099D03*
X690888D03*
X699728D03*
X698950Y1374881D03*
Y1381801D03*
Y1369889D03*
X691666D03*
Y1374881D03*
Y1381801D03*
X686710Y1374881D03*
Y1369889D03*
Y1381801D03*
X699728Y1372385D03*
Y1384297D03*
X690888Y1372385D03*
X687488D03*
Y1384297D03*
X690888D03*
X698950Y1399079D03*
Y1394087D03*
X686710D03*
Y1399079D03*
X691666Y1394087D03*
Y1399079D03*
X698950Y1386793D03*
X691666D03*
X686710D03*
X690888Y1396583D03*
X687488D03*
X699728D03*
X698950Y1405999D03*
Y1410991D03*
X686710D03*
X691666D03*
X686710Y1405999D03*
X691666D03*
X687488Y1408495D03*
X690888D03*
X699728D03*
X718110Y1075196D03*
X710630D03*
X703149D03*
X714370D03*
X706890D03*
X718110Y1078936D03*
X710630D03*
X703149D03*
X714370Y1082677D03*
X706890D03*
X714370Y1086417D03*
X706890D03*
X718110Y1090157D03*
X714370D03*
X710630D03*
X706890D03*
X703149D03*
X718110Y1086417D03*
X714370Y1078936D03*
X710630Y1086417D03*
X706890Y1078936D03*
X703149Y1086417D03*
X718110Y1082677D03*
X710630D03*
X703149D03*
X718110Y1093897D03*
X710630D03*
X703149D03*
X718110Y1097637D03*
X710630D03*
X703149D03*
X714370Y1101377D03*
X706890D03*
X714370Y1105117D03*
X706890D03*
X718110D03*
X714370Y1097637D03*
X710630Y1105117D03*
X706890Y1097637D03*
X703149Y1105117D03*
X718110Y1101377D03*
X714370Y1093897D03*
X710630Y1101377D03*
X706890Y1093897D03*
X703149Y1101377D03*
X718110Y1108858D03*
X714370D03*
X710630D03*
X706890D03*
X703149D03*
X718110Y1120078D03*
X714370D03*
X710630D03*
X706890D03*
X703149D03*
X718110Y1123818D03*
X714370D03*
X710630D03*
X706890D03*
X703149D03*
X710630Y1116338D03*
X706890D03*
X703149D03*
X706890Y1112598D03*
X714370Y1116338D03*
X703149Y1112598D03*
X718110D03*
X714370D03*
X718110Y1116338D03*
X710630Y1112598D03*
X718110Y1127558D03*
X714370D03*
X710630D03*
X706890D03*
X703149D03*
X718110Y1135039D03*
X714370D03*
X710630D03*
X706890D03*
X703149D03*
X718110Y1131299D03*
X714370D03*
X710630D03*
X706890D03*
X703149D03*
X718110Y1138779D03*
X714370D03*
X710630D03*
X706890D03*
X703149D03*
X718110Y1142519D03*
X714370D03*
X710630D03*
X706890D03*
X703149D03*
X718110Y1149999D03*
X714370D03*
X710630D03*
X706890D03*
X703149D03*
X718110Y1146259D03*
X714370D03*
X710630D03*
X706890D03*
X703149D03*
X718110Y1153740D03*
X714370D03*
X710630D03*
X706890D03*
X703149D03*
X718110Y1157480D03*
X710630D03*
X703149D03*
X714370Y1161220D03*
X706890D03*
X718110Y1164960D03*
X710630D03*
X703149D03*
X714370Y1168700D03*
X706890D03*
X718110Y1172440D03*
X710630D03*
X703149D03*
X718110Y1161220D03*
Y1168700D03*
X714370Y1157480D03*
X706890D03*
X710630Y1161220D03*
X703149D03*
X714370Y1164960D03*
X706890D03*
X710630Y1168700D03*
X703149D03*
X714370Y1172440D03*
X706890D03*
X718110Y1187401D03*
X714370D03*
X710630D03*
X706890D03*
X703149D03*
X718110Y1179921D03*
X714370D03*
X710630D03*
X706890D03*
X703149D03*
X718110Y1183661D03*
X714370D03*
X710630D03*
X706890D03*
X703149D03*
X718110Y1176180D03*
X714370D03*
X710630D03*
X706890D03*
X703149D03*
X718110Y1194881D03*
X714370D03*
X710630D03*
X706890D03*
X703149D03*
X718110Y1202362D03*
X714370D03*
X710630D03*
X706890D03*
X703149D03*
X718110Y1198621D03*
X714370D03*
X710630D03*
X706890D03*
X703149D03*
X718110Y1191141D03*
X714370D03*
X710630D03*
X706890D03*
X703149D03*
X718110Y1206102D03*
X714370D03*
X710630D03*
X706890D03*
X703149D03*
X718110Y1209842D03*
X714370D03*
X710630D03*
X706890D03*
X703149D03*
X718110Y1221062D03*
X714370D03*
X710630D03*
X706890D03*
X703149D03*
Y1213582D03*
X706890D03*
X718110D03*
X714370Y1217322D03*
X706890D03*
X714370Y1213582D03*
X710630D03*
X703149Y1217322D03*
X718110D03*
X710630D03*
X714370Y1224803D03*
X706890D03*
X714370Y1228543D03*
X706890D03*
X718110Y1232283D03*
X710630D03*
X703149D03*
X718110Y1236023D03*
X710630D03*
X703149D03*
X718110Y1224803D03*
X714370Y1232283D03*
X710630Y1224803D03*
X706890Y1232283D03*
X703149Y1224803D03*
X718110Y1228543D03*
X714370Y1236023D03*
X710630Y1228543D03*
X706890Y1236023D03*
X703149Y1228543D03*
X718110Y1239763D03*
X714370D03*
X710630D03*
X706890D03*
X703149D03*
X714370Y1243503D03*
X706890D03*
X714370Y1247243D03*
X706890D03*
X718110Y1250984D03*
X710630D03*
X703149D03*
X718110Y1243503D03*
X714370Y1250984D03*
X710630Y1243503D03*
X706890Y1250984D03*
X703149Y1243503D03*
X718110Y1247243D03*
X710630D03*
X703149D03*
X718110Y1254724D03*
X710630D03*
X703149D03*
X714370D03*
X706890D03*
X716146Y1350683D03*
X711190D03*
X716146Y1345691D03*
X711190D03*
X703906Y1350683D03*
Y1345597D03*
X715368Y1348187D03*
X711968D03*
X703128D03*
X716146Y1357603D03*
X711190D03*
Y1362595D03*
X716146D03*
X703906Y1357603D03*
Y1362595D03*
X715368Y1360099D03*
X711968D03*
X703128D03*
X716146Y1374881D03*
Y1381801D03*
Y1369889D03*
X711190D03*
Y1374881D03*
Y1381801D03*
X703906D03*
Y1369889D03*
Y1374881D03*
X703128Y1372385D03*
Y1384297D03*
X715368Y1372385D03*
X711968D03*
X715368Y1384297D03*
X711968D03*
X716146Y1399079D03*
X711190D03*
X716146Y1393993D03*
X711190D03*
X703906Y1394087D03*
Y1399079D03*
X716146Y1386793D03*
X711190D03*
X703906D03*
X715368Y1396583D03*
X711968D03*
X703128D03*
X716146Y1405999D03*
X711190D03*
X716146Y1410991D03*
X711190D03*
X703906Y1405999D03*
Y1410991D03*
X715368Y1408495D03*
X711968D03*
X703128D03*
X733071Y1075196D03*
X725590D03*
X729331D03*
X721850D03*
X733071Y1078936D03*
X725590D03*
X729331Y1082677D03*
X721850D03*
X729331Y1086417D03*
X721850D03*
X733071Y1090157D03*
X729331D03*
X725590D03*
X721850D03*
X733071Y1086417D03*
X729331Y1078936D03*
X725590Y1086417D03*
X721850Y1078936D03*
X733071Y1082677D03*
X725590D03*
X733071Y1093897D03*
X725590D03*
X733071Y1097637D03*
X725590D03*
X729331Y1101377D03*
X721850D03*
X729331Y1105117D03*
X721850D03*
X733071D03*
X729331Y1097637D03*
X725590Y1105117D03*
X721850Y1097637D03*
X733071Y1101377D03*
X729331Y1093897D03*
X725590Y1101377D03*
X721850Y1093897D03*
X733071Y1108858D03*
X729331D03*
X725590D03*
X721850D03*
X733071Y1120078D03*
X729331D03*
X725590D03*
X721850D03*
X729331Y1123818D03*
X725590D03*
X721850D03*
X733071D03*
X729331Y1116338D03*
X733071Y1112598D03*
X721850Y1116338D03*
Y1112598D03*
X733071Y1116338D03*
X729331Y1112598D03*
X725590Y1116338D03*
Y1112598D03*
X729331Y1127558D03*
X725590D03*
X721850D03*
X725590Y1131299D03*
X729331Y1135039D03*
X725590D03*
X721850D03*
X733071Y1138779D03*
X725590D03*
X729331Y1131299D03*
Y1138779D03*
X721850Y1131299D03*
Y1138779D03*
X733071Y1127558D03*
Y1135039D03*
Y1131299D03*
Y1142519D03*
X725590D03*
X721850D03*
X733071Y1146259D03*
X725590D03*
X733071Y1149999D03*
X729331D03*
X725590D03*
X721850D03*
X733071Y1153740D03*
X729331D03*
X725590D03*
X721850Y1146259D03*
Y1153740D03*
X729331Y1142519D03*
Y1146259D03*
Y1157480D03*
X725590D03*
X729331Y1161220D03*
Y1164960D03*
Y1168700D03*
Y1172440D03*
X725590D03*
Y1161220D03*
X721850D03*
X725590Y1164960D03*
X721850D03*
X725590Y1168700D03*
X721850D03*
Y1157480D03*
Y1172440D03*
X733071Y1157480D03*
Y1161220D03*
Y1164960D03*
Y1168700D03*
Y1172440D03*
Y1183661D03*
X725590D03*
X733071Y1187401D03*
X725590D03*
X721850D03*
X733071Y1176180D03*
X725590D03*
X733071Y1179921D03*
X721850D03*
Y1183661D03*
Y1176180D03*
X725590Y1179921D03*
X729331Y1183661D03*
Y1187401D03*
Y1179921D03*
Y1176180D03*
X733071Y1191141D03*
X725590D03*
X729331Y1194881D03*
X725590D03*
X721850D03*
X725590Y1198621D03*
X729331Y1202362D03*
X725590D03*
X721850D03*
X729331Y1198621D03*
Y1191141D03*
X721850Y1198621D03*
Y1191141D03*
X733071Y1198621D03*
Y1202362D03*
Y1194881D03*
X729331Y1206102D03*
X725590D03*
X721850D03*
X733071Y1209842D03*
X729331D03*
X725590D03*
X721850D03*
X733071Y1221062D03*
X729331D03*
X725590D03*
X721850D03*
X733071Y1206102D03*
X725590Y1217322D03*
X733071D03*
Y1213582D03*
X729331D03*
X725590D03*
X721850D03*
Y1217322D03*
X729331D03*
Y1224803D03*
X721850D03*
X729331Y1228543D03*
X721850D03*
X733071Y1232283D03*
X725590D03*
X733071Y1236023D03*
X725590D03*
X733071Y1224803D03*
X729331Y1232283D03*
X725590Y1224803D03*
X721850Y1232283D03*
X733071Y1228543D03*
X729331Y1236023D03*
X725590Y1228543D03*
X721850Y1236023D03*
X733071Y1239763D03*
X729331D03*
X725590D03*
X721850D03*
X729331Y1243503D03*
X721850D03*
X729331Y1247243D03*
X721850D03*
X733071Y1250984D03*
X725590D03*
X733071Y1243503D03*
X729331Y1250984D03*
X725590Y1243503D03*
X721850Y1250984D03*
X733071Y1247243D03*
X725590D03*
X733071Y1254724D03*
X725590D03*
X729331D03*
X721850D03*
X723430Y1350683D03*
X728386Y1345691D03*
X723430D03*
X728386Y1350683D03*
X727608Y1348187D03*
X724208D03*
X728386Y1357603D03*
Y1362595D03*
X723430Y1357603D03*
Y1362595D03*
X724208Y1360099D03*
X727608D03*
X728386Y1381801D03*
Y1374881D03*
Y1369889D03*
X723430D03*
Y1381801D03*
Y1374881D03*
X724208Y1372385D03*
Y1384297D03*
X727608D03*
Y1372385D03*
X728386Y1386793D03*
X723430D03*
X728386Y1398985D03*
Y1393993D03*
X723430Y1398985D03*
Y1393993D03*
X724208Y1396489D03*
X727608D03*
X728386Y1410897D03*
Y1405905D03*
X723430Y1410897D03*
Y1405905D03*
X724208Y1408401D03*
X727608D03*
X748031Y1075196D03*
X740551D03*
X744291D03*
X736811D03*
X748031Y1078936D03*
X740551D03*
X744291Y1082677D03*
X736811D03*
X744291Y1086417D03*
X736811D03*
X748031Y1090157D03*
X744291D03*
X740551D03*
X736811D03*
X748031Y1086417D03*
X744291Y1078936D03*
X740551Y1086417D03*
X736811Y1078936D03*
X748031Y1082677D03*
X740551D03*
X748031Y1093897D03*
X740551D03*
X748031Y1097637D03*
X740551D03*
X744291Y1101377D03*
X736811D03*
X744291Y1105117D03*
X736811D03*
X748031D03*
X744291Y1097637D03*
X740551Y1105117D03*
X736811Y1097637D03*
X748031Y1101377D03*
X744291Y1093897D03*
X740551Y1101377D03*
X736811Y1093897D03*
X748031Y1108858D03*
X744291D03*
X740551D03*
X736811D03*
X748031Y1112598D03*
Y1116338D03*
Y1120078D03*
X736811D03*
X748031Y1123818D03*
X736811D03*
X740551Y1120078D03*
X736811Y1112598D03*
Y1116338D03*
X740551D03*
Y1123818D03*
X744291Y1116338D03*
Y1123818D03*
Y1120078D03*
Y1112598D03*
X740551D03*
X748031Y1127558D03*
X736811D03*
X748031Y1131299D03*
X736811D03*
X748031Y1135039D03*
X736811D03*
X748031Y1138779D03*
X736811D03*
X744291Y1127558D03*
Y1131299D03*
X740551Y1127558D03*
Y1131299D03*
X744291Y1138779D03*
X740551Y1135039D03*
X744291D03*
X740551Y1138779D03*
X748031Y1142519D03*
X736811D03*
X748031Y1146259D03*
X736811D03*
X748031Y1149999D03*
X736811D03*
X748031Y1153740D03*
X744291D03*
X740551D03*
X736811D03*
X740551Y1142519D03*
X744291Y1149999D03*
X740551D03*
Y1146259D03*
X744291Y1142519D03*
Y1146259D03*
X748031Y1157480D03*
X744291D03*
X736811D03*
X748031Y1161220D03*
X744291D03*
X736811D03*
X748031Y1164960D03*
X744291D03*
X736811D03*
X748031Y1168700D03*
X744291D03*
X736811D03*
X748031Y1172440D03*
X744291D03*
X736811D03*
X740551Y1157480D03*
Y1161220D03*
Y1164960D03*
Y1168700D03*
Y1172440D03*
X748031Y1183661D03*
X740551D03*
X736811D03*
X748031Y1187401D03*
X736811D03*
X748031Y1176180D03*
X744291D03*
X740551D03*
X736811D03*
X748031Y1179921D03*
X740551D03*
X744291Y1187401D03*
X736811Y1179921D03*
X740551Y1187401D03*
X744291Y1179921D03*
Y1183661D03*
X748031Y1191141D03*
X740551D03*
X736811D03*
X748031Y1194881D03*
X736811D03*
X748031Y1198621D03*
X736811D03*
X748031Y1202362D03*
X736811D03*
X744291Y1191141D03*
X740551Y1194881D03*
Y1202362D03*
X744291Y1194881D03*
Y1202362D03*
Y1198621D03*
X740551D03*
X748031Y1206102D03*
X736811D03*
X748031Y1209842D03*
X736811D03*
X748031Y1213582D03*
Y1217322D03*
Y1221062D03*
X744291D03*
X740551D03*
X736811D03*
X744291Y1217322D03*
X740551Y1209842D03*
Y1213582D03*
X736811D03*
X740551Y1217322D03*
X744291Y1213582D03*
Y1209842D03*
X736811Y1217322D03*
X740551Y1206102D03*
X744291D03*
Y1224803D03*
X736811D03*
X744291Y1228543D03*
X736811D03*
X748031Y1232283D03*
X740551D03*
X748031Y1236023D03*
X740551D03*
X744291Y1232283D03*
X740551Y1224803D03*
X736811Y1232283D03*
X744291Y1236023D03*
X740551Y1228543D03*
X736811Y1236023D03*
X748031Y1224803D03*
Y1228543D03*
Y1239763D03*
X744291D03*
X740551D03*
X736811D03*
X744291Y1243503D03*
X736811D03*
X744291Y1247243D03*
X736811D03*
X748031Y1250984D03*
X740551D03*
X744291D03*
X740551Y1243503D03*
X736811Y1250984D03*
X740551Y1247243D03*
X748031Y1243503D03*
Y1247243D03*
Y1254724D03*
X740551D03*
X744291D03*
X736811D03*
X747910Y1345691D03*
Y1350683D03*
X735670D03*
X740626D03*
X735670Y1345691D03*
X740626D03*
X739848Y1348187D03*
X736448D03*
X748688D03*
X747910Y1357603D03*
Y1362595D03*
X735670Y1357603D03*
Y1362595D03*
X740626Y1357603D03*
Y1362595D03*
X736448Y1360099D03*
X739848D03*
X748688D03*
X747910Y1374881D03*
Y1381801D03*
Y1369889D03*
X740626Y1381801D03*
Y1369889D03*
Y1374881D03*
X735670Y1381801D03*
Y1369889D03*
Y1374881D03*
X748688Y1372385D03*
Y1384297D03*
X739848Y1372385D03*
X736448D03*
X739848Y1384297D03*
X736448D03*
X747910Y1386793D03*
X735670Y1393993D03*
X740626D03*
Y1398985D03*
X735670D03*
X740626Y1386793D03*
X735670D03*
X739848Y1396489D03*
X736448D03*
X735670Y1405905D03*
Y1410897D03*
X740626Y1405905D03*
Y1410897D03*
X739848Y1408401D03*
X736448D03*
X762992Y1075196D03*
X755512D03*
X751772D03*
X759252D03*
X766732D03*
X762992Y1078936D03*
X755512D03*
X766732Y1082677D03*
X759252D03*
X751772D03*
X766732Y1086417D03*
X759252D03*
X751772D03*
X766732Y1090157D03*
X762992D03*
X759252D03*
X755512D03*
X751772D03*
Y1078936D03*
X755512Y1086417D03*
X759252Y1078936D03*
X762992Y1086417D03*
X766732Y1078936D03*
X755512Y1082677D03*
X762992D03*
Y1093897D03*
X755512D03*
X762992Y1097637D03*
X755512D03*
X766732Y1101377D03*
X759252D03*
X751772D03*
X766732Y1105117D03*
X759252D03*
X751772D03*
Y1097637D03*
X755512Y1105117D03*
X759252Y1097637D03*
X762992Y1105117D03*
X766732Y1097637D03*
X751772Y1093897D03*
X755512Y1101377D03*
X759252Y1093897D03*
X762992Y1101377D03*
X766732Y1093897D03*
Y1108858D03*
X762992D03*
X759252D03*
X755512D03*
X751772D03*
X766732Y1112598D03*
X755512D03*
X751772D03*
X766732Y1116338D03*
X762992D03*
X759252D03*
X766732Y1120078D03*
X755512D03*
X751772D03*
X766732Y1123818D03*
X762992D03*
X759252D03*
Y1112598D03*
X751772Y1116338D03*
X759252Y1120078D03*
X751772Y1123818D03*
X762992Y1112598D03*
X755512Y1116338D03*
X762992Y1120078D03*
X755512Y1123818D03*
X766732Y1127558D03*
X755512D03*
X751772D03*
X766732Y1131299D03*
X762992D03*
X759252D03*
X766732Y1135039D03*
X755512D03*
X751772D03*
X766732Y1138779D03*
X762992D03*
X759252D03*
X751772D03*
X755512D03*
X759252Y1127558D03*
X751772Y1131299D03*
X759252Y1135039D03*
X762992Y1127558D03*
X755512Y1131299D03*
X762992Y1135039D03*
X766732Y1142519D03*
X755512D03*
X751772D03*
X766732Y1146259D03*
X762992D03*
X759252D03*
X766732Y1149999D03*
X755512D03*
X751772D03*
X766732Y1153740D03*
X762992D03*
X759252D03*
Y1142519D03*
X751772Y1146259D03*
X759252Y1149999D03*
X751772Y1153740D03*
X762992Y1142519D03*
X755512Y1146259D03*
X762992Y1149999D03*
X755512Y1153740D03*
X766732Y1157480D03*
X755512D03*
X751772D03*
X766732Y1161220D03*
X762992D03*
X759252D03*
X766732Y1164960D03*
X755512D03*
X751772D03*
X766732Y1168700D03*
X762992D03*
X759252D03*
X766732Y1172440D03*
X755512D03*
X751772D03*
X759252Y1157480D03*
X751772Y1161220D03*
X759252Y1164960D03*
X751772Y1168700D03*
X759252Y1172440D03*
X762992Y1157480D03*
X755512Y1161220D03*
X762992Y1164960D03*
X755512Y1168700D03*
X762992Y1172440D03*
X766732Y1183661D03*
X762992D03*
X759252D03*
X766732Y1187401D03*
X755512D03*
X751772D03*
X766732Y1176180D03*
X762992D03*
X759252D03*
X766732Y1179921D03*
X755512D03*
X751772D03*
Y1176180D03*
X759252Y1179921D03*
X751772Y1183661D03*
X759252Y1187401D03*
X755512Y1176180D03*
X762992Y1179921D03*
X755512Y1183661D03*
X762992Y1187401D03*
X766732Y1191141D03*
X762992D03*
X759252D03*
X766732Y1194881D03*
X755512D03*
X751772D03*
X766732Y1198621D03*
X762992D03*
X759252D03*
X766732Y1202362D03*
X755512D03*
X751772D03*
Y1191141D03*
X759252Y1194881D03*
X755512Y1191141D03*
X762992Y1194881D03*
X759252Y1202362D03*
X751772Y1198621D03*
X762992Y1202362D03*
X755512Y1198621D03*
X766732Y1206102D03*
X762992D03*
X759252D03*
X766732Y1209842D03*
X755512D03*
X751772D03*
X766732Y1213582D03*
X762992D03*
X759252D03*
X766732Y1217322D03*
X755512D03*
X751772D03*
X766732Y1221062D03*
X762992D03*
X759252D03*
X755512D03*
X751772D03*
X759252Y1217322D03*
X751772Y1213582D03*
X759252Y1209842D03*
X751772Y1206102D03*
X762992Y1217322D03*
X755512Y1213582D03*
X762992Y1209842D03*
X755512Y1206102D03*
X766732Y1224803D03*
X759252D03*
X751772D03*
X766732Y1228543D03*
X759252D03*
X751772D03*
X762992Y1232283D03*
X755512D03*
X762992Y1236023D03*
X755512D03*
X751772Y1232283D03*
X755512Y1224803D03*
X759252Y1232283D03*
X762992Y1224803D03*
X766732Y1232283D03*
X751772Y1236023D03*
X755512Y1228543D03*
X759252Y1236023D03*
X762992Y1228543D03*
X766732Y1236023D03*
Y1239763D03*
X762992D03*
X759252D03*
X755512D03*
X751772D03*
X766732Y1243503D03*
X759252D03*
X751772D03*
X766732Y1247243D03*
X759252D03*
X751772D03*
X762992Y1250984D03*
X755512D03*
X751772D03*
X755512Y1243503D03*
X759252Y1250984D03*
X762992Y1243503D03*
X766732Y1250984D03*
X755512Y1247243D03*
X762992D03*
Y1254724D03*
X755512D03*
X751772D03*
X759252D03*
X766732D03*
X765106Y1350683D03*
Y1345597D03*
X760150D03*
Y1350683D03*
X752866Y1345691D03*
Y1350683D03*
X760928Y1348187D03*
X764328D03*
X752088D03*
X765106Y1362595D03*
Y1357603D03*
X760150D03*
Y1362595D03*
X752866Y1357603D03*
Y1362595D03*
X764328Y1360099D03*
X760928D03*
X752088D03*
X765106Y1374881D03*
Y1381801D03*
Y1369889D03*
X760150Y1374881D03*
Y1381801D03*
Y1369889D03*
X752866Y1374881D03*
Y1381801D03*
Y1369889D03*
X752088Y1372385D03*
Y1384297D03*
X764328Y1372385D03*
X760928D03*
X764328Y1384297D03*
X760928D03*
X765106Y1386793D03*
X760150D03*
X752866D03*
X777953Y1075196D03*
X770472D03*
X774212D03*
X781693Y1078936D03*
X777953D03*
X770472D03*
X774212Y1082677D03*
X781693Y1086417D03*
X777953D03*
X774212D03*
Y1090157D03*
X770472D03*
X777953D03*
X781693D03*
X774212Y1078936D03*
X777953Y1082677D03*
X770472Y1086417D03*
X781693Y1082677D03*
X770472D03*
X781693Y1093897D03*
X777953D03*
X770472D03*
X781693Y1097637D03*
X777953D03*
X770472D03*
X774212Y1101377D03*
X781693Y1105117D03*
X777953D03*
X774212D03*
Y1097637D03*
X777953Y1101377D03*
X770472Y1105117D03*
X774212Y1093897D03*
X781693Y1101377D03*
X770472D03*
X774212Y1108858D03*
X770472D03*
X781693Y1112598D03*
X777953D03*
X774212Y1116338D03*
X770472D03*
X781693Y1120078D03*
X777953D03*
X774212Y1123818D03*
X770472D03*
X777953Y1108858D03*
X770472Y1112598D03*
X777953Y1116338D03*
X770472Y1120078D03*
X777953Y1123818D03*
X781693Y1108858D03*
X774212Y1112598D03*
X781693Y1116338D03*
X774212Y1120078D03*
X781693Y1123818D03*
Y1127558D03*
X777953D03*
X774212Y1131299D03*
X770472D03*
X781693Y1135039D03*
X777953D03*
X774212Y1138779D03*
X770472D03*
X777953D03*
X781693D03*
X770472Y1127558D03*
X777953Y1131299D03*
X770472Y1135039D03*
X774212Y1127558D03*
X781693Y1131299D03*
X774212Y1135039D03*
X781693Y1142519D03*
X777953D03*
X774212Y1146259D03*
X770472D03*
X781693Y1149999D03*
X777953D03*
X774212Y1153740D03*
X770472D03*
Y1142519D03*
X777953Y1146259D03*
X770472Y1149999D03*
X777953Y1153740D03*
X774212Y1142519D03*
X781693Y1146259D03*
X774212Y1149999D03*
X781693Y1153740D03*
Y1157480D03*
X777953D03*
X774212Y1161220D03*
X770472D03*
X781693Y1164960D03*
X777953D03*
X774212Y1168700D03*
X770472D03*
X781693Y1172440D03*
X777953D03*
X770472Y1157480D03*
X777953Y1161220D03*
X770472Y1164960D03*
X777953Y1168700D03*
X770472Y1172440D03*
X774212Y1157480D03*
X781693Y1161220D03*
X774212Y1164960D03*
X781693Y1168700D03*
X774212Y1172440D03*
Y1183661D03*
X770472D03*
X781693Y1187401D03*
X777953D03*
X774212Y1176180D03*
X770472D03*
X781693Y1179921D03*
X777953D03*
Y1176180D03*
X770472Y1179921D03*
X777953Y1183661D03*
X770472Y1187401D03*
X781693Y1176180D03*
X774212Y1179921D03*
X781693Y1183661D03*
X774212Y1187401D03*
Y1191141D03*
X770472D03*
X781693Y1194881D03*
X777953D03*
X774212Y1198621D03*
X770472D03*
X781693Y1202362D03*
X777953D03*
Y1191141D03*
X770472Y1194881D03*
X781693Y1191141D03*
X774212Y1194881D03*
X770472Y1202362D03*
X777953Y1198621D03*
X774212Y1202362D03*
X781693Y1198621D03*
X774212Y1206102D03*
X770472D03*
X781693Y1209842D03*
X777953D03*
X774212Y1213582D03*
X770472D03*
X781693Y1217322D03*
X777953D03*
X774212Y1221062D03*
X770472D03*
X777953D03*
X770472Y1217322D03*
X777953Y1213582D03*
X770472Y1209842D03*
X777953Y1206102D03*
X781693Y1221062D03*
X774212Y1217322D03*
X781693Y1213582D03*
X774212Y1209842D03*
X781693Y1206102D03*
Y1224803D03*
X777953D03*
X774212D03*
Y1228543D03*
X781693Y1232283D03*
X777953D03*
X770472D03*
X781693Y1236023D03*
X777953D03*
X770472D03*
Y1224803D03*
X774212Y1232283D03*
X777953Y1228543D03*
X770472D03*
X774212Y1236023D03*
X781693Y1228543D03*
X774212Y1239763D03*
X770472D03*
X781693Y1243503D03*
X777953D03*
X774212D03*
Y1247243D03*
X781693Y1250984D03*
X777953D03*
X770472D03*
X777953Y1239763D03*
X781693D03*
X770472Y1243503D03*
X774212Y1250984D03*
X777953Y1247243D03*
X770472D03*
X781693D03*
X777953Y1254724D03*
X770472D03*
X774212D03*
X772390Y1350683D03*
X777346D03*
Y1345691D03*
X772390D03*
X776568Y1348187D03*
X773168D03*
X772390Y1357603D03*
Y1362595D03*
X777346Y1357603D03*
Y1362595D03*
X773168Y1360099D03*
X776568D03*
X878220Y848442D03*
Y845293D03*
Y835844D03*
Y851592D03*
X877800Y876500D03*
X897118Y848442D03*
X881370Y835844D03*
X893968Y845293D03*
X884519Y848442D03*
X897118Y842143D03*
X893968D03*
X887669Y848442D03*
X886093Y835318D03*
X897118Y845293D03*
X893968Y838994D03*
X890818Y842143D03*
X893968Y835846D03*
X887669Y845293D03*
X890818D03*
X893968Y848442D03*
X884519Y845293D03*
X881370D03*
X884519Y842143D03*
X887669D03*
X881370Y848442D03*
X890818D03*
X897118Y857891D03*
Y864189D03*
Y854742D03*
X893968Y864189D03*
Y857891D03*
Y854742D03*
X887669Y851592D03*
X890818Y854742D03*
X887669D03*
X897118Y851592D03*
X890818Y864189D03*
Y857891D03*
X887669Y864189D03*
X884519Y854742D03*
Y851592D03*
Y857891D03*
X887669D03*
X890818Y851592D03*
X893967Y851591D03*
X881370Y851592D03*
X897118Y873638D03*
Y870488D03*
Y867338D03*
X893968Y870488D03*
Y873638D03*
Y867338D03*
X887669Y876787D03*
Y867338D03*
X890818Y870488D03*
X887669D03*
X897118Y876787D03*
X890818Y867338D03*
X881370D03*
X897118Y879937D03*
X884519Y873638D03*
X887669D03*
X884519Y876787D03*
X890818Y879937D03*
X881370Y876787D03*
X887669Y879937D03*
X884519Y867338D03*
X890818Y873638D03*
X893968Y876787D03*
Y879937D03*
X890818Y876787D03*
X884519Y879937D03*
Y870488D03*
X881370D03*
Y883086D03*
X884585Y886354D03*
X885126Y889742D03*
X881370Y886236D03*
X912864Y848442D03*
Y845293D03*
Y842143D03*
X909714Y845293D03*
Y842143D03*
Y838994D03*
X906565Y848442D03*
X900267D03*
X906565Y838994D03*
X900267Y838992D03*
X909714Y848442D03*
X906565Y842143D03*
X900267Y845293D03*
Y842143D03*
X906565Y845293D03*
X900266Y835844D03*
X900267Y864189D03*
X909714Y854742D03*
X906565Y857891D03*
X909714D03*
X906565Y864189D03*
X909714D03*
X906565Y854742D03*
X900267Y857891D03*
Y854742D03*
X912864Y851592D03*
Y864189D03*
Y857891D03*
Y854742D03*
X900267Y851592D03*
X906565D03*
X909714D03*
Y873638D03*
Y870488D03*
X906565Y873638D03*
Y870488D03*
Y867338D03*
X900267Y873638D03*
Y870488D03*
Y867338D03*
X909714D03*
X912864Y870488D03*
Y867338D03*
X909714Y876787D03*
X900267Y879937D03*
Y876787D03*
X906565D03*
X912864Y873638D03*
Y879937D03*
X909714D03*
X906565D03*
X912864Y876787D03*
X928612Y835844D03*
X922313Y845293D03*
X919163Y848442D03*
X916014D03*
Y842143D03*
X919163Y845293D03*
X922313Y842143D03*
X916014Y845293D03*
X919163Y835844D03*
Y838994D03*
Y842143D03*
X925462Y845293D03*
X922313Y851592D03*
X929611Y858669D03*
X919163Y854742D03*
Y857891D03*
X922313Y854742D03*
X916014Y857891D03*
Y854742D03*
X919163Y851592D03*
X916014D03*
Y864189D03*
X925462Y851592D03*
X922313Y864189D03*
Y857891D03*
X925462D03*
X928612Y864189D03*
X919163D03*
X925462D03*
X916014Y870488D03*
X925462Y873638D03*
X922313Y876787D03*
X928612Y870488D03*
X925462D03*
X916014Y873638D03*
X922313D03*
X916014Y876787D03*
X928612Y873638D03*
X925462Y876787D03*
X928612D03*
Y879937D03*
X916014D03*
X922313D03*
X919163D03*
X925462D03*
X916014Y867338D03*
X919163Y873638D03*
Y870488D03*
X922313D03*
X919163Y876787D03*
X922313Y867338D03*
X919163D03*
X925462D03*
X922313Y883086D03*
Y886236D03*
X925462D03*
X919163Y883086D03*
X928612Y886236D03*
X925462Y883086D03*
X928612D03*
X1059251Y1078936D03*
Y1086417D03*
Y1090157D03*
Y1082677D03*
Y1093897D03*
Y1097637D03*
Y1105117D03*
Y1101377D03*
Y1112598D03*
Y1120078D03*
Y1108858D03*
Y1116338D03*
Y1123818D03*
Y1127558D03*
Y1135039D03*
Y1131299D03*
Y1138779D03*
Y1142519D03*
Y1146259D03*
Y1153740D03*
Y1149999D03*
Y1161220D03*
Y1168700D03*
Y1157480D03*
Y1164960D03*
Y1172440D03*
Y1183661D03*
Y1187401D03*
Y1176180D03*
Y1179921D03*
Y1194881D03*
Y1202362D03*
Y1198621D03*
Y1191141D03*
Y1209842D03*
Y1217322D03*
Y1221062D03*
Y1213582D03*
Y1206102D03*
Y1224803D03*
Y1232283D03*
Y1236023D03*
Y1228543D03*
Y1243503D03*
Y1250984D03*
Y1239763D03*
Y1247243D03*
X1058891Y1345691D03*
Y1350683D03*
X1053935Y1345691D03*
Y1350683D03*
X1058113Y1348187D03*
X1054713D03*
X1058891Y1362595D03*
X1053935D03*
X1058891Y1357603D03*
X1053935D03*
X1058113Y1360099D03*
X1054713D03*
X1058891Y1381801D03*
Y1374881D03*
Y1369889D03*
X1053935Y1381801D03*
Y1374881D03*
Y1369889D03*
X1058113Y1372385D03*
X1054713D03*
Y1384297D03*
X1058113D03*
X1058891Y1386793D03*
X1053935D03*
X1070472Y1075196D03*
X1062991D03*
X1074212D03*
X1066732D03*
X1070472Y1078936D03*
X1062991D03*
X1074212Y1082677D03*
X1066732D03*
X1074212Y1086417D03*
X1066732D03*
X1062991D03*
X1074212Y1090157D03*
X1070472D03*
X1066732D03*
X1062991D03*
X1074212Y1078936D03*
X1070472Y1086417D03*
X1066732Y1078936D03*
X1062991Y1082677D03*
X1070472D03*
Y1093897D03*
X1062991D03*
X1070472Y1097637D03*
X1062991D03*
X1074212Y1101377D03*
X1066732D03*
X1074212Y1105117D03*
X1066732D03*
X1062991D03*
X1074212Y1097637D03*
X1070472Y1105117D03*
X1066732Y1097637D03*
X1062991Y1101377D03*
X1074212Y1093897D03*
X1070472Y1101377D03*
X1066732Y1093897D03*
X1074212Y1108858D03*
X1070472D03*
X1066732D03*
X1074212Y1112598D03*
X1062991D03*
X1074212Y1116338D03*
X1070472D03*
X1066732D03*
X1074212Y1120078D03*
X1062991D03*
X1074212Y1123818D03*
X1070472D03*
X1066732D03*
X1062991Y1108858D03*
X1070472Y1112598D03*
X1062991Y1116338D03*
X1070472Y1120078D03*
X1062991Y1123818D03*
X1066732Y1112598D03*
Y1120078D03*
X1074212Y1127558D03*
X1062991D03*
X1074212Y1131299D03*
X1070472D03*
X1066732D03*
X1074212Y1135039D03*
X1062991D03*
X1074212Y1138779D03*
X1070472D03*
X1066732D03*
X1070472Y1127558D03*
X1062991Y1131299D03*
X1070472Y1135039D03*
X1062991Y1138779D03*
X1066732Y1127558D03*
Y1135039D03*
X1074212Y1142519D03*
X1070472D03*
X1066732D03*
X1062991D03*
X1066732Y1146259D03*
X1062991D03*
X1074212Y1149999D03*
X1070472D03*
X1066732D03*
Y1153740D03*
X1062991D03*
X1070472Y1146259D03*
X1074212D03*
X1062991Y1149999D03*
X1074212Y1153740D03*
X1070472D03*
X1074212Y1157480D03*
X1070472D03*
X1066732D03*
Y1161220D03*
X1062991D03*
X1074212Y1164960D03*
X1070472D03*
X1066732D03*
Y1168700D03*
X1062991D03*
X1074212Y1172440D03*
X1070472D03*
X1066732D03*
X1062991Y1157480D03*
X1074212Y1161220D03*
X1070472D03*
X1062991Y1164960D03*
X1074212Y1168700D03*
X1070472D03*
X1062991Y1172440D03*
X1074212Y1183661D03*
X1070472D03*
X1066732D03*
X1062991D03*
X1074212Y1187401D03*
X1062991D03*
X1066732Y1176180D03*
X1062991D03*
X1074212Y1179921D03*
X1070472D03*
X1066732D03*
X1062991D03*
X1074212Y1176180D03*
X1070472D03*
Y1187401D03*
X1066732D03*
X1074212Y1191141D03*
X1070472D03*
X1066732D03*
X1074212Y1194881D03*
X1062991D03*
X1074212Y1198621D03*
X1070472D03*
X1066732D03*
X1074212Y1202362D03*
X1062991D03*
X1070472D03*
X1062991Y1198621D03*
X1070472Y1194881D03*
X1062991Y1191141D03*
X1066732Y1202362D03*
Y1194881D03*
X1074212Y1206102D03*
X1070472D03*
X1066732D03*
X1074212Y1209842D03*
X1062991D03*
X1074212Y1213582D03*
X1070472D03*
X1066732D03*
X1074212Y1217322D03*
X1062991D03*
X1074212Y1221062D03*
X1070472D03*
X1066732D03*
X1062991D03*
X1070472Y1217322D03*
X1062991Y1213582D03*
X1070472Y1209842D03*
X1062991Y1206102D03*
X1066732Y1217322D03*
Y1209842D03*
X1074212Y1224803D03*
X1066732D03*
X1062991D03*
X1074212Y1228543D03*
X1066732D03*
X1070472Y1232283D03*
X1062991D03*
X1070472Y1236023D03*
X1062991D03*
X1074212Y1232283D03*
X1070472Y1224803D03*
X1066732Y1232283D03*
X1062991Y1228543D03*
X1074212Y1236023D03*
X1070472Y1228543D03*
X1066732Y1236023D03*
X1074212Y1239763D03*
X1070472D03*
X1066732D03*
X1074212Y1243503D03*
X1066732D03*
X1062991D03*
X1074212Y1247243D03*
X1066732D03*
X1070472Y1250984D03*
X1062991D03*
Y1239763D03*
X1074212Y1250984D03*
X1070472Y1243503D03*
X1066732Y1250984D03*
X1062991Y1247243D03*
X1070472D03*
Y1254724D03*
X1062991D03*
X1074212D03*
X1066732D03*
X1066175Y1350683D03*
Y1345691D03*
X1071131Y1350683D03*
Y1345691D03*
X1066953Y1348187D03*
X1070353D03*
X1066175Y1357603D03*
Y1362595D03*
X1071131Y1357603D03*
Y1362595D03*
X1066953Y1360099D03*
X1070353D03*
X1066175Y1381801D03*
Y1369795D03*
Y1374881D03*
X1071131Y1381801D03*
Y1369795D03*
Y1374881D03*
X1066953Y1384297D03*
Y1372385D03*
X1070353D03*
Y1384297D03*
X1066175Y1393993D03*
Y1399079D03*
Y1386793D03*
X1071131Y1399079D03*
Y1393993D03*
Y1386793D03*
X1070353Y1396583D03*
X1066953D03*
X1066175Y1405999D03*
Y1410991D03*
X1071131Y1405999D03*
Y1410991D03*
X1066953Y1408495D03*
X1070353D03*
X1085432Y1075196D03*
X1077952D03*
X1081692D03*
X1089172D03*
X1085432Y1078936D03*
X1077952D03*
X1089172Y1082677D03*
X1081692D03*
X1089172Y1086417D03*
X1081692D03*
X1089172Y1090157D03*
X1085432D03*
X1081692D03*
X1077952D03*
X1085432Y1086417D03*
X1081692Y1078936D03*
X1077952Y1086417D03*
X1085432Y1082677D03*
X1077952D03*
X1089172Y1078936D03*
X1085432Y1093897D03*
X1077952D03*
X1085432Y1097637D03*
X1077952D03*
X1089172Y1101377D03*
X1081692D03*
X1089172Y1105117D03*
X1081692D03*
X1085432D03*
X1081692Y1097637D03*
X1077952Y1105117D03*
X1085432Y1101377D03*
X1081692Y1093897D03*
X1077952Y1101377D03*
X1089172Y1097637D03*
Y1093897D03*
Y1108858D03*
X1085432D03*
X1081692D03*
X1077952D03*
X1089172Y1112598D03*
X1085432D03*
X1081692Y1116338D03*
X1077952D03*
X1089172Y1120078D03*
X1085432D03*
X1081692Y1123818D03*
X1077952D03*
X1081692Y1112598D03*
X1089172Y1116338D03*
X1081692Y1120078D03*
X1089172Y1123818D03*
X1077952Y1112598D03*
X1085432Y1116338D03*
X1077952Y1120078D03*
X1085432Y1123818D03*
X1089172Y1127558D03*
X1085432D03*
X1081692Y1131299D03*
X1077952D03*
X1089172Y1135039D03*
X1085432D03*
X1081692Y1138779D03*
X1077952D03*
X1081692Y1127558D03*
X1089172Y1131299D03*
X1081692Y1135039D03*
X1089172Y1138779D03*
X1077952Y1127558D03*
X1085432Y1131299D03*
X1077952Y1135039D03*
X1085432Y1138779D03*
X1089172Y1142519D03*
X1085432D03*
X1081692D03*
X1077952D03*
X1089172Y1146259D03*
X1085432D03*
X1077952D03*
X1089172Y1149999D03*
X1077952D03*
X1089172Y1153740D03*
X1077952D03*
X1085432D03*
X1081692Y1149999D03*
X1085432D03*
X1081692Y1146259D03*
Y1153740D03*
X1089172Y1157480D03*
X1077952D03*
X1089172Y1161220D03*
X1077952D03*
X1089172Y1164960D03*
X1077952D03*
X1089172Y1168700D03*
X1077952D03*
X1089172Y1172440D03*
X1077952D03*
X1085432Y1164960D03*
Y1172440D03*
Y1168700D03*
X1081692Y1172440D03*
Y1168700D03*
Y1164960D03*
X1085432Y1157480D03*
Y1161220D03*
X1081692D03*
Y1157480D03*
X1089172Y1183661D03*
X1085432D03*
X1081692D03*
X1077952D03*
X1089172Y1187401D03*
X1085432D03*
X1089172Y1176180D03*
X1077952D03*
X1089172Y1179921D03*
X1085432D03*
X1081692D03*
X1077952D03*
X1081692Y1176180D03*
X1085432D03*
X1081692Y1187401D03*
X1077952D03*
X1081692Y1191141D03*
X1077952D03*
X1089172Y1194881D03*
X1085432D03*
X1081692Y1198621D03*
X1077952D03*
X1089172Y1202362D03*
X1085432D03*
X1081692D03*
X1089172Y1198621D03*
X1081692Y1194881D03*
X1089172Y1191141D03*
X1077952Y1202362D03*
X1085432Y1198621D03*
X1077952Y1194881D03*
X1085432Y1191141D03*
X1081692Y1206102D03*
X1077952D03*
X1089172Y1209842D03*
X1085432D03*
X1081692Y1213582D03*
X1077952D03*
X1089172Y1217322D03*
X1085432D03*
X1089172Y1221062D03*
X1085432D03*
X1081692D03*
X1077952D03*
X1081692Y1217322D03*
X1089172Y1213582D03*
X1081692Y1209842D03*
X1089172Y1206102D03*
X1077952Y1217322D03*
X1085432Y1213582D03*
X1077952Y1209842D03*
X1085432Y1206102D03*
X1089172Y1224803D03*
X1081692D03*
X1089172Y1228543D03*
X1081692D03*
X1085432Y1232283D03*
X1077952D03*
X1085432Y1236023D03*
X1077952D03*
X1081692Y1232283D03*
X1077952Y1224803D03*
X1081692Y1236023D03*
X1077952Y1228543D03*
X1085432Y1224803D03*
X1089172Y1232283D03*
X1085432Y1228543D03*
X1089172Y1236023D03*
Y1239763D03*
X1085432D03*
X1081692D03*
X1077952D03*
X1089172Y1243503D03*
X1081692D03*
X1089172Y1247243D03*
X1081692D03*
X1085432Y1250984D03*
X1077952D03*
X1081692D03*
X1077952Y1243503D03*
Y1247243D03*
X1085432Y1243503D03*
X1089172Y1250984D03*
X1085432Y1247243D03*
Y1254724D03*
X1077952D03*
X1081692D03*
X1089172D03*
X1090655Y1350683D03*
Y1345691D03*
X1083371D03*
Y1350683D03*
X1078415Y1345691D03*
Y1350683D03*
X1091433Y1348187D03*
X1082593D03*
X1079193D03*
X1090655Y1357603D03*
Y1362595D03*
X1083371Y1357603D03*
Y1362595D03*
X1078415D03*
Y1357603D03*
X1091433Y1360099D03*
X1082593D03*
X1079193D03*
X1090655Y1381801D03*
Y1374881D03*
Y1369889D03*
X1083371D03*
Y1374881D03*
Y1381801D03*
X1078415Y1369889D03*
Y1374881D03*
Y1381801D03*
X1079193Y1372385D03*
X1082593D03*
Y1384297D03*
X1079193D03*
X1091433D03*
Y1372385D03*
X1090655Y1394087D03*
Y1399079D03*
Y1386793D03*
X1083371D03*
Y1399079D03*
Y1394087D03*
X1078415Y1386793D03*
Y1394087D03*
Y1399079D03*
X1091433Y1396583D03*
X1082593D03*
X1079193D03*
X1090655Y1405999D03*
Y1410991D03*
X1083371Y1405999D03*
Y1410991D03*
X1078415Y1405999D03*
Y1410991D03*
X1091433Y1408495D03*
X1082593D03*
X1079193D03*
X1107873Y1075196D03*
X1100393D03*
X1092913D03*
X1096653D03*
X1104133D03*
X1107873Y1078936D03*
X1100393D03*
X1092913D03*
X1104133Y1082677D03*
X1096653D03*
X1104133Y1086417D03*
X1096653D03*
X1107873Y1090157D03*
X1104133D03*
X1100393D03*
X1096653D03*
X1092913D03*
Y1086417D03*
X1096653Y1078936D03*
X1100393Y1086417D03*
X1104133Y1078936D03*
X1107873Y1086417D03*
X1092913Y1082677D03*
X1100393D03*
X1107873D03*
Y1093897D03*
X1100393D03*
X1092913D03*
X1107873Y1097637D03*
X1100393D03*
X1092913D03*
X1104133Y1101377D03*
X1096653D03*
X1104133Y1105117D03*
X1096653D03*
X1092913D03*
X1096653Y1097637D03*
X1100393Y1105117D03*
X1104133Y1097637D03*
X1107873Y1105117D03*
X1092913Y1101377D03*
X1096653Y1093897D03*
X1100393Y1101377D03*
X1104133Y1093897D03*
X1107873Y1101377D03*
Y1108858D03*
X1104133D03*
X1100393D03*
X1096653D03*
X1092913D03*
X1096653Y1112598D03*
X1092913D03*
X1096653Y1116338D03*
X1092913D03*
X1107873Y1120078D03*
X1104133D03*
X1100393D03*
X1096653D03*
X1092913D03*
X1107873Y1123818D03*
X1104133D03*
X1100393D03*
X1096653D03*
X1092913D03*
X1104133Y1116338D03*
X1100393D03*
Y1112598D03*
X1104133D03*
X1107873Y1116338D03*
Y1112598D03*
Y1127558D03*
X1104133D03*
X1100393D03*
X1096653D03*
X1092913D03*
X1104133Y1131299D03*
X1100393D03*
X1096653D03*
X1092913D03*
X1104133Y1135039D03*
X1100393D03*
X1096653D03*
X1092913D03*
X1104133Y1138779D03*
X1096653D03*
X1092913D03*
X1100393D03*
X1107873D03*
Y1131299D03*
Y1135039D03*
X1100393Y1149999D03*
X1104133Y1153740D03*
Y1142519D03*
X1100393D03*
X1096653D03*
X1092913D03*
X1104133Y1146259D03*
X1096653D03*
X1107873Y1149999D03*
X1096653D03*
Y1153740D03*
X1107873Y1142519D03*
X1100393Y1146259D03*
X1092913D03*
Y1149999D03*
Y1153740D03*
X1104133Y1149999D03*
X1100393Y1153740D03*
X1107873Y1146259D03*
Y1153740D03*
X1100393Y1157480D03*
X1104133Y1161220D03*
X1100393Y1164960D03*
X1104133Y1168700D03*
X1100393Y1172440D03*
X1107873Y1157480D03*
X1096653D03*
X1092913D03*
X1096653Y1161220D03*
X1107873Y1164960D03*
X1096653D03*
Y1168700D03*
X1092913D03*
X1107873Y1172440D03*
X1096653D03*
X1092913D03*
Y1161220D03*
Y1164960D03*
X1104133Y1172440D03*
Y1157480D03*
X1100393Y1161220D03*
X1104133Y1164960D03*
X1100393Y1168700D03*
X1107873Y1161220D03*
Y1168700D03*
X1104133Y1176180D03*
X1100393Y1179921D03*
X1104133Y1183661D03*
X1096653D03*
X1092913D03*
X1107873Y1187401D03*
X1104133D03*
X1100393D03*
X1096653D03*
X1092913D03*
X1096653Y1176180D03*
X1107873Y1179921D03*
X1096653D03*
X1092913Y1176180D03*
Y1179921D03*
X1100393Y1183661D03*
Y1176180D03*
X1104133Y1179921D03*
X1107873Y1183661D03*
Y1176180D03*
X1104133Y1191141D03*
X1100393D03*
X1096653D03*
X1092913D03*
X1104133Y1194881D03*
X1100393D03*
X1096653D03*
X1092913D03*
X1104133Y1198621D03*
X1100393D03*
X1096653D03*
X1092913D03*
X1107873Y1202362D03*
X1104133D03*
X1100393D03*
X1096653D03*
X1092913D03*
X1107873Y1191141D03*
Y1198621D03*
Y1194881D03*
Y1206102D03*
X1104133D03*
X1100393D03*
X1096653D03*
X1092913D03*
X1107873Y1209842D03*
X1104133D03*
X1100393D03*
X1096653D03*
X1092913D03*
X1107873Y1213582D03*
X1100393D03*
X1096653D03*
X1092913D03*
X1107873Y1217322D03*
X1096653D03*
X1092913D03*
X1107873Y1221062D03*
X1104133D03*
X1100393D03*
X1096653D03*
X1092913D03*
X1104133Y1217322D03*
X1100393D03*
X1104133Y1213582D03*
Y1224803D03*
X1096653D03*
X1104133Y1228543D03*
X1096653D03*
X1107873Y1232283D03*
X1100393D03*
X1092913D03*
X1107873Y1236023D03*
X1100393D03*
X1092913D03*
Y1224803D03*
X1096653Y1232283D03*
X1100393Y1224803D03*
X1104133Y1232283D03*
X1107873Y1224803D03*
X1092913Y1228543D03*
X1096653Y1236023D03*
X1100393Y1228543D03*
X1104133Y1236023D03*
X1107873Y1228543D03*
Y1239763D03*
X1104133D03*
X1100393D03*
X1096653D03*
X1092913D03*
X1104133Y1243503D03*
X1096653D03*
X1104133Y1247243D03*
X1096653D03*
X1107873Y1250984D03*
X1100393D03*
X1092913D03*
Y1243503D03*
X1096653Y1250984D03*
X1100393Y1243503D03*
X1104133Y1250984D03*
X1107873Y1243503D03*
X1092913Y1247243D03*
X1100393D03*
X1107873D03*
Y1254724D03*
X1100393D03*
X1092913D03*
X1096653D03*
X1104133D03*
X1107851Y1345691D03*
X1102895Y1350683D03*
Y1345691D03*
X1107851Y1350683D03*
X1095611D03*
Y1345691D03*
X1094833Y1348187D03*
X1107073D03*
X1103673D03*
X1107851Y1357603D03*
X1102895Y1362595D03*
Y1357603D03*
X1107851Y1362595D03*
X1095611Y1357603D03*
Y1362595D03*
X1094833Y1360099D03*
X1103673D03*
X1107073D03*
X1107851Y1369889D03*
Y1374881D03*
Y1381801D03*
X1102895Y1374881D03*
Y1369889D03*
Y1381801D03*
X1095611D03*
Y1374881D03*
Y1369889D03*
X1107073Y1372385D03*
X1103673D03*
X1107073Y1384297D03*
X1103673D03*
X1094833D03*
Y1372385D03*
X1107851Y1386793D03*
Y1394087D03*
Y1399079D03*
X1102895Y1386793D03*
Y1394087D03*
Y1399079D03*
X1095611D03*
Y1394087D03*
Y1386793D03*
X1094833Y1396583D03*
X1107073D03*
X1103673D03*
X1107851Y1405999D03*
Y1410991D03*
X1102895Y1405999D03*
Y1410991D03*
X1095611Y1405999D03*
Y1410991D03*
X1094833Y1408495D03*
X1107073D03*
X1103673D03*
X1122834Y1075196D03*
X1115354D03*
X1111613D03*
X1119094D03*
X1122834Y1078936D03*
X1115354D03*
X1119094Y1082677D03*
X1111613D03*
X1119094Y1086417D03*
X1111613D03*
X1122834Y1090157D03*
X1119094D03*
X1115354D03*
X1111613D03*
Y1078936D03*
X1115354Y1086417D03*
X1119094Y1078936D03*
X1122834Y1086417D03*
X1115354Y1082677D03*
X1122834D03*
Y1093897D03*
X1115354D03*
X1122834Y1097637D03*
X1115354D03*
X1119094Y1101377D03*
X1111613D03*
X1119094Y1105117D03*
X1111613D03*
Y1097637D03*
X1115354Y1105117D03*
X1119094Y1097637D03*
X1122834Y1105117D03*
X1111613Y1093897D03*
X1115354Y1101377D03*
X1119094Y1093897D03*
X1122834Y1101377D03*
Y1108858D03*
X1119094D03*
X1115354D03*
X1111613D03*
X1122834Y1120078D03*
X1119094D03*
X1115354D03*
X1111613D03*
X1122834Y1123818D03*
X1119094D03*
X1115354D03*
X1111613D03*
X1115354Y1112598D03*
X1119094Y1116338D03*
X1115354D03*
X1119094Y1112598D03*
X1122834Y1116338D03*
Y1112598D03*
X1111613Y1116338D03*
Y1112598D03*
X1122834Y1127558D03*
X1119094D03*
X1115354D03*
X1111613D03*
Y1131299D03*
X1122834Y1135039D03*
X1119094D03*
X1115354D03*
X1111613D03*
Y1138779D03*
X1122834Y1131299D03*
X1119094D03*
X1115354D03*
X1122834Y1138779D03*
X1119094D03*
X1115354D03*
X1122834Y1142519D03*
X1119094D03*
X1115354D03*
X1111613Y1146259D03*
X1122834Y1149999D03*
X1119094D03*
X1115354D03*
X1111613Y1153740D03*
X1122834Y1146259D03*
X1119094D03*
X1115354D03*
X1122834Y1153740D03*
X1119094D03*
X1115354D03*
X1111613Y1142519D03*
Y1149999D03*
X1122834Y1157480D03*
X1115354D03*
X1119094Y1161220D03*
X1111613D03*
X1122834Y1164960D03*
X1115354D03*
X1119094Y1168700D03*
X1111613D03*
X1122834Y1172440D03*
X1115354D03*
X1119094Y1157480D03*
X1111613D03*
X1122834Y1161220D03*
X1115354D03*
X1119094Y1164960D03*
X1111613D03*
X1122834Y1168700D03*
X1115354D03*
X1119094Y1172440D03*
X1111613D03*
Y1183661D03*
X1122834Y1187401D03*
X1119094D03*
X1115354D03*
X1111613D03*
Y1176180D03*
X1122834Y1179921D03*
X1119094D03*
X1115354D03*
X1122834Y1183661D03*
X1119094D03*
X1115354D03*
X1122834Y1176180D03*
X1119094D03*
X1115354D03*
X1111613Y1179921D03*
Y1191141D03*
X1122834Y1194881D03*
X1119094D03*
X1115354D03*
X1111613D03*
Y1198621D03*
X1122834Y1202362D03*
X1119094D03*
X1115354D03*
X1111613D03*
X1122834Y1198621D03*
X1119094D03*
X1115354D03*
X1122834Y1191141D03*
X1119094D03*
X1115354D03*
X1122834Y1206102D03*
X1119094D03*
X1115354D03*
X1111613D03*
X1122834Y1209842D03*
X1119094D03*
X1115354D03*
X1111613D03*
X1122834Y1221062D03*
X1119094D03*
X1115354D03*
X1111613D03*
X1119094Y1213582D03*
X1115354D03*
X1122834Y1217322D03*
Y1213582D03*
X1119094Y1217322D03*
X1111613Y1213582D03*
X1115354Y1217322D03*
X1111613D03*
X1119094Y1224803D03*
X1111613D03*
X1119094Y1228543D03*
X1111613D03*
X1122834Y1232283D03*
X1115354D03*
X1122834Y1236023D03*
X1115354D03*
X1111613Y1232283D03*
X1115354Y1224803D03*
X1119094Y1232283D03*
X1122834Y1224803D03*
X1111613Y1236023D03*
X1115354Y1228543D03*
X1119094Y1236023D03*
X1122834Y1228543D03*
Y1239763D03*
X1119094D03*
X1115354D03*
X1111613D03*
X1119094Y1243503D03*
X1111613D03*
X1119094Y1247243D03*
X1111613D03*
X1122834Y1250984D03*
X1115354D03*
X1111613D03*
X1115354Y1243503D03*
X1119094Y1250984D03*
X1122834Y1243503D03*
X1115354Y1247243D03*
X1122834D03*
Y1254724D03*
X1115354D03*
X1111613D03*
X1119094D03*
X1115135Y1345691D03*
Y1350683D03*
X1120091Y1345691D03*
Y1350683D03*
X1115913Y1348187D03*
X1119313D03*
X1115135Y1357603D03*
Y1362595D03*
X1120091Y1357603D03*
Y1362595D03*
X1115913Y1360099D03*
X1119313D03*
X1115135Y1374881D03*
Y1381801D03*
Y1369889D03*
X1120091D03*
Y1374881D03*
Y1381801D03*
X1119313Y1384297D03*
X1115913Y1372385D03*
X1119313D03*
X1115913Y1384297D03*
X1115135Y1394087D03*
Y1399079D03*
Y1386793D03*
X1120091Y1399079D03*
Y1394087D03*
Y1386793D03*
X1115913Y1396583D03*
X1119313D03*
X1115913Y1408495D03*
X1115135Y1405999D03*
Y1410991D03*
X1120091Y1405999D03*
Y1410991D03*
X1119313Y1408495D03*
X1137795Y1075196D03*
X1130314D03*
X1126574D03*
X1134054D03*
X1137795Y1078936D03*
X1130314D03*
X1134054Y1082677D03*
X1126574D03*
X1134054Y1086417D03*
X1126574D03*
X1137795Y1090157D03*
X1134054D03*
X1130314D03*
X1126574D03*
Y1078936D03*
X1130314Y1086417D03*
X1134054Y1078936D03*
X1137795Y1086417D03*
X1130314Y1082677D03*
X1137795D03*
Y1093897D03*
X1130314D03*
X1137795Y1097637D03*
X1130314D03*
X1134054Y1101377D03*
X1126574D03*
X1134054Y1105117D03*
X1126574D03*
Y1097637D03*
X1130314Y1105117D03*
X1134054Y1097637D03*
X1137795Y1105117D03*
X1126574Y1093897D03*
X1130314Y1101377D03*
X1134054Y1093897D03*
X1137795Y1101377D03*
Y1108858D03*
X1134054D03*
X1130314D03*
X1126574D03*
X1130314Y1112598D03*
Y1116338D03*
X1137795Y1120078D03*
X1134054D03*
X1130314D03*
X1126574D03*
X1137795Y1123818D03*
X1134054D03*
X1130314D03*
X1126574D03*
X1137795Y1112598D03*
Y1116338D03*
X1134054D03*
Y1112598D03*
X1126574Y1116338D03*
Y1112598D03*
X1137795Y1127558D03*
X1134054D03*
X1130314D03*
X1126574D03*
X1137795Y1135039D03*
X1134054D03*
X1130314D03*
X1126574D03*
X1137795Y1131299D03*
X1134054D03*
X1130314D03*
X1126574D03*
X1137795Y1138779D03*
X1134054D03*
X1130314D03*
X1126574D03*
X1137795Y1142519D03*
X1134054D03*
X1130314D03*
X1126574D03*
X1137795Y1149999D03*
X1134054D03*
X1130314D03*
X1126574D03*
X1137795Y1146259D03*
X1134054D03*
X1130314D03*
X1126574D03*
X1137795Y1153740D03*
X1134054D03*
X1130314D03*
X1126574D03*
X1137795Y1157480D03*
X1130314D03*
X1134054Y1161220D03*
X1126574D03*
X1137795Y1164960D03*
X1130314D03*
X1134054Y1168700D03*
X1126574D03*
X1137795Y1172440D03*
X1130314D03*
X1134054Y1157480D03*
X1126574D03*
X1137795Y1161220D03*
X1130314D03*
X1134054Y1164960D03*
X1126574D03*
X1137795Y1168700D03*
X1130314D03*
X1134054Y1172440D03*
X1126574D03*
X1137795Y1187401D03*
X1134054D03*
X1130314D03*
X1126574D03*
X1137795Y1179921D03*
X1134054D03*
X1130314D03*
X1126574D03*
X1137795Y1183661D03*
X1134054D03*
X1130314D03*
X1126574D03*
X1137795Y1176180D03*
X1134054D03*
X1130314D03*
X1126574D03*
X1137795Y1194881D03*
X1134054D03*
X1130314D03*
X1126574D03*
X1137795Y1202362D03*
X1134054D03*
X1130314D03*
X1126574D03*
X1137795Y1198621D03*
X1134054D03*
X1130314D03*
X1126574D03*
X1137795Y1191141D03*
X1134054D03*
X1130314D03*
X1126574D03*
X1137795Y1206102D03*
X1134054D03*
X1130314D03*
X1126574D03*
X1137795Y1209842D03*
X1134054D03*
X1130314D03*
X1126574D03*
X1134054Y1213582D03*
Y1217322D03*
X1137795Y1221062D03*
X1134054D03*
X1130314D03*
X1126574D03*
X1137795Y1213582D03*
Y1217322D03*
X1126574Y1213582D03*
X1130314Y1217322D03*
Y1213582D03*
X1126574Y1217322D03*
X1134054Y1224803D03*
X1126574D03*
X1134054Y1228543D03*
X1126574D03*
X1137795Y1232283D03*
X1130314D03*
X1137795Y1236023D03*
X1130314D03*
Y1224803D03*
X1134054Y1232283D03*
X1137795Y1224803D03*
X1126574Y1232283D03*
X1130314Y1228543D03*
X1134054Y1236023D03*
X1137795Y1228543D03*
X1126574Y1236023D03*
X1137795Y1239763D03*
X1134054D03*
X1130314D03*
X1126574D03*
X1134054Y1243503D03*
X1126574D03*
X1134054Y1247243D03*
X1126574D03*
X1137795Y1250984D03*
X1130314D03*
Y1243503D03*
X1134054Y1250984D03*
X1137795Y1243503D03*
X1126574Y1250984D03*
X1130314Y1247243D03*
X1137795D03*
Y1254724D03*
X1130314D03*
X1134054D03*
X1126574D03*
X1139615Y1350683D03*
Y1345691D03*
X1132331D03*
Y1350683D03*
X1127375D03*
Y1345691D03*
X1140393Y1348187D03*
X1131553D03*
X1128153D03*
X1140393Y1360099D03*
X1139615Y1357603D03*
Y1362595D03*
X1132331D03*
Y1357603D03*
X1127375D03*
Y1362595D03*
X1131553Y1360099D03*
X1128153D03*
Y1384297D03*
X1131553D03*
X1139615Y1374881D03*
Y1369889D03*
Y1381801D03*
X1132331Y1369889D03*
Y1381801D03*
Y1374881D03*
X1127375Y1369889D03*
Y1381801D03*
Y1374881D03*
X1128153Y1372385D03*
X1131553D03*
X1140393Y1384297D03*
Y1372385D03*
X1139615Y1394087D03*
Y1399079D03*
Y1386793D03*
X1132331D03*
Y1394087D03*
Y1399079D03*
X1127375Y1386793D03*
Y1394087D03*
Y1399079D03*
X1140393Y1396583D03*
X1131553D03*
X1128153D03*
X1139615Y1405999D03*
Y1410991D03*
X1132331Y1405999D03*
Y1410991D03*
X1127375Y1405999D03*
Y1410991D03*
X1140393Y1408495D03*
X1128153D03*
X1131553D03*
X1152755Y1075196D03*
X1145275D03*
X1141535D03*
X1156495D03*
X1149015D03*
X1152755Y1078936D03*
X1145275D03*
X1156495Y1082677D03*
X1149015D03*
X1141535D03*
X1156495Y1086417D03*
X1149015D03*
X1141535D03*
X1156495Y1090157D03*
X1152755D03*
X1149015D03*
X1145275D03*
X1141535D03*
Y1078936D03*
X1145275Y1086417D03*
Y1082677D03*
X1156495Y1078936D03*
X1152755Y1086417D03*
X1149015Y1078936D03*
X1152755Y1082677D03*
Y1093897D03*
X1145275D03*
X1152755Y1097637D03*
X1145275D03*
X1156495Y1101377D03*
X1149015D03*
X1141535D03*
X1156495Y1105117D03*
X1149015D03*
X1141535D03*
Y1097637D03*
X1145275Y1105117D03*
X1141535Y1093897D03*
X1145275Y1101377D03*
X1156495Y1097637D03*
X1152755Y1105117D03*
X1149015Y1097637D03*
X1156495Y1093897D03*
X1152755Y1101377D03*
X1149015Y1093897D03*
X1156495Y1108858D03*
X1152755D03*
X1149015D03*
X1145275D03*
X1141535D03*
X1145275Y1112598D03*
Y1116338D03*
X1156495Y1120078D03*
X1152755D03*
X1149015D03*
X1145275D03*
X1141535D03*
X1156495Y1123818D03*
X1152755D03*
X1149015D03*
X1145275D03*
X1141535D03*
Y1116338D03*
Y1112598D03*
X1152755Y1116338D03*
X1149015Y1112598D03*
X1156495Y1116338D03*
X1149015D03*
X1156495Y1112598D03*
X1152755D03*
X1156495Y1127558D03*
X1152755D03*
X1149015D03*
X1145275D03*
X1141535D03*
X1156495Y1135039D03*
X1152755D03*
X1149015D03*
X1145275D03*
X1141535D03*
X1156495Y1131299D03*
X1152755D03*
X1149015D03*
X1145275D03*
X1141535D03*
X1156495Y1138779D03*
X1152755D03*
X1149015D03*
X1145275D03*
X1141535D03*
X1156495Y1142519D03*
X1152755D03*
X1149015D03*
X1145275D03*
X1141535D03*
X1156495Y1149999D03*
X1152755D03*
X1149015D03*
X1145275D03*
X1141535D03*
X1156495Y1146259D03*
X1152755D03*
X1149015D03*
X1145275D03*
X1141535D03*
X1156495Y1153740D03*
X1152755D03*
X1149015D03*
X1145275D03*
X1141535D03*
X1152755Y1157480D03*
X1145275D03*
X1156495Y1161220D03*
X1149015D03*
X1141535D03*
X1152755Y1164960D03*
X1145275D03*
X1156495Y1168700D03*
X1149015D03*
X1141535D03*
X1152755Y1172440D03*
X1145275D03*
X1156495Y1157480D03*
X1149015D03*
X1141535D03*
X1152755Y1161220D03*
X1145275D03*
X1156495Y1164960D03*
X1149015D03*
X1141535D03*
X1152755Y1168700D03*
X1145275D03*
X1156495Y1172440D03*
X1149015D03*
X1141535D03*
X1156495Y1187401D03*
X1152755D03*
X1149015D03*
X1145275D03*
X1141535D03*
X1156495Y1179921D03*
X1152755D03*
X1149015D03*
X1145275D03*
X1141535D03*
X1156495Y1183661D03*
X1152755D03*
X1149015D03*
X1145275D03*
X1141535D03*
X1156495Y1176180D03*
X1152755D03*
X1149015D03*
X1145275D03*
X1141535D03*
X1156495Y1194881D03*
X1152755D03*
X1149015D03*
X1145275D03*
X1141535D03*
X1156495Y1202362D03*
X1152755D03*
X1149015D03*
X1145275D03*
X1141535D03*
X1156495Y1198621D03*
X1152755D03*
X1149015D03*
X1145275D03*
X1141535D03*
X1156495Y1191141D03*
X1152755D03*
X1149015D03*
X1145275D03*
X1141535D03*
X1156495Y1206102D03*
X1152755D03*
X1149015D03*
X1145275D03*
X1141535D03*
X1156495Y1209842D03*
X1152755D03*
X1149015D03*
X1145275D03*
X1141535D03*
X1156495Y1221062D03*
X1152755D03*
X1149015D03*
X1145275D03*
X1141535D03*
X1152755Y1217322D03*
X1145275Y1213582D03*
X1141535Y1217322D03*
Y1213582D03*
X1145275Y1217322D03*
X1156495Y1213582D03*
X1149015Y1217322D03*
Y1213582D03*
X1156495Y1217322D03*
X1152755Y1213582D03*
X1156495Y1224803D03*
X1149015D03*
X1141535D03*
X1156495Y1228543D03*
X1149015D03*
X1141535D03*
X1152755Y1232283D03*
X1145275D03*
X1152755Y1236023D03*
X1145275D03*
X1141535Y1232283D03*
Y1236023D03*
X1156495Y1232283D03*
X1152755Y1224803D03*
X1149015Y1232283D03*
X1145275Y1224803D03*
X1156495Y1236023D03*
X1152755Y1228543D03*
X1149015Y1236023D03*
X1145275Y1228543D03*
X1156495Y1239763D03*
X1152755D03*
X1149015D03*
X1145275D03*
X1141535D03*
X1156495Y1243503D03*
X1149015D03*
X1141535D03*
X1156495Y1247243D03*
X1149015D03*
X1141535D03*
X1152755Y1250984D03*
X1145275D03*
X1141535D03*
X1156495D03*
X1152755Y1243503D03*
X1149015Y1250984D03*
X1145275Y1243503D03*
X1152755Y1247243D03*
X1145275D03*
X1152755Y1254724D03*
X1145275D03*
X1141535D03*
X1156495D03*
X1149015D03*
X1156811Y1350683D03*
Y1345691D03*
X1151855D03*
Y1350683D03*
X1144571D03*
Y1345691D03*
X1143793Y1348187D03*
X1156033D03*
X1152633D03*
X1143793Y1360099D03*
X1156811Y1357603D03*
Y1362595D03*
X1151855D03*
Y1357603D03*
X1144571D03*
Y1362595D03*
X1152633Y1360099D03*
X1156033D03*
Y1384297D03*
X1152633D03*
X1156811Y1374881D03*
Y1369889D03*
Y1381801D03*
X1151855Y1374881D03*
Y1369889D03*
Y1381801D03*
X1144571Y1369889D03*
Y1381801D03*
Y1374881D03*
X1156033Y1372385D03*
X1152633D03*
X1143793D03*
Y1384297D03*
X1156811Y1386793D03*
Y1399079D03*
Y1394087D03*
X1151855Y1386793D03*
Y1399079D03*
Y1394087D03*
X1144571D03*
Y1399079D03*
Y1386793D03*
X1143793Y1396583D03*
X1156033D03*
X1152633D03*
X1143793Y1408495D03*
X1156811Y1405999D03*
Y1410991D03*
X1151855Y1405999D03*
Y1410991D03*
X1144571Y1405999D03*
Y1410991D03*
X1152633Y1408495D03*
X1156033D03*
X1167716Y1075196D03*
X1160235D03*
X1171456D03*
X1163976D03*
X1167716Y1078936D03*
X1160235D03*
X1171456Y1082677D03*
X1163976D03*
X1171456Y1086417D03*
X1163976D03*
X1171456Y1090157D03*
X1167716D03*
X1163976D03*
X1160235D03*
X1171456Y1078936D03*
X1167716Y1086417D03*
X1163976Y1078936D03*
X1160235Y1086417D03*
X1167716Y1082677D03*
X1160235D03*
X1167716Y1093897D03*
X1160235D03*
X1167716Y1097637D03*
X1160235D03*
X1171456Y1101377D03*
X1163976D03*
X1171456Y1105117D03*
X1163976D03*
X1171456Y1097637D03*
X1167716Y1105117D03*
X1163976Y1097637D03*
X1160235Y1105117D03*
X1171456Y1093897D03*
X1167716Y1101377D03*
X1163976Y1093897D03*
X1160235Y1101377D03*
X1171456Y1108858D03*
X1167716D03*
X1163976D03*
X1160235D03*
X1171456Y1120078D03*
X1167716D03*
X1163976D03*
X1160235D03*
X1171456Y1123818D03*
X1167716D03*
X1163976D03*
X1160235D03*
X1167716Y1116338D03*
X1163976D03*
X1160235D03*
X1163976Y1112598D03*
X1171456Y1116338D03*
X1160235Y1112598D03*
X1171456D03*
X1167716D03*
X1171456Y1127558D03*
X1167716D03*
X1163976D03*
X1160235D03*
X1171456Y1135039D03*
X1167716D03*
X1163976D03*
X1160235D03*
X1171456Y1131299D03*
X1167716D03*
X1163976D03*
X1160235D03*
X1171456Y1138779D03*
X1167716D03*
X1163976D03*
X1160235D03*
X1171456Y1142519D03*
X1167716D03*
X1163976D03*
X1160235D03*
X1171456Y1149999D03*
X1167716D03*
X1163976D03*
X1160235D03*
X1171456Y1146259D03*
X1167716D03*
X1163976D03*
X1160235D03*
X1171456Y1153740D03*
X1167716D03*
X1163976D03*
X1160235D03*
X1167716Y1157480D03*
X1160235D03*
X1171456Y1161220D03*
X1163976D03*
X1167716Y1164960D03*
X1160235D03*
X1171456Y1168700D03*
X1163976D03*
X1167716Y1172440D03*
X1160235D03*
X1171456Y1157480D03*
X1163976D03*
X1167716Y1161220D03*
X1160235D03*
X1171456Y1164960D03*
X1163976D03*
X1167716Y1168700D03*
X1160235D03*
X1171456Y1172440D03*
X1163976D03*
X1171456Y1187401D03*
X1167716D03*
X1163976D03*
X1160235D03*
X1171456Y1179921D03*
X1167716D03*
X1163976D03*
X1160235D03*
X1171456Y1183661D03*
X1167716D03*
X1163976D03*
X1160235D03*
X1171456Y1176180D03*
X1167716D03*
X1163976D03*
X1160235D03*
X1171456Y1194881D03*
X1167716D03*
X1163976D03*
X1160235D03*
X1171456Y1202362D03*
X1167716D03*
X1163976D03*
X1160235D03*
X1171456Y1198621D03*
X1167716D03*
X1163976D03*
X1160235D03*
X1171456Y1191141D03*
X1167716D03*
X1163976D03*
X1160235D03*
X1171456Y1206102D03*
X1167716D03*
X1163976D03*
X1160235D03*
X1171456Y1209842D03*
X1167716D03*
X1163976D03*
X1160235D03*
X1171456Y1221062D03*
X1167716D03*
X1163976D03*
X1160235D03*
Y1213582D03*
X1163976D03*
X1171456Y1217322D03*
X1163976D03*
X1171456Y1213582D03*
X1167716D03*
X1160235Y1217322D03*
X1167716D03*
X1171456Y1224803D03*
X1163976D03*
X1171456Y1228543D03*
X1163976D03*
X1167716Y1232283D03*
X1160235D03*
X1167716Y1236023D03*
X1160235D03*
X1171456Y1232283D03*
X1167716Y1224803D03*
X1163976Y1232283D03*
X1160235Y1224803D03*
X1171456Y1236023D03*
X1167716Y1228543D03*
X1163976Y1236023D03*
X1160235Y1228543D03*
X1171456Y1239763D03*
X1167716D03*
X1163976D03*
X1160235D03*
X1171456Y1243503D03*
X1163976D03*
X1171456Y1247243D03*
X1163976D03*
X1167716Y1250984D03*
X1160235D03*
X1171456D03*
X1167716Y1243503D03*
X1163976Y1250984D03*
X1160235Y1243503D03*
X1167716Y1247243D03*
X1160235D03*
X1167716Y1254724D03*
X1160235D03*
X1171456D03*
X1163976D03*
X1169051Y1345597D03*
Y1350683D03*
X1164095D03*
Y1345597D03*
X1168273Y1348187D03*
X1164873D03*
Y1360099D03*
X1169051Y1357603D03*
Y1362595D03*
X1164095Y1357603D03*
Y1362595D03*
X1168273Y1360099D03*
X1169051Y1381801D03*
Y1374881D03*
Y1369889D03*
X1164095D03*
Y1381801D03*
Y1374881D03*
X1168273Y1384297D03*
X1164873D03*
X1168273Y1372385D03*
X1164873D03*
X1169051Y1393993D03*
Y1399079D03*
Y1386793D03*
X1164095Y1393993D03*
Y1399079D03*
Y1386793D03*
X1164873Y1396583D03*
X1168273D03*
Y1408495D03*
X1169051Y1410991D03*
Y1405999D03*
X1164095D03*
Y1410991D03*
X1164873Y1408495D03*
X1182676Y1075196D03*
X1175196D03*
X1186417D03*
X1178936D03*
X1182676Y1078936D03*
X1175196D03*
X1186417Y1082677D03*
X1178936D03*
X1186417Y1086417D03*
X1178936D03*
X1186417Y1090157D03*
X1182676D03*
X1178936D03*
X1175196D03*
X1186417Y1078936D03*
X1182676Y1086417D03*
X1178936Y1078936D03*
X1175196Y1086417D03*
X1182676Y1082677D03*
X1175196D03*
X1182676Y1093897D03*
X1175196D03*
X1182676Y1097637D03*
X1175196D03*
X1186417Y1101377D03*
X1178936D03*
X1186417Y1105117D03*
X1178936D03*
X1186417Y1097637D03*
X1182676Y1105117D03*
X1178936Y1097637D03*
X1175196Y1105117D03*
X1186417Y1093897D03*
X1182676Y1101377D03*
X1178936Y1093897D03*
X1175196Y1101377D03*
X1186417Y1108858D03*
X1182676D03*
X1178936D03*
X1175196D03*
X1186417Y1120078D03*
X1182676D03*
X1178936D03*
X1175196D03*
X1186417Y1123818D03*
X1182676D03*
X1178936D03*
X1175196D03*
X1186417Y1116338D03*
X1178936D03*
Y1112598D03*
X1186417D03*
X1182676Y1116338D03*
X1175196Y1112598D03*
Y1116338D03*
X1182676Y1112598D03*
X1186417Y1127558D03*
X1182676D03*
X1178936D03*
X1175196D03*
X1182676Y1131299D03*
X1186417Y1135039D03*
X1182676D03*
X1178936D03*
X1175196D03*
X1182676Y1138779D03*
X1186417Y1131299D03*
Y1138779D03*
X1178936Y1131299D03*
X1175196D03*
X1178936Y1138779D03*
X1175196D03*
X1182676Y1142519D03*
X1178936D03*
X1175196D03*
X1182676Y1146259D03*
X1186417Y1149999D03*
X1182676D03*
X1178936D03*
X1175196D03*
X1186417Y1153740D03*
X1182676D03*
X1178936Y1146259D03*
X1175196D03*
X1178936Y1153740D03*
X1175196D03*
X1186417Y1142519D03*
Y1146259D03*
Y1157480D03*
X1182676D03*
X1175196D03*
X1186417Y1161220D03*
Y1164960D03*
X1175196D03*
X1186417Y1168700D03*
Y1172440D03*
X1182676D03*
X1175196D03*
X1182676Y1161220D03*
X1178936D03*
X1175196D03*
X1182676Y1164960D03*
X1178936D03*
X1182676Y1168700D03*
X1178936D03*
X1175196D03*
X1178936Y1157480D03*
Y1172440D03*
X1182676Y1183661D03*
Y1187401D03*
X1178936D03*
X1175196D03*
X1182676Y1176180D03*
X1178936Y1179921D03*
X1175196D03*
X1178936Y1183661D03*
X1175196D03*
X1178936Y1176180D03*
X1175196D03*
X1182676Y1179921D03*
X1186417Y1183661D03*
Y1187401D03*
Y1179921D03*
Y1176180D03*
X1182676Y1191141D03*
X1186417Y1194881D03*
X1182676D03*
X1178936D03*
X1175196D03*
X1182676Y1198621D03*
X1186417Y1202362D03*
X1182676D03*
X1178936D03*
X1175196D03*
X1186417Y1198621D03*
Y1191141D03*
X1178936Y1198621D03*
X1175196D03*
X1178936Y1191141D03*
X1175196D03*
X1186417Y1206102D03*
X1182676D03*
X1178936D03*
X1175196D03*
X1186417Y1209842D03*
X1182676D03*
X1178936D03*
X1175196D03*
X1186417Y1221062D03*
X1182676D03*
X1178936D03*
X1175196D03*
X1182676Y1217322D03*
X1186417Y1213582D03*
X1175196D03*
X1182676D03*
X1178936D03*
Y1217322D03*
X1186417D03*
X1175196D03*
X1186417Y1224803D03*
X1178936D03*
X1186417Y1228543D03*
X1178936D03*
X1182676Y1232283D03*
X1175196D03*
X1182676Y1236023D03*
X1175196D03*
X1186417Y1232283D03*
X1182676Y1224803D03*
X1178936Y1232283D03*
X1175196Y1224803D03*
X1186417Y1236023D03*
X1182676Y1228543D03*
X1178936Y1236023D03*
X1175196Y1228543D03*
X1186417Y1239763D03*
X1182676D03*
X1178936D03*
X1175196D03*
X1186417Y1243503D03*
X1178936D03*
X1186417Y1247243D03*
X1178936D03*
X1182676Y1250984D03*
X1175196D03*
X1186417D03*
X1182676Y1243503D03*
X1178936Y1250984D03*
X1175196Y1243503D03*
X1182676Y1247243D03*
X1175196D03*
X1182676Y1254724D03*
X1175196D03*
X1186417D03*
X1178936D03*
X1181291Y1350683D03*
Y1345691D03*
X1176335D03*
Y1350683D03*
X1177113Y1348187D03*
X1180513D03*
X1181291Y1362595D03*
Y1357603D03*
X1176335Y1362595D03*
Y1357603D03*
X1177113Y1360099D03*
X1180513D03*
X1177113Y1384297D03*
X1181291Y1369889D03*
Y1381801D03*
Y1374881D03*
X1176335Y1369889D03*
Y1381801D03*
Y1374881D03*
X1180513Y1384297D03*
X1177113Y1372385D03*
X1180513D03*
X1181291Y1386793D03*
Y1399079D03*
Y1394087D03*
X1176335Y1386793D03*
Y1399079D03*
Y1394087D03*
X1180513Y1396583D03*
X1177113D03*
X1181291Y1405999D03*
Y1410991D03*
X1176335Y1405999D03*
Y1410991D03*
X1177113Y1408495D03*
X1180513D03*
X1205117Y1075196D03*
X1197637D03*
X1190157D03*
X1201377D03*
X1193897D03*
X1205117Y1078936D03*
X1197637D03*
X1190157D03*
X1201377Y1082677D03*
X1193897D03*
X1201377Y1086417D03*
X1193897D03*
X1205117Y1090157D03*
X1201377D03*
X1197637D03*
X1193897D03*
X1190157D03*
X1205117Y1086417D03*
X1201377Y1078936D03*
X1197637Y1086417D03*
X1193897Y1078936D03*
X1190157Y1086417D03*
X1205117Y1082677D03*
X1197637D03*
X1190157D03*
X1205117Y1093897D03*
X1197637D03*
X1190157D03*
X1205117Y1097637D03*
X1197637D03*
X1190157D03*
X1201377Y1101377D03*
X1193897D03*
X1201377Y1105117D03*
X1193897D03*
X1205117D03*
X1201377Y1097637D03*
X1197637Y1105117D03*
X1193897Y1097637D03*
X1190157Y1105117D03*
X1205117Y1101377D03*
X1201377Y1093897D03*
X1197637Y1101377D03*
X1193897Y1093897D03*
X1190157Y1101377D03*
X1205117Y1108858D03*
X1201377D03*
X1197637D03*
X1193897D03*
X1190157D03*
X1205117Y1112598D03*
Y1116338D03*
Y1120078D03*
X1193897D03*
X1190157D03*
X1205117Y1123818D03*
X1193897D03*
X1190157D03*
X1197637Y1120078D03*
X1193897Y1112598D03*
Y1116338D03*
X1197637D03*
X1190157Y1112598D03*
X1197637Y1123818D03*
X1201377Y1116338D03*
Y1123818D03*
X1190157Y1116338D03*
X1201377Y1120078D03*
Y1112598D03*
X1197637D03*
X1205117Y1127558D03*
X1193897D03*
X1205117Y1131299D03*
X1193897D03*
X1205117Y1135039D03*
X1193897D03*
X1205117Y1138779D03*
X1193897D03*
X1190157D03*
Y1127558D03*
Y1135039D03*
Y1131299D03*
X1201377Y1127558D03*
Y1131299D03*
X1197637Y1127558D03*
Y1131299D03*
X1201377Y1138779D03*
X1197637Y1135039D03*
X1201377D03*
X1197637Y1138779D03*
X1205117Y1142519D03*
X1193897D03*
X1190157D03*
X1205117Y1146259D03*
X1193897D03*
X1190157D03*
X1205117Y1149999D03*
X1193897D03*
X1190157D03*
X1205117Y1153740D03*
X1201377D03*
X1197637D03*
X1193897D03*
X1190157D03*
X1197637Y1142519D03*
X1201377Y1149999D03*
X1197637D03*
Y1146259D03*
X1201377Y1142519D03*
Y1146259D03*
X1205117Y1157480D03*
X1201377D03*
X1193897D03*
X1205117Y1161220D03*
X1201377D03*
X1193897D03*
X1205117Y1164960D03*
X1201377D03*
X1193897D03*
X1205117Y1168700D03*
X1201377D03*
X1193897D03*
X1205117Y1172440D03*
X1201377D03*
X1193897D03*
X1197637Y1157480D03*
Y1161220D03*
Y1164960D03*
Y1168700D03*
Y1172440D03*
X1190157Y1157480D03*
Y1161220D03*
Y1164960D03*
Y1168700D03*
Y1172440D03*
X1205117Y1183661D03*
X1197637D03*
X1193897D03*
X1190157D03*
X1205117Y1187401D03*
X1193897D03*
X1190157D03*
X1205117Y1176180D03*
X1201377D03*
X1197637D03*
X1193897D03*
X1190157D03*
X1205117Y1179921D03*
X1197637D03*
X1190157D03*
X1201377Y1187401D03*
X1193897Y1179921D03*
X1197637Y1187401D03*
X1201377Y1179921D03*
Y1183661D03*
X1205117Y1191141D03*
X1197637D03*
X1193897D03*
X1190157D03*
X1205117Y1194881D03*
X1193897D03*
X1205117Y1198621D03*
X1193897D03*
X1205117Y1202362D03*
X1193897D03*
X1201377Y1191141D03*
X1190157Y1198621D03*
Y1202362D03*
Y1194881D03*
X1197637D03*
Y1202362D03*
X1201377Y1194881D03*
Y1202362D03*
Y1198621D03*
X1197637D03*
X1205117Y1206102D03*
X1193897D03*
X1205117Y1209842D03*
X1193897D03*
X1190157D03*
X1205117Y1213582D03*
Y1217322D03*
Y1221062D03*
X1201377D03*
X1197637D03*
X1193897D03*
X1190157D03*
Y1206102D03*
X1201377Y1217322D03*
X1197637Y1209842D03*
Y1213582D03*
X1190157Y1217322D03*
Y1213582D03*
X1193897D03*
X1197637Y1217322D03*
X1201377Y1213582D03*
Y1209842D03*
X1193897Y1217322D03*
X1197637Y1206102D03*
X1201377D03*
Y1224803D03*
X1193897D03*
X1201377Y1228543D03*
X1193897D03*
X1205117Y1232283D03*
X1197637D03*
X1190157D03*
X1205117Y1236023D03*
X1197637D03*
X1190157D03*
X1201377Y1232283D03*
X1197637Y1224803D03*
X1193897Y1232283D03*
X1190157Y1224803D03*
X1201377Y1236023D03*
X1197637Y1228543D03*
X1193897Y1236023D03*
X1190157Y1228543D03*
X1205117Y1224803D03*
Y1228543D03*
Y1239763D03*
X1201377D03*
X1197637D03*
X1193897D03*
X1190157D03*
X1201377Y1243503D03*
X1193897D03*
X1201377Y1247243D03*
X1193897D03*
X1205117Y1250984D03*
X1197637D03*
X1190157D03*
X1201377D03*
X1197637Y1243503D03*
X1193897Y1250984D03*
X1190157Y1243503D03*
X1197637Y1247243D03*
X1190157D03*
X1205117Y1243503D03*
Y1247243D03*
Y1254724D03*
X1197637D03*
X1190157D03*
X1201377D03*
X1193897D03*
X1220078Y1075196D03*
X1212598D03*
X1208858D03*
X1216338D03*
X1220078Y1078936D03*
X1212598D03*
X1216338Y1082677D03*
X1208858D03*
X1216338Y1086417D03*
X1208858D03*
X1220078Y1090157D03*
X1216338D03*
X1212598D03*
X1208858D03*
Y1078936D03*
X1212598Y1086417D03*
X1216338Y1078936D03*
X1220078Y1086417D03*
X1212598Y1082677D03*
X1220078D03*
Y1093897D03*
X1212598D03*
X1220078Y1097637D03*
X1212598D03*
X1216338Y1101377D03*
X1208858D03*
X1216338Y1105117D03*
X1208858D03*
Y1097637D03*
X1212598Y1105117D03*
X1216338Y1097637D03*
X1220078Y1105117D03*
X1208858Y1093897D03*
X1212598Y1101377D03*
X1216338Y1093897D03*
X1220078Y1101377D03*
Y1108858D03*
X1216338D03*
X1212598D03*
X1208858D03*
X1212598Y1112598D03*
X1208858D03*
X1220078Y1116338D03*
X1216338D03*
X1212598Y1120078D03*
X1208858D03*
X1220078Y1123818D03*
X1216338D03*
Y1112598D03*
X1208858Y1116338D03*
X1216338Y1120078D03*
X1208858Y1123818D03*
X1220078Y1112598D03*
X1212598Y1116338D03*
X1220078Y1120078D03*
X1212598Y1123818D03*
Y1127558D03*
X1208858D03*
X1220078Y1131299D03*
X1216338D03*
X1212598Y1135039D03*
X1208858D03*
X1220078Y1138779D03*
X1216338D03*
X1208858D03*
X1212598D03*
X1216338Y1127558D03*
X1208858Y1131299D03*
X1216338Y1135039D03*
X1220078Y1127558D03*
X1212598Y1131299D03*
X1220078Y1135039D03*
X1212598Y1142519D03*
X1208858D03*
X1220078Y1146259D03*
X1216338D03*
X1212598Y1149999D03*
X1208858D03*
X1220078Y1153740D03*
X1216338D03*
Y1142519D03*
X1208858Y1146259D03*
X1216338Y1149999D03*
X1208858Y1153740D03*
X1220078Y1142519D03*
X1212598Y1146259D03*
X1220078Y1149999D03*
X1212598Y1153740D03*
Y1157480D03*
X1208858D03*
X1220078Y1161220D03*
X1216338D03*
X1212598Y1164960D03*
X1208858D03*
X1220078Y1168700D03*
X1216338D03*
X1212598Y1172440D03*
X1208858D03*
X1216338Y1157480D03*
X1208858Y1161220D03*
X1216338Y1164960D03*
X1208858Y1168700D03*
X1216338Y1172440D03*
X1220078Y1157480D03*
X1212598Y1161220D03*
X1220078Y1164960D03*
X1212598Y1168700D03*
X1220078Y1172440D03*
Y1183661D03*
X1216338D03*
X1212598Y1187401D03*
X1208858D03*
X1220078Y1176180D03*
X1216338D03*
X1212598Y1179921D03*
X1208858D03*
Y1176180D03*
X1216338Y1179921D03*
X1208858Y1183661D03*
X1216338Y1187401D03*
X1212598Y1176180D03*
X1220078Y1179921D03*
X1212598Y1183661D03*
X1220078Y1187401D03*
Y1191141D03*
X1216338D03*
X1212598Y1194881D03*
X1208858D03*
X1220078Y1198621D03*
X1216338D03*
X1212598Y1202362D03*
X1208858D03*
Y1191141D03*
X1216338Y1194881D03*
X1212598Y1191141D03*
X1220078Y1194881D03*
X1216338Y1202362D03*
X1208858Y1198621D03*
X1220078Y1202362D03*
X1212598Y1198621D03*
X1220078Y1206102D03*
X1216338D03*
X1212598Y1209842D03*
X1208858D03*
X1220078Y1213582D03*
X1216338D03*
X1212598Y1217322D03*
X1208858D03*
X1220078Y1221062D03*
X1216338D03*
X1212598D03*
X1208858D03*
X1216338Y1217322D03*
X1208858Y1213582D03*
X1216338Y1209842D03*
X1208858Y1206102D03*
X1220078Y1217322D03*
X1212598Y1213582D03*
X1220078Y1209842D03*
X1212598Y1206102D03*
X1216338Y1224803D03*
X1208858D03*
X1216338Y1228543D03*
X1208858D03*
X1220078Y1232283D03*
X1212598D03*
X1220078Y1236023D03*
X1212598D03*
X1208858Y1232283D03*
X1212598Y1224803D03*
X1216338Y1232283D03*
X1220078Y1224803D03*
X1208858Y1236023D03*
X1212598Y1228543D03*
X1216338Y1236023D03*
X1220078Y1228543D03*
Y1239763D03*
X1216338D03*
X1212598D03*
X1208858D03*
X1216338Y1243503D03*
X1208858D03*
X1216338Y1247243D03*
X1208858D03*
X1220078Y1250984D03*
X1212598D03*
X1208858D03*
X1212598Y1243503D03*
X1216338Y1250984D03*
X1220078Y1243503D03*
X1212598Y1247243D03*
X1220078D03*
Y1254724D03*
X1212598D03*
X1208858D03*
X1216338D03*
X1235039Y1075196D03*
X1227558D03*
X1231298D03*
X1223818D03*
X1235039Y1078936D03*
X1227558D03*
X1231298Y1082677D03*
X1223818D03*
X1235039Y1086417D03*
X1231298D03*
X1223818D03*
X1231298Y1090157D03*
X1227558D03*
X1223818D03*
X1235039D03*
X1231298Y1078936D03*
X1235039Y1082677D03*
X1223818Y1078936D03*
X1227558Y1086417D03*
Y1082677D03*
X1235039Y1093897D03*
X1227558D03*
X1235039Y1097637D03*
X1227558D03*
X1231298Y1101377D03*
X1223818D03*
X1235039Y1105117D03*
X1231298D03*
X1223818D03*
X1231298Y1097637D03*
X1235039Y1101377D03*
X1223818Y1097637D03*
X1227558Y1105117D03*
X1231298Y1093897D03*
X1223818D03*
X1227558Y1101377D03*
X1231298Y1108858D03*
X1227558D03*
X1223818D03*
X1235039Y1112598D03*
X1223818D03*
X1231298Y1116338D03*
X1227558D03*
X1223818D03*
X1235039Y1120078D03*
X1223818D03*
X1231298Y1123818D03*
X1227558D03*
X1223818D03*
X1235039Y1108858D03*
X1227558Y1112598D03*
X1235039Y1116338D03*
X1227558Y1120078D03*
X1235039Y1123818D03*
X1231298Y1112598D03*
Y1120078D03*
X1235039Y1127558D03*
X1223818D03*
X1231298Y1131299D03*
X1227558D03*
X1223818D03*
X1235039Y1135039D03*
X1223818D03*
X1231298Y1138779D03*
X1227558D03*
X1223818D03*
X1235039D03*
X1227558Y1127558D03*
X1235039Y1131299D03*
X1227558Y1135039D03*
X1231298Y1127558D03*
Y1135039D03*
X1235039Y1142519D03*
X1223818D03*
X1231298Y1146259D03*
X1227558D03*
X1223818D03*
X1235039Y1149999D03*
X1223818D03*
X1231298Y1153740D03*
X1227558D03*
X1223818D03*
X1227558Y1142519D03*
X1235039Y1146259D03*
X1227558Y1149999D03*
X1235039Y1153740D03*
X1231298Y1142519D03*
Y1149999D03*
X1235039Y1157480D03*
X1223818D03*
X1231298Y1161220D03*
X1227558D03*
X1223818D03*
X1235039Y1164960D03*
X1223818D03*
X1231298Y1168700D03*
X1227558D03*
X1223818D03*
X1235039Y1172440D03*
X1223818D03*
X1227558Y1157480D03*
X1235039Y1161220D03*
X1227558Y1164960D03*
X1235039Y1168700D03*
X1227558Y1172440D03*
X1231298Y1157480D03*
Y1164960D03*
Y1172440D03*
Y1183661D03*
X1227558D03*
X1223818D03*
X1235039Y1187401D03*
X1223818D03*
X1231298Y1176180D03*
X1227558D03*
X1223818D03*
X1235039Y1179921D03*
X1223818D03*
X1235039Y1176180D03*
X1227558Y1179921D03*
X1235039Y1183661D03*
X1227558Y1187401D03*
X1231298Y1179921D03*
Y1187401D03*
Y1191141D03*
X1227558D03*
X1223818D03*
X1235039Y1194881D03*
X1223818D03*
X1231298Y1198621D03*
X1227558D03*
X1223818D03*
X1235039Y1202362D03*
X1223818D03*
X1235039Y1191141D03*
X1227558Y1194881D03*
X1231298D03*
X1227558Y1202362D03*
X1235039Y1198621D03*
X1231298Y1202362D03*
Y1206102D03*
X1227558D03*
X1223818D03*
X1235039Y1209842D03*
X1223818D03*
X1231298Y1213582D03*
X1227558D03*
X1223818D03*
X1235039Y1217322D03*
X1223818D03*
X1231298Y1221062D03*
X1227558D03*
X1223818D03*
X1235039D03*
X1227558Y1217322D03*
X1235039Y1213582D03*
X1227558Y1209842D03*
X1235039Y1206102D03*
X1231298Y1217322D03*
Y1209842D03*
X1235039Y1224803D03*
X1231298D03*
X1223818D03*
X1231298Y1228543D03*
X1223818D03*
X1235039Y1232283D03*
X1227558D03*
X1235039Y1236023D03*
X1227558D03*
X1223818Y1232283D03*
X1227558Y1224803D03*
X1231298Y1232283D03*
X1235039Y1228543D03*
X1223818Y1236023D03*
X1227558Y1228543D03*
X1231298Y1236023D03*
Y1239763D03*
X1227558D03*
X1223818D03*
X1235039Y1243503D03*
X1231298D03*
X1223818D03*
X1231298Y1247243D03*
X1223818D03*
X1235039Y1250984D03*
X1227558D03*
X1235039Y1239763D03*
X1223818Y1250984D03*
X1227558Y1243503D03*
X1231298Y1250984D03*
X1235039Y1247243D03*
X1227558D03*
X1235039Y1254724D03*
X1227558D03*
X1223818D03*
X1231298D03*
X1229548Y1350683D03*
Y1345691D03*
X1234504D03*
Y1350683D03*
X1230326Y1348187D03*
X1233726D03*
X1229548Y1362595D03*
Y1357603D03*
X1234504D03*
Y1362595D03*
X1230326Y1360099D03*
X1233726D03*
X1230326Y1372385D03*
X1229548Y1369889D03*
Y1374881D03*
Y1381801D03*
X1234504Y1369889D03*
Y1374881D03*
Y1381801D03*
X1233726Y1372385D03*
X1230326Y1384297D03*
X1233726D03*
X1229548Y1386793D03*
X1234504D03*
X1238779Y1078936D03*
Y1086417D03*
Y1090157D03*
Y1082677D03*
Y1093897D03*
Y1097637D03*
Y1105117D03*
Y1101377D03*
Y1112598D03*
Y1120078D03*
Y1108858D03*
Y1116338D03*
Y1123818D03*
Y1127558D03*
Y1135039D03*
Y1138779D03*
Y1131299D03*
Y1142519D03*
Y1149999D03*
Y1146259D03*
Y1153740D03*
Y1157480D03*
Y1164960D03*
Y1172440D03*
Y1161220D03*
Y1168700D03*
Y1187401D03*
Y1179921D03*
Y1176180D03*
Y1183661D03*
Y1194881D03*
Y1202362D03*
Y1191141D03*
Y1198621D03*
Y1209842D03*
Y1217322D03*
Y1221062D03*
Y1213582D03*
Y1206102D03*
Y1224803D03*
Y1232283D03*
Y1236023D03*
Y1228543D03*
Y1243503D03*
Y1250984D03*
Y1239763D03*
Y1247243D03*
X1245966Y1348187D03*
X1242566D03*
X1254028Y1350683D03*
Y1345691D03*
X1241788D03*
Y1350683D03*
X1246744Y1345691D03*
Y1350683D03*
X1254806Y1348187D03*
X1254028Y1357603D03*
Y1362595D03*
X1241788D03*
Y1357603D03*
X1246744Y1362595D03*
Y1357603D03*
X1254806Y1360099D03*
X1242566D03*
X1245966D03*
X1254806Y1372385D03*
X1254028Y1381801D03*
Y1374881D03*
Y1369889D03*
X1241788Y1374881D03*
Y1369795D03*
Y1381801D03*
X1246744Y1374881D03*
Y1369795D03*
Y1381801D03*
X1242566Y1372385D03*
X1245966D03*
X1242566Y1384297D03*
X1245966D03*
X1254806D03*
X1245966Y1396583D03*
X1254028Y1386793D03*
Y1399079D03*
Y1394087D03*
X1241788Y1399079D03*
Y1393993D03*
Y1386793D03*
X1246744Y1393993D03*
Y1399079D03*
Y1386793D03*
X1254806Y1396583D03*
X1242566D03*
X1254028Y1410991D03*
Y1405999D03*
X1241788Y1410991D03*
Y1405999D03*
X1246744Y1410991D03*
Y1405999D03*
X1254806Y1408495D03*
X1242566D03*
X1245966D03*
X1267046Y1348187D03*
X1270446D03*
X1266268Y1345691D03*
Y1350683D03*
X1258984D03*
Y1345691D03*
X1258206Y1348187D03*
X1266268Y1362595D03*
Y1357603D03*
X1258984Y1362595D03*
Y1357603D03*
X1258206Y1360099D03*
X1270446D03*
X1267046D03*
X1258206Y1372385D03*
X1266268Y1369889D03*
Y1374881D03*
Y1381801D03*
X1258984D03*
Y1369889D03*
Y1374881D03*
X1270446Y1372385D03*
X1267046D03*
X1270446Y1384297D03*
X1267046D03*
X1258206D03*
X1267046Y1396583D03*
X1270446D03*
X1266268Y1399079D03*
Y1394087D03*
Y1386793D03*
X1258984Y1394087D03*
Y1386793D03*
Y1399079D03*
X1258206Y1396583D03*
X1266268Y1410991D03*
Y1405999D03*
X1258984D03*
Y1410991D03*
X1258206Y1408495D03*
X1270446D03*
X1267046D03*
X1283464Y1345691D03*
Y1350683D03*
X1278508Y1345691D03*
Y1350683D03*
X1271224Y1345691D03*
Y1350683D03*
X1282686Y1348187D03*
X1279286D03*
X1283464Y1362595D03*
Y1357603D03*
X1278508D03*
Y1362595D03*
X1271224D03*
Y1357603D03*
X1279286Y1360099D03*
X1282686D03*
X1279286Y1372385D03*
X1283464Y1381801D03*
Y1369889D03*
Y1374881D03*
X1278508Y1381801D03*
Y1369889D03*
Y1374881D03*
X1271224Y1369889D03*
Y1374881D03*
Y1381801D03*
X1282686Y1372385D03*
Y1384297D03*
X1279286D03*
X1283464Y1386793D03*
Y1399079D03*
Y1394087D03*
X1278508Y1386793D03*
Y1399079D03*
Y1394087D03*
X1271224D03*
Y1399079D03*
Y1386793D03*
X1279286Y1396583D03*
X1282686D03*
X1283464Y1410991D03*
Y1405999D03*
X1278508Y1410991D03*
Y1405999D03*
X1271224Y1410991D03*
Y1405999D03*
X1279286Y1408495D03*
X1282686D03*
X1291526Y1348187D03*
X1302988Y1345691D03*
Y1350683D03*
X1290748D03*
Y1345691D03*
X1295704Y1350683D03*
Y1345691D03*
X1294926Y1348187D03*
X1302988Y1362595D03*
Y1357603D03*
X1290748Y1362595D03*
Y1357603D03*
X1295704Y1362595D03*
Y1357603D03*
X1291526Y1360099D03*
X1294926D03*
X1302988Y1374881D03*
Y1381801D03*
Y1369889D03*
X1290748D03*
Y1381801D03*
Y1374881D03*
X1295704Y1381801D03*
Y1374881D03*
Y1369889D03*
X1291526Y1372385D03*
X1294926D03*
X1291526Y1384297D03*
X1294926D03*
Y1396583D03*
X1291526D03*
X1302988Y1386793D03*
Y1399079D03*
Y1394087D03*
X1290748Y1399079D03*
Y1394087D03*
Y1386793D03*
X1295704Y1394087D03*
Y1399079D03*
Y1386793D03*
X1302988Y1410991D03*
Y1405999D03*
X1290748Y1410991D03*
Y1405999D03*
X1295704Y1410991D03*
Y1405999D03*
X1291526Y1408495D03*
X1294926D03*
X1313756Y829871D03*
X1316906D03*
Y842470D03*
Y833021D03*
Y848769D03*
X1313756Y833021D03*
Y836170D03*
X1316906Y839320D03*
X1310555Y848675D03*
X1313756Y848769D03*
X1316906Y836170D03*
X1313756Y842470D03*
Y858218D03*
X1316906Y855068D03*
X1313756Y855066D03*
X1316906Y858218D03*
Y867665D03*
Y883413D03*
Y892862D03*
X1309856Y899161D03*
X1305761D03*
X1313756D03*
X1319406Y1348187D03*
X1316006D03*
X1315228Y1345691D03*
Y1350683D03*
X1307944D03*
Y1345691D03*
X1307166Y1348187D03*
X1303766D03*
X1319406Y1360099D03*
X1315228Y1362595D03*
Y1357603D03*
X1307944D03*
Y1362595D03*
X1316006Y1360099D03*
X1307166D03*
X1303766D03*
X1316006Y1372385D03*
X1307166D03*
X1303766D03*
Y1384297D03*
X1315228Y1381801D03*
Y1369889D03*
Y1374881D03*
X1307944D03*
Y1381801D03*
Y1369889D03*
X1307166Y1384297D03*
X1319406Y1372385D03*
X1316006Y1384297D03*
X1319406D03*
Y1396583D03*
X1316006D03*
X1315228Y1399079D03*
Y1394087D03*
Y1386793D03*
X1307944D03*
Y1399079D03*
Y1394087D03*
X1303766Y1396583D03*
X1307166D03*
X1315228Y1410991D03*
Y1405999D03*
X1307944Y1410991D03*
Y1405999D03*
X1316006Y1408495D03*
X1319406D03*
X1307166D03*
X1303766D03*
X1335803Y829871D03*
X1323205D03*
X1332654Y836170D03*
X1326355Y839320D03*
X1335803D03*
X1329504Y833021D03*
X1332654Y842470D03*
X1329504Y845619D03*
X1332654D03*
X1326355Y836170D03*
X1335803Y842470D03*
X1329504Y836170D03*
X1335803Y845619D03*
Y848769D03*
X1329504Y839320D03*
X1323205Y836170D03*
X1335803D03*
X1329504Y842470D03*
X1335803Y833021D03*
X1323205D03*
X1320055Y845619D03*
X1326355D03*
X1320055Y836170D03*
X1326355Y842470D03*
X1320055Y848769D03*
X1323205Y845619D03*
X1332654Y848769D03*
X1320055Y839320D03*
X1326355Y848769D03*
X1323205D03*
X1329504D03*
X1323204Y839319D03*
X1332654Y839320D03*
X1320055Y842470D03*
X1323205D03*
Y861367D03*
X1335803Y851918D03*
X1329504Y855068D03*
Y858218D03*
X1320055Y851918D03*
X1332654Y855068D03*
X1326355D03*
Y858218D03*
X1329504Y861367D03*
X1323205Y858218D03*
X1320055D03*
X1332654Y861367D03*
X1329504Y851918D03*
X1323205D03*
X1326355Y861367D03*
X1320055Y855068D03*
X1332654Y858218D03*
X1335803Y855068D03*
Y858218D03*
Y861367D03*
X1320055D03*
X1323204Y855067D03*
X1326355Y851918D03*
X1332654D03*
X1335803Y877114D03*
X1326355Y880263D03*
X1329504Y877114D03*
X1335803Y880263D03*
X1326355Y867665D03*
Y870814D03*
X1323205D03*
X1320055D03*
X1329504Y867665D03*
X1326355Y873964D03*
X1332654Y880263D03*
X1329504D03*
X1332654Y877114D03*
X1326355D03*
X1329504Y870814D03*
X1320055Y873964D03*
X1332654Y870814D03*
X1323204Y873965D03*
X1332654Y867665D03*
X1320055Y880263D03*
Y867665D03*
X1323205Y880263D03*
Y877114D03*
X1320055D03*
X1335803Y867665D03*
Y873964D03*
Y870814D03*
X1332654Y873964D03*
X1329504D03*
X1323205Y867665D03*
X1335802Y896011D03*
X1326355Y886562D03*
X1323205D03*
X1326355Y889712D03*
X1335803Y883413D03*
X1329504Y892862D03*
X1332654Y889712D03*
X1335803Y892862D03*
Y889712D03*
X1326355Y892862D03*
X1329504Y889712D03*
X1320055Y892862D03*
X1323205D03*
X1329504Y886562D03*
X1332654Y883413D03*
X1320055Y886562D03*
X1326355Y883413D03*
X1323205D03*
X1332654Y892862D03*
X1320055Y883413D03*
X1332654Y886562D03*
X1335803D03*
X1320055Y889712D03*
X1323204Y889713D03*
X1329504Y883413D03*
X1332424Y1345691D03*
Y1350683D03*
X1327468D03*
Y1345691D03*
X1320184Y1350683D03*
Y1345691D03*
X1328246Y1348187D03*
X1331646D03*
X1332424Y1362595D03*
Y1357603D03*
X1327468D03*
Y1362595D03*
X1320184D03*
Y1357603D03*
X1328246Y1360099D03*
X1331646D03*
Y1384297D03*
Y1372385D03*
X1328246D03*
X1332424Y1381801D03*
Y1369889D03*
Y1374881D03*
X1327468Y1381801D03*
Y1369889D03*
Y1374881D03*
X1320184Y1381801D03*
Y1374881D03*
Y1369889D03*
X1328246Y1384297D03*
X1332424Y1386793D03*
Y1394087D03*
Y1399079D03*
X1327468Y1386793D03*
Y1394087D03*
Y1399079D03*
X1320184D03*
Y1394087D03*
Y1386793D03*
X1331646Y1396583D03*
X1328246D03*
X1332424Y1410991D03*
Y1405999D03*
X1327468Y1410991D03*
Y1405999D03*
X1320184Y1410991D03*
Y1405999D03*
X1331646Y1408495D03*
X1328246D03*
X1351550Y839320D03*
X1342103Y845619D03*
X1345252Y836170D03*
X1338953Y845619D03*
X1345252Y833021D03*
X1342103Y836170D03*
X1351550D03*
X1342103Y842470D03*
X1345252Y845619D03*
X1342103Y839320D03*
X1338953Y848769D03*
X1338952Y839319D03*
X1345252Y842470D03*
X1342103Y848769D03*
X1338953Y842470D03*
X1345252Y848769D03*
X1338953Y836170D03*
X1351550Y842470D03*
Y848769D03*
Y845619D03*
X1345252Y839320D03*
X1351550Y855068D03*
X1345252D03*
X1342103D03*
Y861367D03*
X1338953D03*
Y858218D03*
X1338952Y855067D03*
X1351550Y858218D03*
X1345252D03*
Y861367D03*
X1342103Y858218D03*
X1351550Y861367D03*
X1338953Y851918D03*
X1342103D03*
X1345252D03*
X1351550D03*
X1338953Y870814D03*
X1342103Y867665D03*
X1338953D03*
X1351550Y873964D03*
X1345252D03*
X1342103D03*
X1338952Y873965D03*
X1338953Y880263D03*
X1351550D03*
X1345252D03*
X1342103Y870814D03*
X1345252D03*
Y867665D03*
X1351550Y870814D03*
Y867665D03*
X1338953Y877114D03*
X1345252D03*
X1351550D03*
X1342103Y880263D03*
X1345252Y892862D03*
X1338953Y883413D03*
X1345252Y889712D03*
Y886562D03*
X1342103Y883413D03*
X1345252D03*
X1338952Y889713D03*
X1338953Y892862D03*
X1342103Y886562D03*
Y892862D03*
Y889712D03*
X1338953Y886562D03*
X1351550Y883413D03*
Y889712D03*
Y886562D03*
Y892862D03*
X1343886Y1348187D03*
X1340486D03*
X1351948Y1350683D03*
Y1345691D03*
X1339708Y1345597D03*
Y1350683D03*
X1344664Y1345597D03*
Y1350683D03*
X1343886Y1360099D03*
X1351948Y1357603D03*
Y1362595D03*
X1339708D03*
Y1357603D03*
X1344664Y1362595D03*
Y1357603D03*
X1340486Y1360099D03*
X1351948Y1374881D03*
Y1381801D03*
Y1369889D03*
X1339708Y1374881D03*
Y1381801D03*
Y1369889D03*
X1344664D03*
Y1374881D03*
Y1381801D03*
X1343886Y1372385D03*
X1340486D03*
Y1384297D03*
X1343886D03*
X1340486Y1396583D03*
X1343886D03*
X1351948Y1386793D03*
Y1394087D03*
Y1399079D03*
X1339708D03*
Y1393993D03*
Y1386793D03*
X1344664Y1393993D03*
Y1399079D03*
Y1386793D03*
X1351948Y1410991D03*
Y1405999D03*
X1339708Y1410991D03*
Y1405999D03*
X1344664Y1410991D03*
Y1405999D03*
X1343886Y1408495D03*
X1340486D03*
X1364148Y829871D03*
X1367298D03*
X1359425Y829000D03*
X1364148Y836170D03*
X1354699Y842470D03*
Y848769D03*
X1357849D03*
X1364148Y845619D03*
X1354699Y836170D03*
X1357849Y833021D03*
X1367298Y845619D03*
X1364148Y842470D03*
X1357850Y839319D03*
X1357849Y836170D03*
X1360999Y842470D03*
X1354699Y845619D03*
X1357849D03*
X1360999Y839320D03*
X1367298Y842470D03*
X1360999Y848769D03*
Y845619D03*
X1367298Y833021D03*
X1354699Y839320D03*
X1360999Y836170D03*
X1367298Y848769D03*
X1364148Y839320D03*
X1357849Y842470D03*
X1364148Y833021D03*
X1367298Y836170D03*
Y839320D03*
X1364148Y848769D03*
X1354699Y855068D03*
X1357849Y861367D03*
X1354699D03*
X1357849Y858218D03*
X1357850Y855067D03*
X1360999Y851918D03*
X1364148D03*
X1367298Y861367D03*
X1364148Y858218D03*
Y855068D03*
Y861367D03*
X1367298Y858218D03*
Y851918D03*
X1354699Y858218D03*
X1367298Y855068D03*
X1360999D03*
Y858218D03*
Y861367D03*
X1354699Y851918D03*
X1357849D03*
X1360999Y877114D03*
X1357850Y873965D03*
X1354699Y873964D03*
X1357849Y870814D03*
Y867665D03*
X1354699D03*
X1364148D03*
X1367298Y877114D03*
X1364148Y870814D03*
X1367298Y873964D03*
X1364148D03*
Y877114D03*
X1367298Y870814D03*
X1364148Y880263D03*
X1367298D03*
X1357849D03*
X1360999D03*
X1367298Y867665D03*
X1354699Y870814D03*
X1357849Y877114D03*
X1354699Y880263D03*
X1360999Y867665D03*
Y870814D03*
Y873964D03*
X1364148Y896011D03*
X1367298Y883413D03*
X1354699Y892862D03*
X1360999D03*
X1367298D03*
X1360999Y883413D03*
X1357850Y889713D03*
X1364148Y889712D03*
X1357849Y883413D03*
X1367298Y889712D03*
X1354699D03*
X1357849Y886562D03*
X1364148D03*
X1357849Y892862D03*
X1360999Y889712D03*
X1354699Y883413D03*
X1360999Y886562D03*
X1364148Y892862D03*
Y883413D03*
X1367298Y886562D03*
X1354699D03*
X1356904Y1345691D03*
Y1350683D03*
X1356126Y1348187D03*
X1352726D03*
X1356904Y1357603D03*
Y1362595D03*
X1356126Y1360099D03*
X1352726D03*
Y1384297D03*
X1356126Y1372385D03*
X1356904Y1381801D03*
Y1369889D03*
Y1374881D03*
X1356126Y1384297D03*
X1352726Y1372385D03*
X1356904Y1386793D03*
Y1394087D03*
Y1399079D03*
X1356126Y1396583D03*
X1352726D03*
X1356904Y1410991D03*
Y1405999D03*
X1352726Y1408495D03*
X1356126D03*
X1383046Y829871D03*
X1370447D03*
X1379896Y842470D03*
X1370447Y839320D03*
X1383046Y845619D03*
X1379896D03*
X1373597D03*
Y842470D03*
X1370447Y848769D03*
X1379896D03*
Y839320D03*
X1373597Y848769D03*
X1376747D03*
X1373597Y833021D03*
X1370447D03*
X1373597Y836170D03*
X1370447D03*
X1373598Y839319D03*
X1370447Y842470D03*
Y845619D03*
X1383046Y842470D03*
X1376747Y836170D03*
Y842470D03*
X1379896Y833021D03*
X1383046Y839320D03*
X1376747Y845619D03*
Y839320D03*
X1379896Y858218D03*
Y855068D03*
Y861367D03*
X1376747Y858218D03*
Y851918D03*
X1373597Y861367D03*
X1376747Y855068D03*
X1373597Y858218D03*
X1376747Y861367D03*
X1383046Y851918D03*
X1373597D03*
X1373598Y855067D03*
X1379896Y851918D03*
X1370447D03*
Y858218D03*
X1383046D03*
Y861367D03*
X1370447Y855068D03*
Y861367D03*
Y867665D03*
X1379896Y870814D03*
X1383046Y873964D03*
X1376747Y880263D03*
X1370447Y877114D03*
X1373598Y873965D03*
X1370447Y873964D03*
X1379896Y877114D03*
X1373597Y880263D03*
X1383046Y877114D03*
X1370447Y880263D03*
X1376747Y873964D03*
X1383046Y880263D03*
X1370447Y870814D03*
X1376747D03*
X1373597D03*
X1376747Y867665D03*
Y877114D03*
X1373597Y867665D03*
X1379896D03*
X1383046Y870814D03*
X1379896Y880263D03*
X1373597Y877114D03*
X1379896Y873964D03*
X1370447Y886562D03*
X1379896Y883413D03*
X1383046Y892862D03*
X1379896Y886562D03*
X1370447Y883413D03*
X1373598Y889713D03*
X1376747Y886562D03*
X1383046Y883413D03*
X1376747Y889712D03*
X1383046D03*
X1379896D03*
X1373597Y883413D03*
Y886562D03*
X1370447Y892862D03*
X1376747D03*
X1370447Y889712D03*
X1373597Y892862D03*
X1383046Y886562D03*
X1379896Y892862D03*
X1376747Y883413D03*
X1383046Y899161D03*
X1464770Y1348187D03*
X1460592Y1345691D03*
Y1350683D03*
X1465548Y1345691D03*
Y1350683D03*
X1461370Y1348187D03*
X1460592Y1357603D03*
Y1362595D03*
X1465548Y1357603D03*
Y1362595D03*
X1464770Y1360099D03*
X1461370D03*
X1464770Y1372385D03*
X1460592Y1381801D03*
Y1374881D03*
Y1369889D03*
X1465548Y1381801D03*
Y1374881D03*
Y1369889D03*
X1461370Y1372385D03*
X1464770Y1384297D03*
X1461370D03*
X1460592Y1386793D03*
X1465548D03*
X1477010Y1348187D03*
X1477788Y1350683D03*
Y1345691D03*
X1472832Y1350683D03*
Y1345691D03*
X1473610Y1348187D03*
X1477788Y1357603D03*
Y1362595D03*
X1472832Y1357603D03*
Y1362595D03*
X1473610Y1360099D03*
X1477010D03*
X1473610Y1372385D03*
X1477010D03*
X1477788Y1381801D03*
Y1369795D03*
Y1374881D03*
X1472832Y1381801D03*
Y1369795D03*
Y1374881D03*
X1473610Y1384297D03*
X1477010D03*
Y1396583D03*
X1477788Y1386793D03*
Y1399079D03*
Y1393993D03*
X1472832Y1386793D03*
Y1393993D03*
Y1399079D03*
X1473610Y1396583D03*
X1477788Y1405999D03*
Y1410991D03*
X1472832Y1405999D03*
Y1410991D03*
X1473610Y1408495D03*
X1477010D03*
X1489250Y1348187D03*
X1485850D03*
X1497312Y1350683D03*
Y1345691D03*
X1485072D03*
Y1350683D03*
X1490028Y1345691D03*
Y1350683D03*
X1498090Y1348187D03*
X1497312Y1357603D03*
Y1362595D03*
X1485072D03*
Y1357603D03*
X1490028D03*
Y1362595D03*
X1498090Y1360099D03*
X1485850D03*
X1489250D03*
Y1372385D03*
X1485850D03*
X1485072Y1369889D03*
Y1374881D03*
Y1381801D03*
X1490028Y1369889D03*
Y1374881D03*
Y1381801D03*
X1497312D03*
Y1374881D03*
Y1369889D03*
X1498090Y1372385D03*
X1485850Y1384297D03*
X1498090D03*
X1489250D03*
X1498090Y1396583D03*
X1485850D03*
X1489250D03*
X1497312Y1386793D03*
Y1394087D03*
Y1399079D03*
X1485072Y1394087D03*
Y1399079D03*
Y1386793D03*
X1490028Y1399079D03*
Y1394087D03*
Y1386793D03*
X1497312Y1405999D03*
Y1410991D03*
X1485072Y1405999D03*
Y1410991D03*
X1490028Y1405999D03*
Y1410991D03*
X1498090Y1408495D03*
X1489250D03*
X1485850D03*
X1513730Y1348187D03*
X1509552Y1350683D03*
Y1345691D03*
X1514508Y1350683D03*
Y1345691D03*
X1502268Y1350683D03*
Y1345691D03*
X1510330Y1348187D03*
X1501490D03*
X1509552Y1362595D03*
Y1357603D03*
X1514508D03*
Y1362595D03*
X1502268Y1357603D03*
Y1362595D03*
X1510330Y1360099D03*
X1501490D03*
X1513730D03*
X1510330Y1372385D03*
X1513730D03*
X1501490D03*
X1509552Y1374881D03*
Y1369889D03*
Y1381801D03*
X1514508Y1374881D03*
Y1369889D03*
Y1381801D03*
X1502268D03*
Y1374881D03*
Y1369889D03*
X1501490Y1384297D03*
X1513730D03*
X1510330D03*
Y1396583D03*
X1509552Y1394087D03*
Y1399079D03*
Y1386793D03*
X1514508Y1394087D03*
Y1399079D03*
Y1386793D03*
X1502268D03*
Y1399079D03*
Y1394087D03*
X1513730Y1396583D03*
X1501490D03*
X1509552Y1405999D03*
Y1410991D03*
X1514508Y1405999D03*
Y1410991D03*
X1502268Y1405999D03*
Y1410991D03*
X1510330Y1408495D03*
X1513730D03*
X1501490D03*
X1527559Y1075196D03*
X1520078D03*
X1523819D03*
X1527559Y1078936D03*
X1520078D03*
X1516338D03*
X1523819Y1082677D03*
Y1086417D03*
X1520078D03*
X1516338D03*
X1527559Y1090157D03*
X1523819D03*
X1520078D03*
X1516338D03*
X1527559Y1086417D03*
X1523819Y1078936D03*
X1520078Y1082677D03*
X1527559D03*
X1516338D03*
X1527559Y1093897D03*
X1520078D03*
X1516338D03*
X1527559Y1097637D03*
X1520078D03*
X1516338D03*
X1523819Y1101377D03*
Y1105117D03*
X1520078D03*
X1516338D03*
X1527559D03*
X1523819Y1097637D03*
X1520078Y1101377D03*
X1527559D03*
X1523819Y1093897D03*
X1516338Y1101377D03*
X1527559Y1108858D03*
X1523819D03*
X1520078Y1112598D03*
X1516338D03*
X1527559Y1116338D03*
X1523819D03*
X1520078Y1120078D03*
X1516338D03*
X1527559Y1123818D03*
X1523819D03*
X1520078Y1108858D03*
X1527559Y1112598D03*
X1520078Y1116338D03*
X1527559Y1120078D03*
X1520078Y1123818D03*
X1516338Y1108858D03*
X1523819Y1112598D03*
X1516338Y1116338D03*
X1523819Y1120078D03*
X1516338Y1123818D03*
X1520078Y1127558D03*
X1516338D03*
X1527559Y1131299D03*
X1523819D03*
X1520078Y1135039D03*
X1516338D03*
X1527559Y1138779D03*
X1523819D03*
X1527559Y1127558D03*
X1520078Y1131299D03*
X1527559Y1135039D03*
X1520078Y1138779D03*
X1523819Y1127558D03*
X1516338Y1131299D03*
X1523819Y1135039D03*
X1516338Y1138779D03*
X1527559Y1142519D03*
X1523819D03*
X1520078D03*
X1516338D03*
X1523819Y1146259D03*
X1520078D03*
X1516338D03*
X1527559Y1149999D03*
X1523819D03*
Y1153740D03*
X1520078D03*
X1516338D03*
X1527559Y1146259D03*
X1520078Y1149999D03*
X1516338D03*
X1527559Y1153740D03*
Y1157480D03*
X1523819D03*
Y1161220D03*
X1520078D03*
X1516338D03*
X1527559Y1164960D03*
X1523819D03*
Y1168700D03*
X1520078D03*
X1516338D03*
X1527559Y1172440D03*
X1523819D03*
X1520078Y1157480D03*
X1516338D03*
X1527559Y1161220D03*
X1520078Y1164960D03*
X1516338D03*
X1527559Y1168700D03*
X1520078Y1172440D03*
X1516338D03*
X1527559Y1183661D03*
X1523819D03*
X1520078D03*
X1516338D03*
X1520078Y1187401D03*
X1516338D03*
X1523819Y1176180D03*
X1520078D03*
X1516338D03*
X1527559Y1179921D03*
X1523819D03*
X1520078D03*
X1516338D03*
X1527559Y1176180D03*
Y1187401D03*
X1523819D03*
X1527559Y1191141D03*
X1523819D03*
X1520078Y1194881D03*
X1516338D03*
X1527559Y1198621D03*
X1523819D03*
X1520078Y1202362D03*
X1516338D03*
X1527559D03*
X1520078Y1198621D03*
X1527559Y1194881D03*
X1520078Y1191141D03*
X1523819Y1202362D03*
X1516338Y1198621D03*
X1523819Y1194881D03*
X1516338Y1191141D03*
X1527559Y1206102D03*
X1523819D03*
X1520078Y1209842D03*
X1516338D03*
X1527559Y1213582D03*
X1523819D03*
X1520078Y1217322D03*
X1516338D03*
X1527559Y1221062D03*
X1523819D03*
X1520078D03*
X1527559Y1217322D03*
X1520078Y1213582D03*
X1527559Y1209842D03*
X1520078Y1206102D03*
X1516338Y1221062D03*
X1523819Y1217322D03*
X1516338Y1213582D03*
X1523819Y1209842D03*
X1516338Y1206102D03*
X1523819Y1224803D03*
X1520078D03*
X1516338D03*
X1523819Y1228543D03*
X1527559Y1232283D03*
X1520078D03*
X1516338D03*
X1527559Y1236023D03*
X1520078D03*
X1516338D03*
X1527559Y1224803D03*
X1523819Y1232283D03*
X1520078Y1228543D03*
X1527559D03*
X1523819Y1236023D03*
X1516338Y1228543D03*
X1527559Y1239763D03*
X1523819D03*
Y1243503D03*
X1520078D03*
X1516338D03*
X1523819Y1247243D03*
X1527559Y1250984D03*
X1520078D03*
X1516338D03*
X1520078Y1239763D03*
X1516338D03*
X1527559Y1243503D03*
X1523819Y1250984D03*
X1520078Y1247243D03*
X1527559D03*
X1516338D03*
X1527559Y1254724D03*
X1520078D03*
X1523819D03*
X1525970Y1348187D03*
X1526748Y1345691D03*
Y1350683D03*
X1521792Y1345691D03*
Y1350683D03*
X1522570Y1348187D03*
X1526748Y1357603D03*
Y1362595D03*
X1521792Y1357603D03*
Y1362595D03*
X1522570Y1360099D03*
X1525970D03*
Y1372385D03*
X1526748Y1369889D03*
Y1374881D03*
Y1381801D03*
X1521792Y1374881D03*
Y1381801D03*
Y1369889D03*
X1522570Y1372385D03*
X1525970Y1384297D03*
X1522570D03*
Y1396583D03*
X1526748Y1386793D03*
Y1399079D03*
Y1394087D03*
X1521792Y1386793D03*
Y1394087D03*
Y1399079D03*
X1525970Y1396583D03*
X1526748Y1405999D03*
Y1410991D03*
X1521792Y1405999D03*
Y1410991D03*
X1525970Y1408495D03*
X1522570D03*
X1542519Y1075196D03*
X1535039D03*
X1538779D03*
X1531299D03*
X1546259D03*
X1542519Y1078936D03*
X1535039D03*
X1546259Y1082677D03*
X1538779D03*
X1531299D03*
X1546259Y1086417D03*
X1538779D03*
X1531299D03*
X1546259Y1090157D03*
X1542519D03*
X1538779D03*
X1535039D03*
X1531299D03*
X1542519Y1086417D03*
X1538779Y1078936D03*
X1535039Y1086417D03*
X1531299Y1078936D03*
X1542519Y1082677D03*
X1535039D03*
X1546259Y1078936D03*
X1542519Y1093897D03*
X1535039D03*
X1542519Y1097637D03*
X1535039D03*
X1546259Y1101377D03*
X1538779D03*
X1531299D03*
X1546259Y1105117D03*
X1538779D03*
X1531299D03*
X1542519D03*
X1538779Y1097637D03*
X1535039Y1105117D03*
X1531299Y1097637D03*
X1542519Y1101377D03*
X1538779Y1093897D03*
X1535039Y1101377D03*
X1531299Y1093897D03*
X1546259Y1097637D03*
Y1093897D03*
Y1108858D03*
X1542519D03*
X1538779D03*
X1535039D03*
X1531299D03*
X1546259Y1112598D03*
X1542519D03*
X1531299D03*
X1538779Y1116338D03*
X1535039D03*
X1531299D03*
X1546259Y1120078D03*
X1542519D03*
X1531299D03*
X1538779Y1123818D03*
X1535039D03*
X1531299D03*
X1538779Y1112598D03*
X1546259Y1116338D03*
X1538779Y1120078D03*
X1546259Y1123818D03*
X1535039Y1112598D03*
X1542519Y1116338D03*
X1535039Y1120078D03*
X1542519Y1123818D03*
X1546259Y1127558D03*
X1542519D03*
X1531299D03*
X1538779Y1131299D03*
X1535039D03*
X1531299D03*
X1546259Y1135039D03*
X1542519D03*
X1531299D03*
X1538779Y1138779D03*
X1535039D03*
X1531299D03*
X1538779Y1127558D03*
X1546259Y1131299D03*
X1538779Y1135039D03*
X1546259Y1138779D03*
X1535039Y1127558D03*
X1542519Y1131299D03*
X1535039Y1135039D03*
X1542519Y1138779D03*
X1546259Y1142519D03*
X1542519D03*
X1538779D03*
X1535039D03*
X1531299D03*
X1546259Y1146259D03*
X1542519D03*
X1535039D03*
X1546259Y1149999D03*
X1535039D03*
X1531299D03*
X1546259Y1153740D03*
X1535039D03*
X1531299Y1146259D03*
X1542519Y1153740D03*
X1538779Y1149999D03*
X1542519D03*
X1538779Y1146259D03*
Y1153740D03*
X1531299D03*
X1546259Y1157480D03*
X1535039D03*
X1531299D03*
X1546259Y1161220D03*
X1535039D03*
X1546259Y1164960D03*
X1535039D03*
X1531299D03*
X1546259Y1168700D03*
X1535039D03*
X1546259Y1172440D03*
X1535039D03*
X1531299D03*
X1542519Y1164960D03*
Y1172440D03*
Y1168700D03*
X1538779Y1172440D03*
Y1168700D03*
Y1164960D03*
X1542519Y1157480D03*
Y1161220D03*
X1538779D03*
Y1157480D03*
X1531299Y1161220D03*
Y1168700D03*
X1546259Y1183661D03*
X1542519D03*
X1538779D03*
X1535039D03*
X1531299D03*
X1546259Y1187401D03*
X1542519D03*
X1531299D03*
X1546259Y1176180D03*
X1535039D03*
X1546259Y1179921D03*
X1542519D03*
X1538779D03*
X1535039D03*
X1531299D03*
X1538779Y1176180D03*
X1542519D03*
X1531299D03*
X1538779Y1187401D03*
X1535039D03*
X1538779Y1191141D03*
X1535039D03*
X1531299D03*
X1546259Y1194881D03*
X1542519D03*
X1531299D03*
X1538779Y1198621D03*
X1535039D03*
X1531299D03*
X1546259Y1202362D03*
X1542519D03*
X1531299D03*
X1538779D03*
X1546259Y1198621D03*
X1538779Y1194881D03*
X1546259Y1191141D03*
X1535039Y1202362D03*
X1542519Y1198621D03*
X1535039Y1194881D03*
X1542519Y1191141D03*
X1538779Y1206102D03*
X1535039D03*
X1531299D03*
X1546259Y1209842D03*
X1542519D03*
X1531299D03*
X1538779Y1213582D03*
X1535039D03*
X1531299D03*
X1546259Y1217322D03*
X1542519D03*
X1531299D03*
X1546259Y1221062D03*
X1542519D03*
X1538779D03*
X1535039D03*
X1531299D03*
X1538779Y1217322D03*
X1546259Y1213582D03*
X1538779Y1209842D03*
X1546259Y1206102D03*
X1535039Y1217322D03*
X1542519Y1213582D03*
X1535039Y1209842D03*
X1542519Y1206102D03*
X1546259Y1224803D03*
X1538779D03*
X1531299D03*
X1546259Y1228543D03*
X1538779D03*
X1531299D03*
X1542519Y1232283D03*
X1535039D03*
X1542519Y1236023D03*
X1535039D03*
X1538779Y1232283D03*
X1535039Y1224803D03*
X1531299Y1232283D03*
X1538779Y1236023D03*
X1535039Y1228543D03*
X1531299Y1236023D03*
X1542519Y1224803D03*
X1546259Y1232283D03*
X1542519Y1228543D03*
X1546259Y1236023D03*
Y1239763D03*
X1542519D03*
X1538779D03*
X1535039D03*
X1531299D03*
X1546259Y1243503D03*
X1538779D03*
X1531299D03*
X1546259Y1247243D03*
X1538779D03*
X1531299D03*
X1542519Y1250984D03*
X1535039D03*
X1538779D03*
X1535039Y1243503D03*
X1531299Y1250984D03*
X1535039Y1247243D03*
X1542519Y1243503D03*
X1546259Y1250984D03*
X1542519Y1247243D03*
Y1254724D03*
X1535039D03*
X1538779D03*
X1531299D03*
X1546259D03*
X1538210Y1348187D03*
X1547050D03*
X1546272Y1350683D03*
Y1345691D03*
X1534032Y1350683D03*
Y1345691D03*
X1538988D03*
Y1350683D03*
X1534810Y1348187D03*
X1546272Y1357603D03*
Y1362595D03*
X1534032Y1357603D03*
Y1362595D03*
X1538988D03*
Y1357603D03*
X1538210Y1360099D03*
X1534810D03*
X1547050D03*
X1538210Y1372385D03*
X1534810D03*
X1547050D03*
X1546272Y1374881D03*
Y1369889D03*
Y1381801D03*
X1534032Y1369889D03*
Y1381801D03*
Y1374881D03*
X1538988Y1369889D03*
Y1381801D03*
Y1374881D03*
X1547050Y1384297D03*
X1534810D03*
X1538210D03*
Y1396583D03*
X1546272Y1386793D03*
Y1394087D03*
Y1399079D03*
X1534032Y1394087D03*
Y1399079D03*
Y1386793D03*
X1538988Y1394087D03*
Y1399079D03*
Y1386793D03*
X1534810Y1396583D03*
X1547050D03*
X1546272Y1405999D03*
Y1410991D03*
X1534032Y1405999D03*
Y1410991D03*
X1538988Y1405999D03*
Y1410991D03*
X1538210Y1408495D03*
X1534810D03*
X1547050D03*
X1557480Y1075196D03*
X1550000D03*
X1553740D03*
X1561220D03*
X1557480Y1078936D03*
X1550000D03*
X1561220Y1082677D03*
X1553740D03*
X1561220Y1086417D03*
X1553740D03*
X1561220Y1090157D03*
X1557480D03*
X1553740D03*
X1550000D03*
Y1086417D03*
X1553740Y1078936D03*
X1557480Y1086417D03*
X1561220Y1078936D03*
X1550000Y1082677D03*
X1557480D03*
Y1093897D03*
X1550000D03*
X1557480Y1097637D03*
X1550000D03*
X1561220Y1101377D03*
X1553740D03*
X1561220Y1105117D03*
X1553740D03*
X1550000D03*
X1553740Y1097637D03*
X1557480Y1105117D03*
X1561220Y1097637D03*
X1550000Y1101377D03*
X1553740Y1093897D03*
X1557480Y1101377D03*
X1561220Y1093897D03*
Y1108858D03*
X1557480D03*
X1553740D03*
X1550000D03*
X1553740Y1112598D03*
X1550000D03*
X1553740Y1116338D03*
X1550000D03*
X1561220Y1120078D03*
X1557480D03*
X1553740D03*
X1550000D03*
X1561220Y1123818D03*
X1557480D03*
X1553740D03*
X1550000D03*
X1561220Y1116338D03*
X1557480D03*
Y1112598D03*
X1561220D03*
Y1127558D03*
X1557480D03*
X1553740D03*
X1550000D03*
X1561220Y1131299D03*
X1557480D03*
X1553740D03*
X1550000D03*
X1561220Y1135039D03*
X1557480D03*
X1553740D03*
X1550000D03*
X1561220Y1138779D03*
X1553740D03*
X1550000D03*
X1557480D03*
Y1149999D03*
X1561220Y1153740D03*
Y1142519D03*
X1557480D03*
X1553740D03*
X1550000D03*
X1561220Y1146259D03*
X1553740D03*
Y1149999D03*
Y1153740D03*
X1557480Y1146259D03*
X1550000D03*
Y1149999D03*
Y1153740D03*
X1561220Y1149999D03*
X1557480Y1153740D03*
Y1157480D03*
X1561220Y1161220D03*
X1557480Y1164960D03*
X1561220Y1168700D03*
X1557480Y1172440D03*
X1553740Y1157480D03*
X1550000D03*
X1553740Y1161220D03*
Y1164960D03*
Y1168700D03*
X1550000D03*
X1553740Y1172440D03*
X1550000D03*
Y1161220D03*
Y1164960D03*
X1561220Y1172440D03*
Y1157480D03*
X1557480Y1161220D03*
X1561220Y1164960D03*
X1557480Y1168700D03*
X1561220Y1176180D03*
X1557480Y1179921D03*
X1561220Y1183661D03*
X1553740D03*
X1550000D03*
X1561220Y1187401D03*
X1557480D03*
X1553740D03*
X1550000D03*
X1553740Y1176180D03*
Y1179921D03*
X1550000Y1176180D03*
Y1179921D03*
X1557480Y1183661D03*
Y1176180D03*
X1561220Y1179921D03*
Y1191141D03*
X1557480D03*
X1553740D03*
X1550000D03*
X1561220Y1194881D03*
X1557480D03*
X1553740D03*
X1550000D03*
X1561220Y1198621D03*
X1557480D03*
X1553740D03*
X1550000D03*
X1561220Y1202362D03*
X1557480D03*
X1553740D03*
X1550000D03*
X1561220Y1206102D03*
X1557480D03*
X1553740D03*
X1550000D03*
X1561220Y1209842D03*
X1557480D03*
X1553740D03*
X1550000D03*
X1557480Y1213582D03*
X1553740D03*
X1550000D03*
X1553740Y1217322D03*
X1550000D03*
X1561220Y1221062D03*
X1557480D03*
X1553740D03*
X1550000D03*
X1561220Y1217322D03*
X1557480D03*
X1561220Y1213582D03*
Y1224803D03*
X1553740D03*
X1561220Y1228543D03*
X1553740D03*
X1557480Y1232283D03*
X1550000D03*
X1557480Y1236023D03*
X1550000D03*
Y1224803D03*
X1553740Y1232283D03*
X1557480Y1224803D03*
X1561220Y1232283D03*
X1550000Y1228543D03*
X1553740Y1236023D03*
X1557480Y1228543D03*
X1561220Y1236023D03*
Y1239763D03*
X1557480D03*
X1553740D03*
X1550000D03*
X1561220Y1243503D03*
X1553740D03*
X1561220Y1247243D03*
X1553740D03*
X1557480Y1250984D03*
X1550000D03*
Y1243503D03*
X1553740Y1250984D03*
X1557480Y1243503D03*
X1561220Y1250984D03*
X1550000Y1247243D03*
X1557480D03*
Y1254724D03*
X1550000D03*
X1553740D03*
X1561220D03*
X1550450Y1348187D03*
X1558512Y1345691D03*
Y1350683D03*
X1563468D03*
Y1345691D03*
X1551228Y1350683D03*
Y1345691D03*
X1559290Y1348187D03*
X1562690D03*
X1563468Y1362595D03*
X1551228Y1357603D03*
Y1362595D03*
X1558512D03*
Y1357603D03*
X1563468D03*
X1559290Y1360099D03*
X1562690D03*
X1550450D03*
X1562690Y1372385D03*
X1559290D03*
X1558512Y1374881D03*
Y1369889D03*
Y1381801D03*
X1563468Y1374881D03*
Y1369889D03*
Y1381801D03*
X1551228Y1369889D03*
Y1381801D03*
Y1374881D03*
X1550450Y1372385D03*
X1562690Y1384297D03*
X1559290D03*
X1550450D03*
Y1396583D03*
X1562690D03*
X1558512Y1399079D03*
Y1394087D03*
Y1386793D03*
X1563468Y1399079D03*
Y1394087D03*
Y1386793D03*
X1551228D03*
Y1394087D03*
Y1399079D03*
X1559290Y1396583D03*
X1558512Y1405999D03*
Y1410991D03*
X1563468Y1405999D03*
Y1410991D03*
X1551228Y1405999D03*
Y1410991D03*
X1559290Y1408495D03*
X1562690D03*
X1550450D03*
X1572441Y1075196D03*
X1564960D03*
X1568700D03*
X1576181D03*
X1572441Y1078936D03*
X1564960D03*
X1576181Y1082677D03*
X1568700D03*
X1576181Y1086417D03*
X1568700D03*
X1576181Y1090157D03*
X1572441D03*
X1568700D03*
X1564960D03*
Y1086417D03*
X1568700Y1078936D03*
X1572441Y1086417D03*
X1576181Y1078936D03*
X1564960Y1082677D03*
X1572441D03*
Y1093897D03*
X1564960D03*
X1572441Y1097637D03*
X1564960D03*
X1576181Y1101377D03*
X1568700D03*
X1576181Y1105117D03*
X1568700D03*
X1564960D03*
X1568700Y1097637D03*
X1572441Y1105117D03*
X1576181Y1097637D03*
X1564960Y1101377D03*
X1568700Y1093897D03*
X1572441Y1101377D03*
X1576181Y1093897D03*
Y1108858D03*
X1572441D03*
X1568700D03*
X1564960D03*
X1576181Y1120078D03*
X1572441D03*
X1568700D03*
X1564960D03*
X1576181Y1123818D03*
X1572441D03*
X1568700D03*
X1564960D03*
X1572441Y1112598D03*
X1576181Y1116338D03*
X1572441D03*
X1576181Y1112598D03*
X1564960Y1116338D03*
Y1112598D03*
X1568700Y1116338D03*
Y1112598D03*
X1576181Y1127558D03*
X1572441D03*
X1568700D03*
X1564960D03*
X1568700Y1131299D03*
X1576181Y1135039D03*
X1572441D03*
X1568700D03*
Y1138779D03*
X1564960D03*
X1576181Y1131299D03*
X1572441D03*
X1576181Y1138779D03*
X1572441D03*
X1564960Y1131299D03*
Y1135039D03*
X1576181Y1142519D03*
X1572441D03*
X1568700Y1146259D03*
X1576181Y1149999D03*
X1572441D03*
X1564960D03*
X1568700Y1153740D03*
X1576181Y1146259D03*
X1572441D03*
X1576181Y1153740D03*
X1572441D03*
X1564960Y1142519D03*
X1568700D03*
X1564960Y1146259D03*
X1568700Y1149999D03*
X1564960Y1153740D03*
X1572441Y1157480D03*
X1564960D03*
X1576181Y1161220D03*
X1568700D03*
X1572441Y1164960D03*
X1564960D03*
X1576181Y1168700D03*
X1568700D03*
X1572441Y1172440D03*
X1564960D03*
X1576181Y1157480D03*
X1568700D03*
X1572441Y1161220D03*
X1564960D03*
X1576181Y1164960D03*
X1568700D03*
X1572441Y1168700D03*
X1564960D03*
X1576181Y1172440D03*
X1568700D03*
Y1183661D03*
X1576181Y1187401D03*
X1572441D03*
X1568700D03*
X1564960D03*
X1568700Y1176180D03*
X1576181Y1179921D03*
X1572441D03*
X1564960D03*
X1576181Y1183661D03*
X1572441D03*
X1576181Y1176180D03*
X1572441D03*
X1564960Y1183661D03*
Y1176180D03*
X1568700Y1179921D03*
Y1191141D03*
X1576181Y1194881D03*
X1572441D03*
X1568700D03*
Y1198621D03*
X1576181Y1202362D03*
X1572441D03*
X1568700D03*
X1564960D03*
Y1191141D03*
X1576181Y1198621D03*
X1572441D03*
X1576181Y1191141D03*
X1572441D03*
X1564960Y1198621D03*
Y1194881D03*
X1576181Y1206102D03*
X1572441D03*
X1568700D03*
X1564960D03*
X1576181Y1209842D03*
X1572441D03*
X1568700D03*
X1564960D03*
Y1213582D03*
Y1217322D03*
X1576181Y1221062D03*
X1572441D03*
X1568700D03*
X1564960D03*
X1576181Y1213582D03*
X1572441D03*
X1576181Y1217322D03*
X1568700Y1213582D03*
X1572441Y1217322D03*
X1568700D03*
X1576181Y1224803D03*
X1568700D03*
X1576181Y1228543D03*
X1568700D03*
X1572441Y1232283D03*
X1564960D03*
X1572441Y1236023D03*
X1564960D03*
Y1224803D03*
X1568700Y1232283D03*
X1572441Y1224803D03*
X1576181Y1232283D03*
X1564960Y1228543D03*
X1568700Y1236023D03*
X1572441Y1228543D03*
X1576181Y1236023D03*
Y1239763D03*
X1572441D03*
X1568700D03*
X1564960D03*
X1576181Y1243503D03*
X1568700D03*
X1576181Y1247243D03*
X1568700D03*
X1572441Y1250984D03*
X1564960D03*
Y1243503D03*
X1568700Y1250984D03*
X1572441Y1243503D03*
X1576181Y1250984D03*
X1564960Y1247243D03*
X1572441D03*
Y1254724D03*
X1564960D03*
X1568700D03*
X1576181D03*
X1574930Y1348187D03*
X1571530D03*
X1575708Y1345597D03*
X1570752Y1350683D03*
Y1345597D03*
X1575708Y1350683D03*
X1570752Y1357603D03*
Y1362595D03*
X1575708D03*
Y1357603D03*
X1574930Y1360099D03*
X1571530D03*
X1575708Y1381801D03*
Y1374881D03*
Y1369889D03*
X1570752D03*
Y1381801D03*
Y1374881D03*
X1574930Y1372385D03*
X1571530D03*
Y1384297D03*
X1574930D03*
X1571530Y1396583D03*
X1575708Y1386793D03*
Y1399079D03*
Y1393993D03*
X1570752Y1386793D03*
Y1393993D03*
Y1399079D03*
X1574930Y1396583D03*
X1575708Y1405999D03*
Y1410991D03*
X1570752Y1405999D03*
Y1410991D03*
X1571530Y1408495D03*
X1574930D03*
X1594882Y1075196D03*
X1587401D03*
X1579921D03*
X1583661D03*
X1591141D03*
X1594882Y1078936D03*
X1587401D03*
X1579921D03*
X1591141Y1082677D03*
X1583661D03*
X1591141Y1086417D03*
X1583661D03*
X1594882Y1090157D03*
X1591141D03*
X1587401D03*
X1583661D03*
X1579921D03*
Y1086417D03*
X1583661Y1078936D03*
X1587401Y1086417D03*
X1591141Y1078936D03*
X1594882Y1086417D03*
X1579921Y1082677D03*
X1587401D03*
X1594882D03*
Y1093897D03*
X1587401D03*
X1579921D03*
X1594882Y1097637D03*
X1587401D03*
X1579921D03*
X1591141Y1101377D03*
X1583661D03*
X1591141Y1105117D03*
X1583661D03*
X1579921D03*
X1583661Y1097637D03*
X1587401Y1105117D03*
X1591141Y1097637D03*
X1594882Y1105117D03*
X1579921Y1101377D03*
X1583661Y1093897D03*
X1587401Y1101377D03*
X1591141Y1093897D03*
X1594882Y1101377D03*
Y1108858D03*
X1591141D03*
X1587401D03*
X1583661D03*
X1579921D03*
X1587401Y1112598D03*
Y1116338D03*
X1594882Y1120078D03*
X1591141D03*
X1587401D03*
X1583661D03*
X1579921D03*
X1594882Y1123818D03*
X1591141D03*
X1587401D03*
X1583661D03*
X1579921D03*
X1594882Y1112598D03*
Y1116338D03*
X1591141D03*
Y1112598D03*
X1579921Y1116338D03*
Y1112598D03*
X1583661Y1116338D03*
Y1112598D03*
X1594882Y1127558D03*
X1591141D03*
X1587401D03*
X1583661D03*
X1579921D03*
X1594882Y1135039D03*
X1591141D03*
X1587401D03*
X1583661D03*
X1579921D03*
X1594882Y1131299D03*
X1591141D03*
X1587401D03*
X1583661D03*
X1579921D03*
X1594882Y1138779D03*
X1591141D03*
X1587401D03*
X1583661D03*
X1579921D03*
X1594882Y1142519D03*
X1591141D03*
X1587401D03*
X1583661D03*
X1579921D03*
X1594882Y1149999D03*
X1591141D03*
X1587401D03*
X1583661D03*
X1579921D03*
X1594882Y1146259D03*
X1591141D03*
X1587401D03*
X1583661D03*
X1579921D03*
X1594882Y1153740D03*
X1591141D03*
X1587401D03*
X1583661D03*
X1579921D03*
X1594882Y1157480D03*
X1587401D03*
X1579921D03*
X1591141Y1161220D03*
X1583661D03*
X1594882Y1164960D03*
X1587401D03*
X1579921D03*
X1591141Y1168700D03*
X1583661D03*
X1594882Y1172440D03*
X1587401D03*
X1579921D03*
X1591141Y1157480D03*
X1583661D03*
X1594882Y1161220D03*
X1587401D03*
X1579921D03*
X1591141Y1164960D03*
X1583661D03*
X1594882Y1168700D03*
X1587401D03*
X1579921D03*
X1591141Y1172440D03*
X1583661D03*
X1594882Y1187401D03*
X1591141D03*
X1587401D03*
X1583661D03*
X1579921D03*
X1594882Y1179921D03*
X1591141D03*
X1587401D03*
X1583661D03*
X1579921D03*
X1594882Y1183661D03*
X1591141D03*
X1587401D03*
X1583661D03*
X1579921D03*
X1594882Y1176180D03*
X1591141D03*
X1587401D03*
X1583661D03*
X1579921D03*
X1594882Y1194881D03*
X1591141D03*
X1587401D03*
X1583661D03*
X1579921D03*
X1594882Y1202362D03*
X1591141D03*
X1587401D03*
X1583661D03*
X1579921D03*
X1594882Y1198621D03*
X1591141D03*
X1587401D03*
X1583661D03*
X1579921D03*
X1594882Y1191141D03*
X1591141D03*
X1587401D03*
X1583661D03*
X1579921D03*
X1594882Y1206102D03*
X1591141D03*
X1587401D03*
X1583661D03*
X1579921D03*
X1594882Y1209842D03*
X1591141D03*
X1587401D03*
X1583661D03*
X1579921D03*
X1591141Y1213582D03*
Y1217322D03*
X1594882Y1221062D03*
X1591141D03*
X1587401D03*
X1583661D03*
X1579921D03*
X1594882Y1213582D03*
Y1217322D03*
X1583661Y1213582D03*
X1579921Y1217322D03*
X1587401D03*
X1579921Y1213582D03*
X1587401D03*
X1583661Y1217322D03*
X1591141Y1224803D03*
X1583661D03*
X1591141Y1228543D03*
X1583661D03*
X1594882Y1232283D03*
X1587401D03*
X1579921D03*
X1594882Y1236023D03*
X1587401D03*
X1579921D03*
X1587401Y1224803D03*
X1591141Y1232283D03*
X1594882Y1224803D03*
X1579921D03*
X1583661Y1232283D03*
X1587401Y1228543D03*
X1591141Y1236023D03*
X1594882Y1228543D03*
X1579921D03*
X1583661Y1236023D03*
X1594882Y1239763D03*
X1591141D03*
X1587401D03*
X1583661D03*
X1579921D03*
X1591141Y1243503D03*
X1583661D03*
X1591141Y1247243D03*
X1583661D03*
X1594882Y1250984D03*
X1587401D03*
X1579921D03*
X1587401Y1243503D03*
X1591141Y1250984D03*
X1594882Y1243503D03*
X1579921D03*
X1583661Y1250984D03*
X1587401Y1247243D03*
X1594882D03*
X1579921D03*
X1594882Y1254724D03*
X1587401D03*
X1579921D03*
X1591141D03*
X1583661D03*
X1587170Y1348187D03*
X1587948Y1350683D03*
Y1345691D03*
X1582992D03*
Y1350683D03*
X1583770Y1348187D03*
X1587948Y1362595D03*
Y1357603D03*
X1582992Y1362595D03*
Y1357603D03*
X1587170Y1360099D03*
X1583770D03*
X1587170Y1372385D03*
X1583770D03*
X1582992Y1369889D03*
Y1381801D03*
Y1374881D03*
X1587948Y1369889D03*
Y1381801D03*
Y1374881D03*
X1583770Y1384297D03*
X1587170D03*
X1583770Y1396583D03*
X1582992Y1399079D03*
Y1394087D03*
Y1386793D03*
X1587948Y1399079D03*
Y1394087D03*
Y1386793D03*
X1587170Y1396583D03*
X1582992Y1405999D03*
Y1410991D03*
X1587948Y1405999D03*
Y1410991D03*
X1583770Y1408495D03*
X1587170D03*
X1609842Y1075196D03*
X1602362D03*
X1598622D03*
X1606102D03*
X1609842Y1078936D03*
X1602362D03*
X1606102Y1082677D03*
X1598622D03*
X1606102Y1086417D03*
X1598622D03*
X1609842Y1090157D03*
X1606102D03*
X1602362D03*
X1598622D03*
Y1078936D03*
X1602362Y1086417D03*
Y1082677D03*
X1609842Y1086417D03*
X1606102Y1078936D03*
X1609842Y1082677D03*
Y1093897D03*
X1602362D03*
X1609842Y1097637D03*
X1602362D03*
X1606102Y1101377D03*
X1598622D03*
X1606102Y1105117D03*
X1598622D03*
Y1097637D03*
X1602362Y1105117D03*
X1598622Y1093897D03*
X1602362Y1101377D03*
X1609842Y1105117D03*
X1606102Y1097637D03*
X1609842Y1101377D03*
X1606102Y1093897D03*
X1609842Y1108858D03*
X1606102D03*
X1602362D03*
X1598622D03*
X1602362Y1112598D03*
Y1116338D03*
X1609842Y1120078D03*
X1606102D03*
X1602362D03*
X1598622D03*
X1609842Y1123818D03*
X1606102D03*
X1602362D03*
X1598622D03*
Y1116338D03*
Y1112598D03*
X1609842Y1116338D03*
X1606102Y1112598D03*
Y1116338D03*
X1609842Y1112598D03*
Y1127558D03*
X1606102D03*
X1602362D03*
X1598622D03*
X1609842Y1135039D03*
X1606102D03*
X1602362D03*
X1598622D03*
X1609842Y1131299D03*
X1606102D03*
X1602362D03*
X1598622D03*
X1609842Y1138779D03*
X1606102D03*
X1602362D03*
X1598622D03*
X1609842Y1142519D03*
X1606102D03*
X1602362D03*
X1598622D03*
X1609842Y1149999D03*
X1606102D03*
X1602362D03*
X1598622D03*
X1609842Y1146259D03*
X1606102D03*
X1602362D03*
X1598622D03*
X1609842Y1153740D03*
X1606102D03*
X1602362D03*
X1598622D03*
X1609842Y1157480D03*
X1602362D03*
X1606102Y1161220D03*
X1598622D03*
X1609842Y1164960D03*
X1602362D03*
X1606102Y1168700D03*
X1598622D03*
X1609842Y1172440D03*
X1602362D03*
X1606102Y1157480D03*
X1598622D03*
X1609842Y1161220D03*
X1602362D03*
X1606102Y1164960D03*
X1598622D03*
X1609842Y1168700D03*
X1602362D03*
X1606102Y1172440D03*
X1598622D03*
X1609842Y1187401D03*
X1606102D03*
X1602362D03*
X1598622D03*
X1609842Y1179921D03*
X1606102D03*
X1602362D03*
X1598622D03*
X1609842Y1183661D03*
X1606102D03*
X1602362D03*
X1598622D03*
X1609842Y1176180D03*
X1606102D03*
X1602362D03*
X1598622D03*
X1609842Y1194881D03*
X1606102D03*
X1602362D03*
X1598622D03*
X1609842Y1202362D03*
X1606102D03*
X1602362D03*
X1598622D03*
X1609842Y1198621D03*
X1606102D03*
X1602362D03*
X1598622D03*
X1609842Y1191141D03*
X1606102D03*
X1602362D03*
X1598622D03*
X1609842Y1206102D03*
X1606102D03*
X1602362D03*
X1598622D03*
X1609842Y1209842D03*
X1606102D03*
X1602362D03*
X1598622D03*
X1609842Y1221062D03*
X1606102D03*
X1602362D03*
X1598622D03*
X1609842Y1217322D03*
X1602362Y1213582D03*
X1598622Y1217322D03*
Y1213582D03*
X1602362Y1217322D03*
X1606102D03*
Y1213582D03*
X1609842D03*
X1606102Y1224803D03*
X1598622D03*
X1606102Y1228543D03*
X1598622D03*
X1609842Y1232283D03*
X1602362D03*
X1609842Y1236023D03*
X1602362D03*
X1598622Y1232283D03*
Y1236023D03*
X1609842Y1224803D03*
X1606102Y1232283D03*
X1602362Y1224803D03*
X1609842Y1228543D03*
X1606102Y1236023D03*
X1602362Y1228543D03*
X1609842Y1239763D03*
X1606102D03*
X1602362D03*
X1598622D03*
X1606102Y1243503D03*
X1598622D03*
X1606102Y1247243D03*
X1598622D03*
X1609842Y1250984D03*
X1602362D03*
X1598622D03*
X1609842Y1243503D03*
X1606102Y1250984D03*
X1602362Y1243503D03*
X1609842Y1247243D03*
X1602362D03*
X1609842Y1254724D03*
X1602362D03*
X1598622D03*
X1606102D03*
X1610620Y1345691D03*
Y1350683D03*
X1611398Y1348187D03*
X1610620Y1357603D03*
Y1362595D03*
X1611398Y1360099D03*
X1610620Y1381801D03*
Y1374881D03*
Y1369889D03*
X1611398Y1384297D03*
Y1372385D03*
X1610620Y1386793D03*
X1624803Y1075196D03*
X1617322D03*
X1621063D03*
X1613582D03*
X1624803Y1078936D03*
X1617322D03*
X1621063Y1082677D03*
X1613582D03*
X1621063Y1086417D03*
X1613582D03*
X1624803Y1090157D03*
X1621063D03*
X1617322D03*
X1613582D03*
X1624803Y1086417D03*
X1621063Y1078936D03*
X1617322Y1086417D03*
X1613582Y1078936D03*
X1624803Y1082677D03*
X1617322D03*
X1624803Y1093897D03*
X1617322D03*
X1624803Y1097637D03*
X1617322D03*
X1621063Y1101377D03*
X1613582D03*
X1621063Y1105117D03*
X1613582D03*
X1624803D03*
X1621063Y1097637D03*
X1617322Y1105117D03*
X1613582Y1097637D03*
X1624803Y1101377D03*
X1621063Y1093897D03*
X1617322Y1101377D03*
X1613582Y1093897D03*
X1624803Y1108858D03*
X1621063D03*
X1617322D03*
X1613582D03*
X1624803Y1120078D03*
X1621063D03*
X1617322D03*
X1613582D03*
X1624803Y1123818D03*
X1621063D03*
X1617322D03*
X1613582D03*
X1624803Y1116338D03*
X1621063D03*
X1617322D03*
X1621063Y1112598D03*
X1617322D03*
X1613582Y1116338D03*
Y1112598D03*
X1624803D03*
Y1127558D03*
X1621063D03*
X1617322D03*
X1613582D03*
X1624803Y1135039D03*
X1621063D03*
X1617322D03*
X1613582D03*
X1624803Y1131299D03*
X1621063D03*
X1617322D03*
X1613582D03*
X1624803Y1138779D03*
X1621063D03*
X1617322D03*
X1613582D03*
X1624803Y1142519D03*
X1621063D03*
X1617322D03*
X1613582D03*
X1624803Y1149999D03*
X1621063D03*
X1617322D03*
X1613582D03*
X1624803Y1146259D03*
X1621063D03*
X1617322D03*
X1613582D03*
X1624803Y1153740D03*
X1621063D03*
X1617322D03*
X1613582D03*
X1624803Y1157480D03*
X1617322D03*
X1621063Y1161220D03*
X1613582D03*
X1624803Y1164960D03*
X1617322D03*
X1621063Y1168700D03*
X1613582D03*
X1624803Y1172440D03*
X1617322D03*
X1621063Y1157480D03*
X1613582D03*
X1624803Y1161220D03*
X1617322D03*
X1621063Y1164960D03*
X1613582D03*
X1624803Y1168700D03*
X1617322D03*
X1621063Y1172440D03*
X1613582D03*
X1624803Y1187401D03*
X1621063D03*
X1617322D03*
X1613582D03*
X1624803Y1179921D03*
X1621063D03*
X1617322D03*
X1613582D03*
X1624803Y1183661D03*
X1621063D03*
X1617322D03*
X1613582D03*
X1624803Y1176180D03*
X1621063D03*
X1617322D03*
X1613582D03*
X1624803Y1194881D03*
X1621063D03*
X1617322D03*
X1613582D03*
X1624803Y1202362D03*
X1621063D03*
X1617322D03*
X1613582D03*
X1624803Y1198621D03*
X1621063D03*
X1617322D03*
X1613582D03*
X1624803Y1191141D03*
X1621063D03*
X1617322D03*
X1613582D03*
X1624803Y1206102D03*
X1621063D03*
X1617322D03*
X1613582D03*
X1624803Y1209842D03*
X1621063D03*
X1617322D03*
X1613582D03*
X1624803Y1221062D03*
X1621063D03*
X1617322D03*
X1613582D03*
X1617322Y1213582D03*
X1621063D03*
Y1217322D03*
X1624803Y1213582D03*
X1613582D03*
X1617322Y1217322D03*
X1613582D03*
X1624803D03*
X1621063Y1224803D03*
X1613582D03*
X1621063Y1228543D03*
X1613582D03*
X1624803Y1232283D03*
X1617322D03*
X1624803Y1236023D03*
X1617322D03*
X1624803Y1224803D03*
X1621063Y1232283D03*
X1617322Y1224803D03*
X1613582Y1232283D03*
X1624803Y1228543D03*
X1621063Y1236023D03*
X1617322Y1228543D03*
X1613582Y1236023D03*
X1624803Y1239763D03*
X1621063D03*
X1617322D03*
X1613582D03*
X1621063Y1243503D03*
X1613582D03*
X1621063Y1247243D03*
X1613582D03*
X1624803Y1250984D03*
X1617322D03*
X1624803Y1243503D03*
X1621063Y1250984D03*
X1617322Y1243503D03*
X1613582Y1250984D03*
X1624803Y1247243D03*
X1617322D03*
X1624803Y1254724D03*
X1617322D03*
X1621063D03*
X1613582D03*
X1614798Y1348187D03*
X1615576Y1345691D03*
Y1350683D03*
X1622860D03*
Y1345691D03*
X1627816Y1350683D03*
Y1345691D03*
X1623638Y1348187D03*
X1627038D03*
X1615576Y1357603D03*
Y1362595D03*
X1622860Y1357603D03*
Y1362595D03*
X1627816Y1357603D03*
Y1362595D03*
X1614798Y1360099D03*
X1623638D03*
X1627038D03*
Y1372385D03*
X1622860Y1381801D03*
Y1369795D03*
Y1374881D03*
X1627816Y1381801D03*
Y1369795D03*
Y1374881D03*
X1615576Y1381801D03*
Y1374881D03*
Y1369889D03*
X1623638Y1372385D03*
X1627038Y1384297D03*
X1623638D03*
X1614798Y1372385D03*
Y1384297D03*
X1615576Y1386793D03*
X1622860D03*
Y1393993D03*
Y1399079D03*
X1627816Y1386793D03*
Y1399079D03*
Y1393993D03*
X1627038Y1396583D03*
X1623638D03*
X1622860Y1405999D03*
Y1410991D03*
X1627816Y1405999D03*
Y1410991D03*
X1627038Y1408495D03*
X1623638D03*
X1639763Y1075196D03*
X1632283D03*
X1643504D03*
X1636023D03*
X1628543D03*
X1639763Y1078936D03*
X1632283D03*
X1643504Y1082677D03*
X1636023D03*
X1628543D03*
X1643504Y1086417D03*
X1636023D03*
X1628543D03*
X1643504Y1090157D03*
X1639763D03*
X1636023D03*
X1632283D03*
X1628543D03*
X1643504Y1078936D03*
X1639763Y1086417D03*
X1636023Y1078936D03*
X1632283Y1086417D03*
X1628543Y1078936D03*
X1639763Y1082677D03*
X1632283D03*
X1639763Y1093897D03*
X1632283D03*
X1639763Y1097637D03*
X1632283D03*
X1643504Y1101377D03*
X1636023D03*
X1628543D03*
X1643504Y1105117D03*
X1636023D03*
X1628543D03*
X1643504Y1097637D03*
X1639763Y1105117D03*
X1636023Y1097637D03*
X1632283Y1105117D03*
X1628543Y1097637D03*
X1643504Y1093897D03*
X1639763Y1101377D03*
X1636023Y1093897D03*
X1632283Y1101377D03*
X1628543Y1093897D03*
X1643504Y1108858D03*
X1639763D03*
X1636023D03*
X1632283D03*
X1628543D03*
X1643504Y1120078D03*
X1639763D03*
X1636023D03*
X1632283D03*
X1628543D03*
X1643504Y1123818D03*
X1639763D03*
X1636023D03*
X1632283D03*
X1628543D03*
X1643504Y1116338D03*
X1636023D03*
Y1112598D03*
X1643504D03*
X1639763Y1116338D03*
X1628543D03*
X1632283Y1112598D03*
X1628543D03*
X1632283Y1116338D03*
X1639763Y1112598D03*
X1643504Y1127558D03*
X1639763D03*
X1636023D03*
X1632283D03*
X1628543D03*
X1639763Y1131299D03*
X1643504Y1135039D03*
X1639763D03*
X1636023D03*
X1632283D03*
X1628543D03*
X1639763Y1138779D03*
X1643504Y1131299D03*
Y1138779D03*
X1636023Y1131299D03*
X1632283D03*
X1628543D03*
X1636023Y1138779D03*
X1632283D03*
X1628543D03*
X1639763Y1142519D03*
X1636023D03*
X1632283D03*
X1628543D03*
X1639763Y1146259D03*
X1643504Y1149999D03*
X1639763D03*
X1636023D03*
X1632283D03*
X1628543D03*
X1643504Y1153740D03*
X1639763D03*
X1636023Y1146259D03*
X1632283D03*
X1628543D03*
X1636023Y1153740D03*
X1632283D03*
X1628543D03*
X1643504Y1142519D03*
Y1146259D03*
Y1157480D03*
X1639763D03*
X1632283D03*
X1643504Y1161220D03*
X1628543D03*
X1643504Y1164960D03*
X1632283D03*
X1643504Y1168700D03*
X1628543D03*
X1643504Y1172440D03*
X1639763D03*
X1632283D03*
X1639763Y1161220D03*
X1636023D03*
X1632283D03*
X1639763Y1164960D03*
X1636023D03*
X1639763Y1168700D03*
X1636023D03*
X1632283D03*
X1636023Y1157480D03*
X1628543D03*
Y1164960D03*
X1636023Y1172440D03*
X1628543D03*
X1639763Y1183661D03*
Y1187401D03*
X1636023D03*
X1632283D03*
X1628543D03*
X1639763Y1176180D03*
X1636023Y1179921D03*
X1632283D03*
X1628543D03*
X1636023Y1183661D03*
X1632283D03*
X1628543D03*
X1636023Y1176180D03*
X1632283D03*
X1628543D03*
X1639763Y1179921D03*
X1643504Y1183661D03*
Y1187401D03*
Y1179921D03*
Y1176180D03*
X1639763Y1191141D03*
X1643504Y1194881D03*
X1639763D03*
X1636023D03*
X1632283D03*
X1628543D03*
X1639763Y1198621D03*
X1643504Y1202362D03*
X1639763D03*
X1636023D03*
X1632283D03*
X1628543D03*
X1643504Y1198621D03*
Y1191141D03*
X1636023Y1198621D03*
X1632283D03*
X1628543D03*
X1636023Y1191141D03*
X1632283D03*
X1628543D03*
X1643504Y1206102D03*
X1639763D03*
X1636023D03*
X1632283D03*
X1628543D03*
X1643504Y1209842D03*
X1639763D03*
X1636023D03*
X1632283D03*
X1628543D03*
X1643504Y1221062D03*
X1639763D03*
X1636023D03*
X1632283D03*
X1628543D03*
X1639763Y1217322D03*
X1643504Y1213582D03*
X1632283D03*
X1628543Y1217322D03*
X1639763Y1213582D03*
X1636023D03*
Y1217322D03*
X1628543Y1213582D03*
X1643504Y1217322D03*
X1632283D03*
X1643504Y1224803D03*
X1636023D03*
X1628543D03*
X1643504Y1228543D03*
X1636023D03*
X1628543D03*
X1639763Y1232283D03*
X1632283D03*
X1639763Y1236023D03*
X1632283D03*
X1643504Y1232283D03*
X1639763Y1224803D03*
X1636023Y1232283D03*
X1632283Y1224803D03*
X1628543Y1232283D03*
X1643504Y1236023D03*
X1639763Y1228543D03*
X1636023Y1236023D03*
X1632283Y1228543D03*
X1628543Y1236023D03*
X1643504Y1239763D03*
X1639763D03*
X1636023D03*
X1632283D03*
X1628543D03*
X1643504Y1243503D03*
X1636023D03*
X1628543D03*
X1643504Y1247243D03*
X1636023D03*
X1628543D03*
X1639763Y1250984D03*
X1632283D03*
X1643504D03*
X1639763Y1243503D03*
X1636023Y1250984D03*
X1632283Y1243503D03*
X1628543Y1250984D03*
X1639763Y1247243D03*
X1632283D03*
X1639763Y1254724D03*
X1632283D03*
X1643504D03*
X1636023D03*
X1628543D03*
X1639278Y1348187D03*
X1640056Y1345691D03*
Y1350683D03*
X1635100Y1345691D03*
Y1350683D03*
X1635878Y1348187D03*
X1640056Y1357603D03*
Y1362595D03*
X1635100D03*
Y1357603D03*
X1639278Y1360099D03*
X1635878D03*
X1640056Y1369889D03*
Y1374881D03*
Y1381801D03*
X1635100Y1369889D03*
Y1374881D03*
Y1381801D03*
X1635878Y1384297D03*
X1639278D03*
Y1372385D03*
X1635878D03*
X1639278Y1396583D03*
X1640056Y1399079D03*
Y1394087D03*
Y1386793D03*
X1635100Y1394087D03*
Y1399079D03*
Y1386793D03*
X1635878Y1396583D03*
X1635100Y1405999D03*
Y1410991D03*
X1640056Y1405999D03*
Y1410991D03*
X1635878Y1408495D03*
X1639278D03*
X1654724Y1075196D03*
X1647244D03*
X1658464D03*
X1650984D03*
X1654724Y1078936D03*
X1647244D03*
X1658464Y1082677D03*
X1650984D03*
X1658464Y1086417D03*
X1650984D03*
X1658464Y1090157D03*
X1654724D03*
X1650984D03*
X1647244D03*
X1658464Y1078936D03*
X1654724Y1086417D03*
X1650984Y1078936D03*
X1647244Y1086417D03*
X1654724Y1082677D03*
X1647244D03*
X1654724Y1093897D03*
X1647244D03*
X1654724Y1097637D03*
X1647244D03*
X1658464Y1101377D03*
X1650984D03*
X1658464Y1105117D03*
X1650984D03*
X1658464Y1097637D03*
X1654724Y1105117D03*
X1650984Y1097637D03*
X1647244Y1105117D03*
X1658464Y1093897D03*
X1654724Y1101377D03*
X1650984Y1093897D03*
X1647244Y1101377D03*
X1658464Y1108858D03*
X1654724D03*
X1650984D03*
X1647244D03*
X1650984Y1120078D03*
X1647244D03*
X1650984Y1123818D03*
X1647244D03*
X1654724Y1120078D03*
X1650984Y1112598D03*
Y1116338D03*
X1654724D03*
X1647244Y1112598D03*
X1654724Y1123818D03*
X1658464Y1116338D03*
Y1123818D03*
X1647244Y1116338D03*
X1658464Y1120078D03*
Y1112598D03*
X1654724D03*
X1650984Y1127558D03*
Y1131299D03*
Y1135039D03*
Y1138779D03*
X1647244D03*
Y1127558D03*
Y1135039D03*
Y1131299D03*
X1658464Y1127558D03*
Y1131299D03*
X1654724Y1127558D03*
Y1131299D03*
X1658464Y1138779D03*
X1654724Y1135039D03*
X1658464D03*
X1654724Y1138779D03*
X1650984Y1142519D03*
X1647244D03*
X1650984Y1146259D03*
X1647244D03*
X1650984Y1149999D03*
X1647244D03*
X1658464Y1153740D03*
X1654724D03*
X1650984D03*
X1647244D03*
X1654724Y1142519D03*
X1658464Y1149999D03*
X1654724D03*
Y1146259D03*
X1658464Y1142519D03*
Y1146259D03*
Y1157480D03*
X1650984D03*
X1658464Y1161220D03*
X1650984D03*
X1658464Y1164960D03*
X1650984D03*
X1658464Y1168700D03*
X1650984D03*
X1658464Y1172440D03*
X1650984D03*
X1654724Y1157480D03*
Y1161220D03*
Y1164960D03*
Y1168700D03*
Y1172440D03*
X1647244Y1157480D03*
Y1161220D03*
Y1164960D03*
Y1168700D03*
Y1172440D03*
X1654724Y1183661D03*
X1650984D03*
X1647244D03*
X1650984Y1187401D03*
X1647244D03*
X1658464Y1176180D03*
X1654724D03*
X1650984D03*
X1647244D03*
X1654724Y1179921D03*
X1647244D03*
X1658464Y1187401D03*
X1650984Y1179921D03*
X1654724Y1187401D03*
X1658464Y1179921D03*
Y1183661D03*
X1654724Y1191141D03*
X1650984D03*
X1647244D03*
X1650984Y1194881D03*
Y1198621D03*
Y1202362D03*
X1658464Y1191141D03*
X1647244Y1198621D03*
Y1202362D03*
Y1194881D03*
X1654724D03*
Y1202362D03*
X1658464Y1194881D03*
Y1202362D03*
Y1198621D03*
X1654724D03*
X1650984Y1206102D03*
Y1209842D03*
X1647244D03*
X1658464Y1221062D03*
X1654724D03*
X1650984D03*
X1647244D03*
Y1206102D03*
X1658464Y1217322D03*
X1654724Y1209842D03*
Y1213582D03*
X1647244Y1217322D03*
Y1213582D03*
X1650984D03*
X1654724Y1217322D03*
X1658464Y1213582D03*
Y1209842D03*
X1650984Y1217322D03*
X1654724Y1206102D03*
X1658464D03*
Y1224803D03*
X1650984D03*
X1658464Y1228543D03*
X1650984D03*
X1654724Y1232283D03*
X1647244D03*
X1654724Y1236023D03*
X1647244D03*
X1658464Y1232283D03*
X1654724Y1224803D03*
X1650984Y1232283D03*
X1647244Y1224803D03*
X1658464Y1236023D03*
X1654724Y1228543D03*
X1650984Y1236023D03*
X1647244Y1228543D03*
X1658464Y1239763D03*
X1654724D03*
X1650984D03*
X1647244D03*
X1658464Y1243503D03*
X1650984D03*
X1658464Y1247243D03*
X1650984D03*
X1654724Y1250984D03*
X1647244D03*
X1658464D03*
X1654724Y1243503D03*
X1650984Y1250984D03*
X1647244Y1243503D03*
X1654724Y1247243D03*
X1647244D03*
X1654724Y1254724D03*
X1647244D03*
X1658464D03*
X1650984D03*
X1647340Y1350683D03*
Y1345691D03*
X1652296Y1350683D03*
Y1345691D03*
X1659580Y1350683D03*
Y1345691D03*
X1660358Y1348187D03*
X1651518D03*
X1648118D03*
X1647340Y1357603D03*
Y1362595D03*
X1652296Y1357603D03*
Y1362595D03*
X1659580D03*
Y1357603D03*
X1660358Y1360099D03*
X1651518D03*
X1648118D03*
Y1372385D03*
X1647340Y1381801D03*
Y1374881D03*
Y1369889D03*
X1652296Y1381801D03*
Y1374881D03*
Y1369889D03*
X1659580Y1374881D03*
Y1369889D03*
Y1381801D03*
X1651518Y1372385D03*
X1648118Y1384297D03*
X1651518D03*
X1660358D03*
Y1372385D03*
X1647340Y1386793D03*
Y1394087D03*
Y1399079D03*
X1652296Y1386793D03*
Y1399079D03*
Y1394087D03*
X1659580D03*
Y1399079D03*
Y1386793D03*
X1660358Y1396583D03*
X1651518D03*
X1648118D03*
X1647340Y1405999D03*
Y1410991D03*
X1652296Y1405999D03*
Y1410991D03*
X1659580Y1405999D03*
Y1410991D03*
X1660358Y1408495D03*
X1648118D03*
X1651518D03*
X1669685Y1075196D03*
X1662204D03*
X1665945D03*
X1673425D03*
X1669685Y1078936D03*
X1662204D03*
X1673425Y1082677D03*
X1665945D03*
X1673425Y1086417D03*
X1665945D03*
X1673425Y1090157D03*
X1669685D03*
X1665945D03*
X1662204D03*
Y1086417D03*
Y1082677D03*
X1665945Y1078936D03*
X1669685Y1086417D03*
X1673425Y1078936D03*
X1669685Y1082677D03*
Y1093897D03*
X1662204D03*
X1669685Y1097637D03*
X1662204D03*
X1673425Y1101377D03*
X1665945D03*
X1673425Y1105117D03*
X1665945D03*
X1662204D03*
Y1101377D03*
X1665945Y1097637D03*
X1669685Y1105117D03*
X1673425Y1097637D03*
X1665945Y1093897D03*
X1669685Y1101377D03*
X1673425Y1093897D03*
Y1108858D03*
X1669685D03*
X1665945D03*
X1662204D03*
X1669685Y1112598D03*
X1665945D03*
X1662204D03*
X1673425Y1116338D03*
X1662204D03*
X1669685Y1120078D03*
X1665945D03*
X1662204D03*
X1673425Y1123818D03*
X1662204D03*
X1673425Y1112598D03*
X1665945Y1116338D03*
X1673425Y1120078D03*
X1665945Y1123818D03*
X1669685Y1116338D03*
Y1123818D03*
Y1127558D03*
X1665945D03*
X1662204D03*
X1673425Y1131299D03*
X1662204D03*
X1669685Y1135039D03*
X1665945D03*
X1662204D03*
X1673425Y1138779D03*
X1662204D03*
X1665945D03*
X1669685D03*
X1673425Y1127558D03*
X1665945Y1131299D03*
X1673425Y1135039D03*
X1669685Y1131299D03*
Y1142519D03*
X1665945D03*
X1662204D03*
X1673425Y1146259D03*
X1662204D03*
X1669685Y1149999D03*
X1665945D03*
X1662204D03*
X1673425Y1153740D03*
X1662204D03*
X1673425Y1142519D03*
X1665945Y1146259D03*
X1673425Y1149999D03*
X1665945Y1153740D03*
X1669685Y1146259D03*
Y1153740D03*
Y1157480D03*
X1665945D03*
X1662204D03*
X1673425Y1161220D03*
X1662204D03*
X1669685Y1164960D03*
X1665945D03*
X1662204D03*
X1673425Y1168700D03*
X1662204D03*
X1669685Y1172440D03*
X1665945D03*
X1662204D03*
X1673425Y1157480D03*
X1665945Y1161220D03*
X1673425Y1164960D03*
X1665945Y1168700D03*
X1673425Y1172440D03*
X1669685Y1161220D03*
Y1168700D03*
X1673425Y1183661D03*
X1662204D03*
X1669685Y1187401D03*
X1665945D03*
X1662204D03*
X1673425Y1176180D03*
X1662204D03*
X1669685Y1179921D03*
X1665945D03*
X1662204D03*
X1665945Y1176180D03*
X1673425Y1179921D03*
X1665945Y1183661D03*
X1673425Y1187401D03*
X1669685Y1176180D03*
Y1183661D03*
X1673425Y1191141D03*
X1662204D03*
X1669685Y1194881D03*
X1665945D03*
X1662204D03*
X1673425Y1198621D03*
X1662204D03*
X1669685Y1202362D03*
X1665945D03*
X1662204D03*
X1665945Y1191141D03*
X1673425Y1194881D03*
X1669685Y1191141D03*
X1673425Y1202362D03*
X1665945Y1198621D03*
X1669685D03*
X1673425Y1206102D03*
X1662204D03*
X1669685Y1209842D03*
X1665945D03*
X1662204D03*
X1673425Y1213582D03*
X1662204D03*
X1669685Y1217322D03*
X1665945D03*
X1662204D03*
X1673425Y1221062D03*
X1669685D03*
X1665945D03*
X1662204D03*
X1673425Y1217322D03*
X1665945Y1213582D03*
X1673425Y1209842D03*
X1665945Y1206102D03*
X1669685Y1213582D03*
Y1206102D03*
X1673425Y1224803D03*
X1665945D03*
X1673425Y1228543D03*
X1665945D03*
X1669685Y1232283D03*
X1662204D03*
X1669685Y1236023D03*
X1662204D03*
Y1224803D03*
X1665945Y1232283D03*
X1669685Y1224803D03*
X1673425Y1232283D03*
X1662204Y1228543D03*
X1665945Y1236023D03*
X1669685Y1228543D03*
X1673425Y1236023D03*
Y1239763D03*
X1669685D03*
X1665945D03*
X1662204D03*
X1673425Y1243503D03*
X1665945D03*
X1673425Y1247243D03*
X1665945D03*
X1669685Y1250984D03*
X1662204D03*
Y1243503D03*
X1665945Y1250984D03*
X1669685Y1243503D03*
X1673425Y1250984D03*
X1662204Y1247243D03*
X1669685D03*
Y1254724D03*
X1662204D03*
X1665945D03*
X1673425D03*
X1663758Y1348187D03*
X1664536Y1350683D03*
Y1345691D03*
X1671820D03*
Y1350683D03*
X1676776Y1345691D03*
Y1350683D03*
X1672598Y1348187D03*
X1675998D03*
X1664536Y1357603D03*
Y1362595D03*
X1671820Y1357603D03*
Y1362595D03*
X1676776Y1357603D03*
Y1362595D03*
X1663758Y1360099D03*
X1675998D03*
X1672598D03*
X1675998Y1372385D03*
X1672598D03*
X1664536Y1374881D03*
Y1369889D03*
Y1381801D03*
X1671820Y1374881D03*
Y1381801D03*
Y1369889D03*
X1676776D03*
Y1374881D03*
Y1381801D03*
X1672598Y1384297D03*
X1675998D03*
X1663758D03*
Y1372385D03*
Y1396583D03*
X1664536Y1394087D03*
Y1399079D03*
Y1386793D03*
X1671820D03*
Y1394087D03*
Y1399079D03*
X1676776Y1386793D03*
Y1399079D03*
Y1394087D03*
X1675998Y1396583D03*
X1672598D03*
X1664536Y1405999D03*
Y1410991D03*
X1671820Y1405999D03*
Y1410991D03*
X1676776Y1405999D03*
Y1410991D03*
X1663758Y1408495D03*
X1675998D03*
X1672598D03*
X1692126Y1075196D03*
X1684645D03*
X1677165D03*
X1688385D03*
X1680905D03*
X1692126Y1078936D03*
X1684645D03*
X1677165D03*
X1688385Y1082677D03*
X1680905D03*
X1692126Y1086417D03*
X1688385D03*
X1680905D03*
X1688385Y1090157D03*
X1684645D03*
X1680905D03*
X1677165D03*
X1692126D03*
X1688385Y1078936D03*
X1692126Y1082677D03*
X1677165Y1086417D03*
X1680905Y1078936D03*
X1684645Y1086417D03*
X1677165Y1082677D03*
X1684645D03*
X1692126Y1093897D03*
X1684645D03*
X1677165D03*
X1692126Y1097637D03*
X1684645D03*
X1677165D03*
X1688385Y1101377D03*
X1680905D03*
X1692126Y1105117D03*
X1688385D03*
X1680905D03*
X1688385Y1097637D03*
X1692126Y1101377D03*
X1677165Y1105117D03*
X1680905Y1097637D03*
X1684645Y1105117D03*
X1688385Y1093897D03*
X1677165Y1101377D03*
X1680905Y1093897D03*
X1684645Y1101377D03*
X1688385Y1108858D03*
X1684645D03*
X1680905D03*
X1677165D03*
X1692126Y1112598D03*
X1680905D03*
X1688385Y1116338D03*
X1684645D03*
X1680905D03*
X1677165D03*
X1692126Y1120078D03*
X1680905D03*
X1688385Y1123818D03*
X1684645D03*
X1680905D03*
X1677165D03*
Y1112598D03*
Y1120078D03*
X1692126Y1108858D03*
X1684645Y1112598D03*
X1692126Y1116338D03*
X1684645Y1120078D03*
X1692126Y1123818D03*
X1688385Y1112598D03*
Y1120078D03*
X1692126Y1127558D03*
X1680905D03*
X1688385Y1131299D03*
X1684645D03*
X1680905D03*
X1677165D03*
X1692126Y1135039D03*
X1680905D03*
X1688385Y1138779D03*
X1684645D03*
X1680905D03*
X1677165D03*
X1692126D03*
X1677165Y1127558D03*
Y1135039D03*
X1684645Y1127558D03*
X1692126Y1131299D03*
X1684645Y1135039D03*
X1688385Y1127558D03*
Y1135039D03*
X1692126Y1142519D03*
X1680905D03*
X1688385Y1146259D03*
X1684645D03*
X1680905D03*
X1677165D03*
X1692126Y1149999D03*
X1680905D03*
X1688385Y1153740D03*
X1684645D03*
X1680905D03*
X1677165D03*
Y1142519D03*
Y1149999D03*
X1684645Y1142519D03*
X1692126Y1146259D03*
X1684645Y1149999D03*
X1692126Y1153740D03*
X1688385Y1142519D03*
Y1149999D03*
X1692126Y1157480D03*
X1680905D03*
X1688385Y1161220D03*
X1684645D03*
X1680905D03*
X1677165D03*
X1692126Y1164960D03*
X1680905D03*
X1688385Y1168700D03*
X1684645D03*
X1680905D03*
X1677165D03*
X1692126Y1172440D03*
X1680905D03*
X1677165Y1157480D03*
Y1164960D03*
Y1172440D03*
X1684645Y1157480D03*
X1692126Y1161220D03*
X1684645Y1164960D03*
X1692126Y1168700D03*
X1684645Y1172440D03*
X1688385Y1157480D03*
Y1164960D03*
Y1172440D03*
Y1183661D03*
X1684645D03*
X1680905D03*
X1677165D03*
X1692126Y1187401D03*
X1680905D03*
X1688385Y1176180D03*
X1684645D03*
X1680905D03*
X1677165D03*
X1692126Y1179921D03*
X1680905D03*
X1677165D03*
Y1187401D03*
X1692126Y1176180D03*
X1684645Y1179921D03*
X1692126Y1183661D03*
X1684645Y1187401D03*
X1688385Y1179921D03*
Y1187401D03*
Y1191141D03*
X1684645D03*
X1680905D03*
X1677165D03*
X1692126Y1194881D03*
X1680905D03*
X1688385Y1198621D03*
X1684645D03*
X1680905D03*
X1677165D03*
X1692126Y1202362D03*
X1680905D03*
X1677165Y1194881D03*
X1692126Y1191141D03*
X1684645Y1194881D03*
X1688385D03*
X1677165Y1202362D03*
X1684645D03*
X1692126Y1198621D03*
X1688385Y1202362D03*
Y1206102D03*
X1684645D03*
X1680905D03*
X1677165D03*
X1692126Y1209842D03*
X1680905D03*
X1688385Y1213582D03*
X1684645D03*
X1680905D03*
X1677165D03*
X1692126Y1217322D03*
X1680905D03*
X1688385Y1221062D03*
X1684645D03*
X1680905D03*
X1677165D03*
Y1217322D03*
Y1209842D03*
X1692126Y1221062D03*
X1684645Y1217322D03*
X1692126Y1213582D03*
X1684645Y1209842D03*
X1692126Y1206102D03*
X1688385Y1217322D03*
Y1209842D03*
X1692126Y1224803D03*
X1688385D03*
X1680905D03*
X1688385Y1228543D03*
X1680905D03*
X1692126Y1232283D03*
X1684645D03*
X1677165D03*
X1692126Y1236023D03*
X1684645D03*
X1677165D03*
Y1224803D03*
X1680905Y1232283D03*
X1684645Y1224803D03*
X1688385Y1232283D03*
X1692126Y1228543D03*
X1677165D03*
X1680905Y1236023D03*
X1684645Y1228543D03*
X1688385Y1236023D03*
Y1239763D03*
X1684645D03*
X1680905D03*
X1677165D03*
X1692126Y1243503D03*
X1688385D03*
X1680905D03*
X1688385Y1247243D03*
X1680905D03*
X1692126Y1250984D03*
X1684645D03*
X1677165D03*
X1692126Y1239763D03*
X1677165Y1243503D03*
X1680905Y1250984D03*
X1684645Y1243503D03*
X1688385Y1250984D03*
X1692126Y1247243D03*
X1677165D03*
X1684645D03*
X1692126Y1254724D03*
X1684645D03*
X1677165D03*
X1680905D03*
X1688385D03*
X1689016Y1345691D03*
Y1350683D03*
X1684060D03*
Y1345691D03*
X1688238Y1348187D03*
X1684838D03*
X1689016Y1362595D03*
Y1357603D03*
X1684060D03*
Y1362595D03*
X1688238Y1360099D03*
X1684838D03*
X1689016Y1369889D03*
Y1381801D03*
Y1374881D03*
X1684060Y1369889D03*
Y1381801D03*
Y1374881D03*
X1684838Y1384297D03*
X1688238D03*
X1684838Y1372385D03*
X1688238D03*
X1684838Y1396583D03*
X1689016Y1394087D03*
Y1399079D03*
Y1386793D03*
X1684060Y1394087D03*
Y1399079D03*
Y1386793D03*
X1688238Y1396583D03*
X1689016Y1405999D03*
Y1410991D03*
X1684060Y1405999D03*
Y1410991D03*
X1688238Y1408495D03*
X1684838D03*
X1695866Y1078936D03*
Y1086417D03*
Y1090157D03*
Y1082677D03*
Y1093897D03*
Y1097637D03*
Y1105117D03*
Y1101377D03*
Y1112598D03*
Y1120078D03*
Y1108858D03*
Y1116338D03*
Y1123818D03*
Y1127558D03*
Y1135039D03*
Y1138779D03*
Y1131299D03*
Y1142519D03*
Y1149999D03*
Y1146259D03*
Y1153740D03*
Y1157480D03*
Y1164960D03*
Y1172440D03*
Y1161220D03*
Y1168700D03*
Y1187401D03*
Y1179921D03*
Y1176180D03*
Y1183661D03*
Y1194881D03*
Y1202362D03*
Y1191141D03*
Y1198621D03*
Y1209842D03*
Y1217322D03*
Y1221062D03*
Y1213582D03*
Y1206102D03*
Y1224803D03*
Y1232283D03*
Y1236023D03*
Y1228543D03*
Y1243503D03*
Y1250984D03*
Y1239763D03*
Y1247243D03*
X1696300Y1350683D03*
Y1345691D03*
X1701256Y1350683D03*
Y1345691D03*
X1708540D03*
Y1350683D03*
X1709318Y1348187D03*
X1700478D03*
X1697078D03*
X1696300Y1357603D03*
Y1362595D03*
X1701256Y1357603D03*
Y1362595D03*
X1708540D03*
Y1357603D03*
X1709318Y1360099D03*
X1697078D03*
X1700478D03*
X1697078Y1372385D03*
X1696300Y1374881D03*
Y1369889D03*
Y1381801D03*
X1701256Y1369889D03*
Y1381801D03*
Y1374881D03*
X1708540D03*
Y1369889D03*
Y1381801D03*
X1700478Y1372385D03*
X1697078Y1384297D03*
X1700478D03*
X1709318D03*
Y1372385D03*
X1696300Y1386793D03*
Y1394087D03*
Y1399079D03*
X1701256Y1386793D03*
Y1394087D03*
Y1399079D03*
X1708540D03*
Y1394087D03*
Y1386793D03*
X1709318Y1396583D03*
X1700478D03*
X1697078D03*
X1696300Y1405999D03*
Y1410991D03*
X1701256Y1405999D03*
Y1410991D03*
X1708540Y1405999D03*
Y1410991D03*
X1709318Y1408495D03*
X1697078D03*
X1700478D03*
X1713496Y1350683D03*
Y1345691D03*
X1720780Y1350683D03*
Y1345597D03*
X1725736Y1350683D03*
Y1345597D03*
X1712718Y1348187D03*
X1721558D03*
X1724958D03*
X1713496Y1357603D03*
Y1362595D03*
X1720780Y1357603D03*
Y1362595D03*
X1725736Y1357603D03*
Y1362595D03*
X1712718Y1360099D03*
X1724958D03*
X1721558D03*
Y1372385D03*
X1713496Y1374881D03*
Y1369889D03*
Y1381801D03*
X1720780Y1369889D03*
Y1381801D03*
Y1374881D03*
X1725736Y1381801D03*
Y1374881D03*
Y1369889D03*
X1724958Y1372385D03*
Y1384297D03*
X1721558D03*
X1712718Y1372385D03*
Y1384297D03*
Y1396583D03*
X1713496Y1399079D03*
Y1394087D03*
Y1386793D03*
X1720780D03*
Y1393993D03*
Y1399079D03*
X1725736Y1386793D03*
Y1399079D03*
Y1393993D03*
X1721558Y1396583D03*
X1724958D03*
X1713496Y1405999D03*
Y1410991D03*
X1720780Y1405999D03*
Y1410991D03*
X1725736Y1405999D03*
Y1410991D03*
X1712718Y1408495D03*
X1721558D03*
X1724958D03*
X1733798Y1348187D03*
X1737198D03*
X1737976Y1350683D03*
Y1345691D03*
X1733020D03*
Y1350683D03*
X1737976Y1362595D03*
Y1357603D03*
X1733020Y1362595D03*
Y1357603D03*
X1733798Y1360099D03*
X1737198D03*
X1737976Y1369889D03*
Y1374881D03*
X1733020Y1369889D03*
Y1381801D03*
Y1374881D03*
X1737976Y1381801D03*
X1737198Y1384297D03*
X1733798D03*
Y1372385D03*
X1737198D03*
Y1396583D03*
X1737976Y1399079D03*
Y1394087D03*
Y1386793D03*
X1733020Y1399079D03*
Y1394087D03*
Y1386793D03*
X1733798Y1396583D03*
X1737976Y1405999D03*
Y1410991D03*
X1733020Y1405999D03*
Y1410991D03*
X1737198Y1408495D03*
X1733798D03*
X1809078Y2165771D03*
X1806706Y2180760D03*
X1812366Y2063809D03*
X1822066Y2054109D03*
X1812366D03*
X1813087Y2087512D03*
X1825427Y2104853D03*
X1817378Y2165771D03*
X1815006Y2180760D03*
X1841295Y2065122D03*
X1832995D03*
X1833649Y2057507D03*
X1830872Y2083503D03*
X1840875Y2083215D03*
X1837649Y2072324D03*
X1829349D03*
X1833727Y2104853D03*
X1835862Y2121040D03*
X1833506Y2185252D03*
X1852032Y2052576D03*
X1854559Y2077931D03*
X1851762Y2121040D03*
X1854796Y2170548D03*
X1846496D03*
X1855978Y2185118D03*
X1847678D03*
X1859032Y2052576D03*
X1870505Y2064156D03*
X1860338Y2071384D03*
X1874505Y2078973D03*
X1860234Y2157701D03*
X1867072Y2174962D03*
X1864547Y2185020D03*
X1890039Y2066092D03*
X1878805Y2064156D03*
X1886128Y2075919D03*
X1882805Y2078973D03*
X1876497Y2070684D03*
X1884535Y2155415D03*
X1882972Y2174962D03*
X1882111Y2179074D03*
X1874932Y2180585D03*
X1881852Y2196600D03*
X1886699Y2183170D03*
X1876697D03*
X1905939Y2066092D03*
X1893118Y2054585D03*
X1905944Y2055424D03*
X1898342Y2062143D03*
X1901295Y2072745D03*
X1892835Y2155415D03*
X1902872Y2178531D03*
X1894572D03*
X1893087Y2168011D03*
X1896403Y2185019D03*
X1917195Y2072745D03*
X1917550Y2158451D03*
X1909250D03*
X1922010Y2151829D03*
X1913710D03*
X1921855Y2172152D03*
X1936295Y2074343D03*
X1935195Y2155918D03*
X1936377Y2163810D03*
X1924735Y2178131D03*
X1936212Y2173508D03*
X1930155Y2172152D03*
X1931738Y2182647D03*
X1923438D03*
X1941040Y2070124D03*
X1951095Y2155918D03*
X1946077Y2163810D03*
X1969128Y2161283D03*
X1959428D03*
X1969128Y2151583D03*
X1959428D03*
G54D69*
X47195Y1081713D03*
Y1087619D03*
Y1083682D03*
Y1085650D03*
X67987Y584895D03*
Y586864D03*
Y590801D03*
Y588832D03*
X58219Y1087619D03*
Y1085650D03*
Y1081713D03*
Y1083682D03*
X84433Y179897D03*
Y181866D03*
Y185803D03*
Y183834D03*
X79011Y584895D03*
Y586864D03*
Y590801D03*
Y588832D03*
X95457Y179897D03*
Y181866D03*
Y185803D03*
Y183834D03*
X186795Y179897D03*
Y181866D03*
X197819Y179897D03*
Y181866D03*
X186795Y185803D03*
X197819D03*
X186795Y183834D03*
X197819D03*
X289157Y179897D03*
Y181866D03*
Y185803D03*
Y183834D03*
X300181Y179897D03*
Y181866D03*
Y185803D03*
Y183834D03*
X353984Y391572D03*
Y397478D03*
Y393541D03*
Y395509D03*
X365008Y391572D03*
Y397478D03*
Y395509D03*
Y393541D03*
X391519Y179897D03*
Y181866D03*
Y185803D03*
Y183834D03*
X393321Y960580D03*
Y954674D03*
Y958611D03*
X382297Y954674D03*
X393321Y956643D03*
X382297D03*
Y960580D03*
Y958611D03*
X402543Y179897D03*
Y181866D03*
Y185803D03*
Y183834D03*
X426660Y1112693D03*
Y1116237D03*
Y1118008D03*
Y1119780D03*
Y1121552D03*
Y1114465D03*
X458788Y1112693D03*
Y1116237D03*
Y1118008D03*
Y1119780D03*
Y1121552D03*
Y1114465D03*
X492247Y1112693D03*
Y1116237D03*
Y1118008D03*
Y1119780D03*
Y1121552D03*
Y1114465D03*
X536097Y584895D03*
Y586864D03*
X525073Y584895D03*
Y586864D03*
Y590801D03*
X536097D03*
Y588832D03*
X525073D03*
X524375Y1112693D03*
Y1116237D03*
Y1118008D03*
Y1119780D03*
Y1121552D03*
Y1114465D03*
X541520Y179897D03*
Y181866D03*
X552544Y179897D03*
Y181866D03*
X541520Y185803D03*
X552544D03*
X541520Y183834D03*
X552544D03*
X643882Y179897D03*
Y181866D03*
Y185803D03*
Y183834D03*
X654906Y179897D03*
Y181866D03*
Y185803D03*
Y183834D03*
X746244Y179897D03*
Y181866D03*
Y185803D03*
Y183834D03*
X757268Y179897D03*
Y181866D03*
Y185803D03*
Y183834D03*
X848606Y179897D03*
Y181866D03*
Y185803D03*
Y183834D03*
X859630Y179897D03*
Y181866D03*
Y185803D03*
Y183834D03*
X854739Y405479D03*
Y399573D03*
Y401542D03*
Y403510D03*
X865763Y399573D03*
Y405479D03*
Y403510D03*
Y401542D03*
X893885Y1090716D03*
Y1092685D03*
Y1094653D03*
Y1096622D03*
X904909Y1090716D03*
Y1096622D03*
Y1094653D03*
Y1092685D03*
X957862Y1090716D03*
Y1092685D03*
Y1094653D03*
Y1096622D03*
X968886Y1090716D03*
Y1096622D03*
Y1094653D03*
Y1092685D03*
X993184Y584895D03*
Y586864D03*
X982160Y584895D03*
Y586864D03*
Y590801D03*
X993184D03*
Y588832D03*
X982160D03*
X998606Y179897D03*
Y181866D03*
X1009630Y179897D03*
Y181866D03*
X998606Y185803D03*
X1009630D03*
X998606Y183834D03*
X1009630D03*
X1100968Y179897D03*
Y181866D03*
Y185803D03*
Y183834D03*
X1111992Y179897D03*
Y181866D03*
Y185803D03*
Y183834D03*
X1203330Y179897D03*
Y181866D03*
Y185803D03*
Y183834D03*
X1214354Y179897D03*
Y181866D03*
Y185803D03*
Y183834D03*
X1268157Y391572D03*
Y397478D03*
Y393541D03*
Y395509D03*
X1279181Y391572D03*
Y397478D03*
Y395509D03*
Y393541D03*
X1305692Y179897D03*
Y181866D03*
X1316716Y179897D03*
Y181866D03*
X1305692Y185803D03*
X1316716D03*
X1305692Y183834D03*
X1316716D03*
X1340834Y1112693D03*
Y1116237D03*
Y1118008D03*
Y1119780D03*
Y1121552D03*
Y1114465D03*
X1372962Y1112693D03*
Y1116237D03*
Y1118008D03*
Y1119780D03*
Y1121552D03*
Y1114465D03*
X1406421Y1112693D03*
Y1116237D03*
Y1118008D03*
Y1119780D03*
Y1121552D03*
Y1114465D03*
X1439247Y584895D03*
Y586864D03*
Y590801D03*
Y588832D03*
X1438549Y1112693D03*
Y1116237D03*
Y1118008D03*
Y1119780D03*
Y1121552D03*
Y1114465D03*
X1455693Y179897D03*
Y181866D03*
Y185803D03*
Y183834D03*
X1450271Y584895D03*
Y586864D03*
Y590801D03*
Y588832D03*
X1466717Y179897D03*
Y181866D03*
Y185803D03*
Y183834D03*
X1558055Y179897D03*
Y181866D03*
Y185803D03*
Y183834D03*
X1569079Y179897D03*
Y181866D03*
Y185803D03*
Y183834D03*
X1660417Y179897D03*
Y181866D03*
Y185803D03*
Y183834D03*
X1671441Y179897D03*
Y181866D03*
Y185803D03*
Y183834D03*
X1725244Y391572D03*
Y397478D03*
Y393541D03*
Y395509D03*
X1736268Y391572D03*
Y397478D03*
Y395509D03*
Y393541D03*
X1762779Y179897D03*
Y181866D03*
X1773803Y179897D03*
Y181866D03*
X1762779Y185803D03*
X1773803D03*
X1762779Y183834D03*
X1773803D03*
X1801842Y1091202D03*
Y1097108D03*
Y1093171D03*
Y1095139D03*
X1812866Y1091202D03*
Y1097108D03*
Y1095139D03*
Y1093171D03*
G54D199*
X832961Y311852D03*
Y314411D03*
Y316970D03*
Y319529D03*
Y322088D03*
Y324648D03*
Y327207D03*
Y332325D03*
Y329766D03*
Y334884D03*
X855993Y311852D03*
Y327207D03*
Y324648D03*
Y322088D03*
Y319529D03*
Y316970D03*
Y314411D03*
Y334884D03*
Y332325D03*
Y329766D03*
X1298246Y750962D03*
Y753521D03*
Y756080D03*
Y758639D03*
Y761198D03*
Y763758D03*
Y766317D03*
Y768876D03*
Y771435D03*
Y773994D03*
X1321278Y750962D03*
Y766317D03*
Y763758D03*
Y761198D03*
Y758639D03*
Y756080D03*
Y753521D03*
Y773994D03*
Y771435D03*
Y768876D03*
X1350984Y563984D03*
Y566543D03*
Y569102D03*
Y571661D03*
Y574220D03*
Y576780D03*
Y579339D03*
Y581898D03*
Y584457D03*
Y587016D03*
Y610484D03*
Y613043D03*
Y615602D03*
Y618161D03*
Y620720D03*
Y623280D03*
Y625839D03*
Y628398D03*
Y630957D03*
Y633516D03*
Y654984D03*
Y657543D03*
Y660102D03*
Y662661D03*
Y665220D03*
Y667780D03*
Y670339D03*
Y672898D03*
Y675457D03*
Y678016D03*
Y701984D03*
Y704543D03*
Y707102D03*
Y709661D03*
Y712220D03*
Y714780D03*
Y717339D03*
Y719898D03*
Y722457D03*
Y725016D03*
X1374016Y571661D03*
Y569102D03*
Y566543D03*
Y563984D03*
Y587016D03*
Y584457D03*
Y579339D03*
Y576780D03*
Y574220D03*
Y581898D03*
Y620720D03*
Y618161D03*
Y615602D03*
Y613043D03*
Y610484D03*
Y633516D03*
Y630957D03*
Y625839D03*
Y623280D03*
Y628398D03*
Y667780D03*
Y665220D03*
Y662661D03*
Y660102D03*
Y657543D03*
Y654984D03*
Y678016D03*
Y675457D03*
Y670339D03*
Y672898D03*
Y701984D03*
Y717339D03*
Y714780D03*
Y712220D03*
Y709661D03*
Y707102D03*
Y704543D03*
Y725016D03*
Y722457D03*
Y719898D03*
X1441984Y686484D03*
Y689043D03*
Y691602D03*
Y694161D03*
Y696720D03*
Y699280D03*
Y701839D03*
Y704398D03*
Y706957D03*
Y709516D03*
Y730484D03*
Y733043D03*
Y735602D03*
Y738161D03*
Y740720D03*
Y743280D03*
Y745839D03*
Y748398D03*
Y750957D03*
Y753516D03*
X1465016Y701839D03*
Y699280D03*
Y696720D03*
Y694161D03*
Y691602D03*
Y689043D03*
Y686484D03*
Y709516D03*
Y706957D03*
Y704398D03*
Y733043D03*
Y730484D03*
Y750957D03*
Y745839D03*
Y743280D03*
Y740720D03*
Y738161D03*
Y735602D03*
Y748398D03*
Y753516D03*
X1458984Y771984D03*
Y774543D03*
Y777102D03*
Y779661D03*
Y782220D03*
Y784780D03*
Y787339D03*
Y789898D03*
Y792457D03*
Y795016D03*
Y815984D03*
Y818543D03*
Y821102D03*
Y823661D03*
Y826220D03*
Y828780D03*
Y831339D03*
Y833898D03*
Y836457D03*
Y839016D03*
X1482016Y782220D03*
Y779661D03*
Y777102D03*
Y774543D03*
Y771984D03*
Y795016D03*
Y792457D03*
Y787339D03*
Y784780D03*
Y789898D03*
Y815984D03*
Y831339D03*
Y828780D03*
Y826220D03*
Y823661D03*
Y821102D03*
Y818543D03*
Y839016D03*
Y836457D03*
Y833898D03*
G54D88*
X64242Y1434190D03*
X68664Y1483644D03*
X414025Y1509344D03*
X429730Y1457016D03*
X420388Y1467886D03*
G54D97*
X76012Y1355193D03*
Y1353093D03*
X79612Y1355193D03*
Y1353093D03*
X76012Y1379391D03*
Y1377291D03*
X79612Y1379391D03*
Y1377291D03*
X100492Y1355193D03*
Y1353093D03*
X91852Y1355193D03*
Y1353093D03*
X88252Y1355193D03*
Y1353093D03*
X100492Y1379391D03*
Y1377291D03*
X91852Y1379391D03*
Y1377291D03*
X88252Y1379391D03*
Y1377291D03*
Y1403589D03*
Y1401489D03*
X91852Y1403589D03*
Y1401489D03*
X100492Y1403589D03*
Y1401489D03*
X103001Y1035088D03*
Y1032988D03*
X106113Y1035102D03*
Y1033002D03*
X110430Y1105228D03*
Y1107328D03*
Y1130428D03*
Y1132528D03*
Y1143028D03*
Y1145128D03*
Y1168228D03*
Y1170328D03*
Y1180828D03*
Y1182928D03*
X104092Y1355193D03*
Y1353093D03*
X116332Y1355193D03*
Y1353093D03*
X112732Y1355193D03*
Y1353093D03*
X116332Y1379391D03*
Y1377291D03*
X104092Y1379391D03*
Y1377291D03*
X112732Y1379391D03*
Y1377291D03*
X116332Y1403589D03*
Y1401489D03*
X112732Y1403589D03*
Y1401489D03*
X104092Y1403589D03*
Y1401489D03*
X122076Y1012491D03*
Y1014591D03*
Y1025091D03*
Y1027191D03*
X124972Y1355193D03*
Y1353093D03*
X128572Y1355193D03*
Y1353093D03*
Y1379391D03*
Y1377291D03*
X124972Y1379391D03*
Y1377291D03*
X128572Y1403589D03*
Y1401489D03*
X124972Y1403589D03*
Y1401489D03*
X149452Y1355193D03*
Y1353093D03*
X137212Y1355193D03*
Y1353093D03*
X140812Y1355193D03*
Y1353093D03*
X149452Y1379391D03*
Y1377291D03*
X137212Y1379391D03*
Y1377291D03*
X140812Y1379391D03*
Y1377291D03*
X149452Y1403589D03*
Y1401489D03*
X137212Y1403589D03*
Y1401489D03*
X140812Y1403589D03*
Y1401489D03*
X165292Y1355193D03*
Y1353093D03*
X161692Y1355193D03*
Y1353093D03*
X153052Y1355193D03*
Y1353093D03*
X165292Y1379391D03*
Y1377291D03*
X161692Y1379391D03*
Y1377291D03*
X153052Y1379391D03*
Y1377291D03*
X161692Y1403589D03*
Y1401489D03*
X165292Y1403589D03*
Y1401489D03*
X153052Y1403589D03*
Y1401489D03*
X173932Y1355193D03*
Y1353093D03*
X177532Y1355193D03*
Y1353093D03*
X173932Y1379391D03*
Y1377291D03*
X177532Y1379391D03*
Y1377291D03*
X173932Y1403589D03*
Y1401489D03*
X177532Y1403589D03*
Y1401489D03*
X198412Y1355193D03*
Y1353093D03*
X189772Y1355193D03*
Y1353093D03*
X186172Y1355193D03*
Y1353093D03*
X198412Y1379391D03*
Y1377291D03*
X189772Y1379391D03*
Y1377291D03*
X186172Y1379391D03*
Y1377291D03*
X198412Y1403589D03*
Y1401489D03*
X189772Y1403589D03*
Y1401489D03*
X186172Y1403589D03*
Y1401489D03*
X202012Y1355193D03*
Y1353093D03*
Y1379391D03*
Y1377291D03*
Y1403589D03*
Y1401489D03*
X245123Y1355193D03*
Y1353093D03*
X241523Y1355193D03*
Y1353093D03*
X245123Y1379391D03*
Y1377291D03*
X241523Y1379391D03*
Y1377291D03*
X253763Y1355193D03*
Y1353093D03*
X257363Y1355193D03*
Y1353093D03*
Y1379391D03*
Y1377291D03*
X253763Y1379391D03*
Y1377291D03*
Y1403589D03*
Y1401489D03*
X257363Y1403589D03*
Y1401489D03*
X266003Y1355193D03*
Y1353093D03*
X269603Y1355193D03*
Y1353093D03*
X278243Y1355193D03*
Y1353093D03*
X266003Y1379391D03*
Y1377291D03*
X269603Y1379391D03*
Y1377291D03*
X278243Y1379391D03*
Y1377291D03*
X269603Y1403589D03*
Y1401489D03*
X266003Y1403589D03*
Y1401489D03*
X278243Y1403589D03*
Y1401489D03*
X281843Y1355193D03*
Y1353093D03*
X290483Y1355193D03*
Y1353093D03*
X294083Y1355193D03*
Y1353093D03*
X281843Y1379391D03*
Y1377291D03*
X290483Y1379391D03*
Y1377291D03*
X294083Y1379391D03*
Y1377291D03*
X281843Y1403589D03*
Y1401489D03*
X290483Y1403589D03*
Y1401489D03*
X294083Y1403589D03*
Y1401489D03*
X306323Y1355193D03*
Y1353093D03*
X302723Y1355193D03*
Y1353093D03*
X306323Y1379391D03*
Y1377291D03*
X302723Y1379391D03*
Y1377291D03*
Y1403589D03*
Y1401489D03*
X306323Y1403589D03*
Y1401489D03*
X327203Y1355193D03*
Y1353093D03*
X314963Y1355193D03*
Y1353093D03*
X318563Y1355193D03*
Y1353093D03*
X327203Y1379391D03*
Y1377291D03*
X318563Y1379391D03*
Y1377291D03*
X314963Y1379391D03*
Y1377291D03*
X327203Y1403589D03*
Y1401489D03*
X318563Y1403589D03*
Y1401489D03*
X314963Y1403589D03*
Y1401489D03*
X343043Y1355193D03*
Y1353093D03*
X339443Y1355193D03*
Y1353093D03*
X330803Y1355193D03*
Y1353093D03*
X339443Y1379391D03*
Y1377291D03*
X343043Y1379391D03*
Y1377291D03*
X330803Y1379391D03*
Y1377291D03*
X343043Y1403589D03*
Y1401489D03*
X339443Y1403589D03*
Y1401489D03*
X330803Y1403589D03*
Y1401489D03*
X355283Y1355193D03*
Y1353093D03*
X351683Y1355193D03*
Y1353093D03*
Y1379391D03*
Y1377291D03*
X355283Y1379391D03*
Y1377291D03*
Y1403589D03*
Y1401489D03*
X351683Y1403589D03*
Y1401489D03*
X367523Y1355193D03*
Y1353093D03*
X363923Y1355193D03*
Y1353093D03*
Y1379391D03*
Y1377291D03*
X367523Y1379391D03*
Y1377291D03*
Y1403589D03*
Y1401489D03*
X363923Y1403589D03*
Y1401489D03*
X440302Y1355193D03*
Y1353093D03*
Y1379391D03*
Y1377291D03*
X452542Y1355193D03*
Y1353093D03*
X456142Y1355193D03*
Y1353093D03*
X443902Y1355193D03*
Y1353093D03*
X452542Y1379391D03*
Y1377291D03*
X456142Y1379391D03*
Y1377291D03*
X443902Y1379391D03*
Y1377291D03*
X452542Y1403589D03*
Y1401489D03*
X456142Y1403589D03*
Y1401489D03*
X468382Y1355193D03*
Y1353093D03*
X464782Y1355193D03*
Y1353093D03*
Y1379391D03*
Y1377291D03*
X468382Y1379391D03*
Y1377291D03*
X464782Y1403589D03*
Y1401489D03*
X468382Y1403589D03*
Y1401489D03*
X477022Y1355193D03*
Y1353093D03*
X480622Y1355193D03*
Y1353093D03*
X489262Y1355193D03*
Y1353093D03*
X477022Y1379391D03*
Y1377291D03*
X489262Y1379391D03*
Y1377291D03*
X480622Y1379391D03*
Y1377291D03*
X489262Y1403589D03*
Y1401489D03*
X477022Y1403589D03*
Y1401489D03*
X480622Y1403589D03*
Y1401489D03*
X505102Y1355193D03*
Y1353093D03*
X501502Y1355193D03*
Y1353093D03*
X492862Y1355193D03*
Y1353093D03*
X505102Y1379391D03*
Y1377291D03*
X501502Y1379391D03*
Y1377291D03*
X492862Y1379391D03*
Y1377291D03*
X505102Y1403589D03*
Y1401489D03*
X501502Y1403589D03*
Y1401489D03*
X492862Y1403589D03*
Y1401489D03*
X517342Y1355193D03*
Y1353093D03*
X513742Y1355193D03*
Y1353093D03*
X517342Y1379391D03*
Y1377291D03*
X513742Y1379391D03*
Y1377291D03*
Y1403589D03*
Y1401489D03*
X517342Y1403589D03*
Y1401489D03*
X529582Y1355193D03*
Y1353093D03*
X538222Y1355193D03*
Y1353093D03*
X525982Y1355193D03*
Y1353093D03*
X538222Y1379391D03*
Y1377291D03*
X525982Y1379391D03*
Y1377291D03*
X529582Y1379391D03*
Y1377291D03*
X538222Y1403589D03*
Y1401489D03*
X529582Y1403589D03*
Y1401489D03*
X525982Y1403589D03*
Y1401489D03*
X555395Y1035088D03*
Y1032988D03*
X554062Y1355193D03*
Y1353093D03*
X550462Y1355193D03*
Y1353093D03*
X541822Y1355193D03*
Y1353093D03*
X550462Y1379391D03*
Y1377291D03*
X554062Y1379391D03*
Y1377291D03*
X541822Y1379391D03*
Y1377291D03*
X554062Y1403589D03*
Y1401489D03*
X550462Y1403589D03*
Y1401489D03*
X541822Y1403589D03*
Y1401489D03*
X563200Y1035102D03*
Y1033002D03*
X560088Y1035088D03*
Y1032988D03*
X567517Y1105228D03*
Y1107328D03*
Y1117828D03*
Y1119928D03*
Y1130428D03*
Y1132528D03*
Y1143028D03*
Y1145128D03*
Y1155628D03*
Y1157728D03*
Y1180828D03*
Y1182928D03*
X566302Y1355193D03*
Y1353093D03*
X562702Y1355193D03*
Y1353093D03*
Y1379391D03*
Y1377291D03*
X566302Y1379391D03*
Y1377291D03*
Y1403589D03*
Y1401489D03*
X562702Y1403589D03*
Y1401489D03*
X579163Y1012491D03*
Y1014591D03*
Y1025091D03*
Y1027191D03*
X629788Y1403589D03*
Y1401489D03*
X626188Y1403589D03*
Y1401489D03*
X650668Y1355193D03*
Y1353093D03*
Y1379391D03*
Y1377291D03*
X642028Y1379391D03*
Y1377291D03*
X638428Y1379391D03*
Y1377291D03*
X650668Y1403589D03*
Y1401489D03*
X642028Y1403589D03*
Y1401489D03*
X638428Y1403589D03*
Y1401489D03*
X666508Y1355193D03*
Y1353093D03*
X662908Y1355193D03*
Y1353093D03*
X654268Y1355193D03*
Y1353093D03*
Y1379391D03*
Y1377291D03*
X662908Y1379391D03*
Y1377291D03*
X666508Y1379391D03*
Y1377291D03*
X654268Y1403589D03*
Y1401489D03*
X666508Y1403589D03*
Y1401489D03*
X662908Y1403589D03*
Y1401489D03*
X678748Y1355193D03*
Y1353093D03*
X675148Y1355193D03*
Y1353093D03*
X678748Y1379391D03*
Y1377291D03*
X675148Y1379391D03*
Y1377291D03*
X678748Y1403589D03*
Y1401489D03*
X675148Y1403589D03*
Y1401489D03*
X699628Y1355193D03*
Y1353093D03*
X690988Y1355193D03*
Y1353093D03*
X687388Y1355193D03*
Y1353093D03*
X699628Y1379391D03*
Y1377291D03*
X690988Y1379391D03*
Y1377291D03*
X687388Y1379391D03*
Y1377291D03*
X699628Y1403589D03*
Y1401489D03*
X690988Y1403589D03*
Y1401489D03*
X687388Y1403589D03*
Y1401489D03*
X715468Y1355193D03*
Y1353093D03*
X711868Y1355193D03*
Y1353093D03*
X703228Y1355193D03*
Y1353093D03*
X711868Y1379391D03*
Y1377291D03*
X715468Y1379391D03*
Y1377291D03*
X703228Y1379391D03*
Y1377291D03*
X715468Y1403589D03*
Y1401489D03*
X711868Y1403589D03*
Y1401489D03*
X703228Y1403589D03*
Y1401489D03*
X727708Y1355193D03*
Y1353093D03*
X724108Y1355193D03*
Y1353093D03*
Y1379391D03*
Y1377291D03*
X727708Y1379391D03*
Y1377291D03*
X724108Y1403495D03*
Y1401395D03*
X727708Y1403495D03*
Y1401395D03*
X748588Y1355193D03*
Y1353093D03*
X739948Y1355193D03*
Y1353093D03*
X736348Y1355193D03*
Y1353093D03*
X748588Y1379391D03*
Y1377291D03*
X736348Y1379391D03*
Y1377291D03*
X739948Y1379391D03*
Y1377291D03*
X736348Y1403495D03*
Y1401395D03*
X739948Y1403495D03*
Y1401395D03*
X752188Y1355193D03*
Y1353093D03*
X760828Y1355193D03*
Y1353093D03*
X764428Y1355193D03*
Y1353093D03*
X760828Y1379391D03*
Y1377291D03*
X764428Y1379391D03*
Y1377291D03*
X752188Y1379391D03*
Y1377291D03*
X776668Y1355193D03*
Y1353093D03*
X773068Y1355193D03*
Y1353093D03*
X896371Y1073980D03*
Y1076080D03*
X899583Y1074008D03*
X906117Y1074004D03*
X902986Y1073977D03*
X899583Y1076108D03*
X906117Y1076104D03*
X902986Y1076077D03*
X1012517Y1035088D03*
Y1032988D03*
X1020286Y1035102D03*
Y1033002D03*
X1017174Y1035088D03*
Y1032988D03*
X1024603Y1105228D03*
Y1107328D03*
Y1117828D03*
Y1119928D03*
Y1130428D03*
Y1132528D03*
Y1143028D03*
Y1145128D03*
Y1155628D03*
Y1157728D03*
Y1180828D03*
Y1182928D03*
X1036249Y1012491D03*
Y1014591D03*
Y1025091D03*
Y1027191D03*
X1058213Y1355193D03*
Y1353093D03*
X1054613Y1355193D03*
Y1353093D03*
X1058213Y1379391D03*
Y1377291D03*
X1054613Y1379391D03*
Y1377291D03*
X1070453Y1355193D03*
Y1353093D03*
X1066853Y1355193D03*
Y1353093D03*
Y1379391D03*
Y1377291D03*
X1070453Y1379391D03*
Y1377291D03*
Y1403589D03*
Y1401489D03*
X1066853Y1403589D03*
Y1401489D03*
X1082693Y1355193D03*
Y1353093D03*
X1079093Y1355193D03*
Y1353093D03*
X1091333Y1355193D03*
Y1353093D03*
X1079093Y1379391D03*
Y1377291D03*
X1082693Y1379391D03*
Y1377291D03*
X1091333Y1379391D03*
Y1377291D03*
X1079093Y1403589D03*
Y1401489D03*
X1082693Y1403589D03*
Y1401489D03*
X1091333Y1403589D03*
Y1401489D03*
X1094933Y1355193D03*
Y1353093D03*
X1103573Y1355193D03*
Y1353093D03*
X1107173Y1355193D03*
Y1353093D03*
X1094933Y1379391D03*
Y1377291D03*
X1103573Y1379391D03*
Y1377291D03*
X1107173Y1379391D03*
Y1377291D03*
X1094933Y1403589D03*
Y1401489D03*
X1107173Y1403589D03*
Y1401489D03*
X1103573Y1403589D03*
Y1401489D03*
X1115813Y1355193D03*
Y1353093D03*
X1119413Y1355193D03*
Y1353093D03*
X1115813Y1379391D03*
Y1377291D03*
X1119413Y1379391D03*
Y1377291D03*
X1115813Y1403589D03*
Y1401489D03*
X1119413Y1403589D03*
Y1401489D03*
X1131653Y1355193D03*
Y1353093D03*
X1128053Y1355193D03*
Y1353093D03*
X1140293Y1355193D03*
Y1353093D03*
X1128053Y1379391D03*
Y1377291D03*
X1131653Y1379391D03*
Y1377291D03*
X1140293Y1379391D03*
Y1377291D03*
X1131653Y1403589D03*
Y1401489D03*
X1128053Y1403589D03*
Y1401489D03*
X1140293Y1403589D03*
Y1401489D03*
X1143893Y1355193D03*
Y1353093D03*
X1156133Y1355193D03*
Y1353093D03*
X1152533Y1355193D03*
Y1353093D03*
X1143893Y1379391D03*
Y1377291D03*
X1152533Y1379391D03*
Y1377291D03*
X1156133Y1379391D03*
Y1377291D03*
X1143893Y1403589D03*
Y1401489D03*
X1152533Y1403589D03*
Y1401489D03*
X1156133Y1403589D03*
Y1401489D03*
X1168373Y1355193D03*
Y1353093D03*
X1164773Y1355193D03*
Y1353093D03*
Y1379391D03*
Y1377291D03*
X1168373Y1379391D03*
Y1377291D03*
X1164773Y1403589D03*
Y1401489D03*
X1168373Y1403589D03*
Y1401489D03*
X1180613Y1355193D03*
Y1353093D03*
X1177013Y1355193D03*
Y1353093D03*
X1180613Y1379391D03*
Y1377291D03*
X1177013Y1379391D03*
Y1377291D03*
X1180613Y1403589D03*
Y1401489D03*
X1177013Y1403589D03*
Y1401489D03*
X1230226Y1355193D03*
Y1353093D03*
X1233826Y1355193D03*
Y1353093D03*
Y1379391D03*
Y1377291D03*
X1230226Y1379391D03*
Y1377291D03*
X1246066Y1355193D03*
Y1353093D03*
X1242466Y1355193D03*
Y1353093D03*
X1246066Y1379391D03*
Y1377291D03*
X1242466Y1379391D03*
Y1377291D03*
X1246066Y1403589D03*
Y1401489D03*
X1242466Y1403589D03*
Y1401489D03*
X1258306Y1355193D03*
Y1353093D03*
X1254706Y1355193D03*
Y1353093D03*
X1270546Y1355193D03*
Y1353093D03*
X1266946Y1355193D03*
Y1353093D03*
X1254706Y1379391D03*
Y1377291D03*
X1258306Y1379391D03*
Y1377291D03*
X1270546Y1379391D03*
Y1377291D03*
X1266946Y1379391D03*
Y1377291D03*
X1258306Y1403589D03*
Y1401489D03*
X1254706Y1403589D03*
Y1401489D03*
X1270546Y1403589D03*
Y1401489D03*
X1266946Y1403589D03*
Y1401489D03*
X1282786Y1355193D03*
Y1353093D03*
X1279186Y1355193D03*
Y1353093D03*
Y1379391D03*
Y1377291D03*
X1282786Y1379391D03*
Y1377291D03*
X1279186Y1403589D03*
Y1401489D03*
X1282786Y1403589D03*
Y1401489D03*
X1295026Y1355193D03*
Y1353093D03*
X1291426Y1355193D03*
Y1353093D03*
X1295026Y1379391D03*
Y1377291D03*
X1291426Y1379391D03*
Y1377291D03*
X1295026Y1403589D03*
Y1401489D03*
X1291426Y1403589D03*
Y1401489D03*
X1303666Y1355193D03*
Y1353093D03*
X1307266Y1355193D03*
Y1353093D03*
X1315906Y1355193D03*
Y1353093D03*
X1303666Y1379391D03*
Y1377291D03*
X1307266Y1379391D03*
Y1377291D03*
X1315906Y1379391D03*
Y1377291D03*
X1303666Y1403589D03*
Y1401489D03*
X1307266Y1403589D03*
Y1401489D03*
X1315906Y1403589D03*
Y1401489D03*
X1319506Y1355193D03*
Y1353093D03*
X1331746Y1355193D03*
Y1353093D03*
X1328146Y1355193D03*
Y1353093D03*
X1319506Y1379391D03*
Y1377291D03*
X1331746Y1379391D03*
Y1377291D03*
X1328146Y1379391D03*
Y1377291D03*
X1319506Y1403589D03*
Y1401489D03*
X1328146Y1403589D03*
Y1401489D03*
X1331746Y1403589D03*
Y1401489D03*
X1343986Y1355193D03*
Y1353093D03*
X1340386Y1355193D03*
Y1353093D03*
Y1379391D03*
Y1377291D03*
X1343986Y1379391D03*
Y1377291D03*
Y1403589D03*
Y1401489D03*
X1340386Y1403589D03*
Y1401489D03*
X1352626Y1355193D03*
Y1353093D03*
X1356226Y1355193D03*
Y1353093D03*
X1352626Y1379391D03*
Y1377291D03*
X1356226Y1379391D03*
Y1377291D03*
X1352626Y1403589D03*
Y1401489D03*
X1356226Y1403589D03*
Y1401489D03*
X1404239Y1545478D03*
Y1543378D03*
X1403747Y1568156D03*
Y1566056D03*
X1461270Y1355193D03*
Y1353093D03*
X1464870Y1355193D03*
Y1353093D03*
X1461270Y1379391D03*
Y1377291D03*
X1464870Y1379391D03*
Y1377291D03*
X1477373Y1035102D03*
Y1033002D03*
X1474261Y1035088D03*
Y1032988D03*
X1481690Y1105228D03*
Y1107328D03*
Y1117828D03*
Y1119928D03*
Y1130428D03*
Y1132528D03*
Y1143028D03*
Y1145128D03*
Y1155628D03*
Y1168228D03*
Y1170328D03*
Y1157728D03*
Y1180828D03*
Y1182928D03*
X1477110Y1355193D03*
Y1353093D03*
X1473510Y1355193D03*
Y1353093D03*
X1477110Y1379391D03*
Y1377291D03*
X1473510Y1379391D03*
Y1377291D03*
Y1403589D03*
Y1401489D03*
X1477110Y1403589D03*
Y1401489D03*
X1493336Y1025091D03*
Y1012491D03*
Y1014591D03*
Y1027191D03*
X1485750Y1355193D03*
Y1353093D03*
X1489350Y1355193D03*
Y1353093D03*
X1497990Y1355193D03*
Y1353093D03*
Y1379391D03*
Y1377291D03*
X1485750Y1379391D03*
Y1377291D03*
X1489350Y1379391D03*
Y1377291D03*
Y1403589D03*
Y1401489D03*
X1485750Y1403589D03*
Y1401489D03*
X1497990Y1403589D03*
Y1401489D03*
X1501590Y1355193D03*
Y1353093D03*
X1510230Y1355193D03*
Y1353093D03*
X1513830Y1355193D03*
Y1353093D03*
X1501590Y1379391D03*
Y1377291D03*
X1510230Y1379391D03*
Y1377291D03*
X1513830Y1379391D03*
Y1377291D03*
X1501590Y1403589D03*
Y1401489D03*
X1510230Y1403589D03*
Y1401489D03*
X1513830Y1403589D03*
Y1401489D03*
X1522470Y1355193D03*
Y1353093D03*
X1526070Y1355193D03*
Y1353093D03*
Y1379391D03*
Y1377291D03*
X1522470Y1379391D03*
Y1377291D03*
Y1403589D03*
Y1401489D03*
X1526070Y1403589D03*
Y1401489D03*
X1534710Y1355193D03*
Y1353093D03*
X1538310Y1355193D03*
Y1353093D03*
X1534710Y1379391D03*
Y1377291D03*
X1538310Y1379391D03*
Y1377291D03*
Y1403589D03*
Y1401489D03*
X1534710Y1403589D03*
Y1401489D03*
X1559190Y1355193D03*
Y1353093D03*
X1562790Y1355193D03*
Y1353093D03*
X1550550Y1355193D03*
Y1353093D03*
X1546950Y1355193D03*
Y1353093D03*
Y1379391D03*
Y1377291D03*
X1550550Y1379391D03*
Y1377291D03*
X1559190Y1379391D03*
Y1377291D03*
X1562790Y1379391D03*
Y1377291D03*
X1546950Y1403589D03*
Y1401489D03*
X1550550Y1403589D03*
Y1401489D03*
X1562790Y1403589D03*
Y1401489D03*
X1559190Y1403589D03*
Y1401489D03*
X1575030Y1355193D03*
Y1353093D03*
X1571430Y1355193D03*
Y1353093D03*
X1575030Y1379391D03*
Y1377291D03*
X1571430Y1379391D03*
Y1377291D03*
Y1403589D03*
Y1401489D03*
X1575030Y1403589D03*
Y1401489D03*
X1583670Y1355193D03*
Y1353093D03*
X1587270Y1355193D03*
Y1353093D03*
X1583670Y1379391D03*
Y1377291D03*
X1587270Y1379391D03*
Y1377291D03*
X1583670Y1403589D03*
Y1401489D03*
X1587270Y1403589D03*
Y1401489D03*
X1593942Y1437014D03*
Y1439114D03*
X1611298Y1355193D03*
Y1353093D03*
Y1379391D03*
Y1377291D03*
X1623538Y1355193D03*
Y1353093D03*
X1627138Y1355193D03*
Y1353093D03*
X1614898Y1355193D03*
Y1353093D03*
X1627138Y1379391D03*
Y1377291D03*
X1623538Y1379391D03*
Y1377291D03*
X1614898Y1379391D03*
Y1377291D03*
X1623538Y1403589D03*
Y1401489D03*
X1627138Y1403589D03*
Y1401489D03*
X1639378Y1355193D03*
Y1353093D03*
X1635778Y1355193D03*
Y1353093D03*
Y1379391D03*
Y1377291D03*
X1639378Y1379391D03*
Y1377291D03*
X1635778Y1403589D03*
Y1401489D03*
X1639378Y1403589D03*
Y1401489D03*
X1660258Y1355193D03*
Y1353093D03*
X1648018Y1355193D03*
Y1353093D03*
X1651618Y1355193D03*
Y1353093D03*
X1660258Y1379391D03*
Y1377291D03*
X1651618Y1379391D03*
Y1377291D03*
X1648018Y1379391D03*
Y1377291D03*
X1651618Y1403589D03*
Y1401489D03*
X1660258Y1403589D03*
Y1401489D03*
X1648018Y1403589D03*
Y1401489D03*
X1672498Y1355193D03*
Y1353093D03*
X1676098Y1355193D03*
Y1353093D03*
X1663858Y1355193D03*
Y1353093D03*
X1676098Y1379391D03*
Y1377291D03*
X1672498Y1379391D03*
Y1377291D03*
X1663858Y1379391D03*
Y1377291D03*
X1672498Y1403589D03*
Y1401489D03*
X1676098Y1403589D03*
Y1401489D03*
X1663858Y1403589D03*
Y1401489D03*
X1684738Y1355193D03*
Y1353093D03*
X1688338Y1355193D03*
Y1353093D03*
Y1379391D03*
Y1377291D03*
X1684738Y1379391D03*
Y1377291D03*
Y1403589D03*
Y1401489D03*
X1688338Y1403589D03*
Y1401489D03*
X1700578Y1355193D03*
Y1353093D03*
X1696978Y1355193D03*
Y1353093D03*
X1709218Y1355193D03*
Y1353093D03*
Y1379391D03*
Y1377291D03*
X1696978Y1379391D03*
Y1377291D03*
X1700578Y1379391D03*
Y1377291D03*
X1709218Y1403589D03*
Y1401489D03*
X1696978Y1403589D03*
Y1401489D03*
X1700578Y1403589D03*
Y1401489D03*
X1721458Y1355193D03*
Y1353093D03*
X1725058Y1355193D03*
Y1353093D03*
X1712818Y1355193D03*
Y1353093D03*
X1725058Y1379391D03*
Y1377291D03*
X1721458Y1379391D03*
Y1377291D03*
X1712818Y1379391D03*
Y1377291D03*
X1725058Y1403589D03*
Y1401489D03*
X1721458Y1403589D03*
Y1401489D03*
X1712818Y1403589D03*
Y1401489D03*
X1733698Y1355193D03*
Y1353093D03*
X1737298Y1355193D03*
Y1353093D03*
Y1379391D03*
Y1377291D03*
X1733698Y1379391D03*
Y1377291D03*
Y1403589D03*
Y1401489D03*
X1737298Y1403589D03*
Y1401489D03*
X1807393Y1438622D03*
Y1440722D03*
X1807270Y1470812D03*
Y1472912D03*
G54D79*
X58395Y619312D03*
X515481D03*
X972568D03*
X1429655D03*
G54D89*
X68689Y1597855D03*
Y1618721D03*
X73689Y1597855D03*
X78689D03*
X83689D03*
Y1618721D03*
X78689D03*
X73689D03*
X1758820Y1604357D03*
X1763820D03*
X1768820D03*
X1773820D03*
X1758820Y1625223D03*
X1773820D03*
X1768820D03*
X1763820D03*
G54D98*
X82638Y1417010D03*
X931080Y313436D03*
G54D99*
X91838Y682577D03*
X214191Y1429058D03*
Y1432208D03*
Y1429058D03*
Y1425908D03*
X221543Y1428961D03*
Y1432111D03*
Y1428961D03*
Y1425811D03*
X373264Y372604D03*
Y375754D03*
X393620Y1513298D03*
Y1516448D03*
Y1519598D03*
Y1516448D03*
X400903Y1513406D03*
Y1516556D03*
Y1519706D03*
Y1516556D03*
X411487Y1498124D03*
X418839Y1498027D03*
D03*
Y1494877D03*
X411487Y1498124D03*
Y1494974D03*
Y1501274D03*
X418839Y1501177D03*
X454290Y625894D03*
X872736Y385705D03*
Y388855D03*
X915235Y326452D03*
Y323302D03*
Y326452D03*
X920752D03*
D03*
Y323302D03*
X915235Y329602D03*
X920752D03*
X938287Y333667D03*
Y330517D03*
X943787Y333667D03*
Y330517D03*
X938287Y336817D03*
Y333667D03*
X943787Y336817D03*
Y333667D03*
X1025399Y1316576D03*
Y1313426D03*
X1744524Y372604D03*
Y375754D03*
M02*
